FILE_TYPE=PINLIST;
{ Packager-XL run on 24-Aug-2023 AT 15:36:33 }
TIME=' COMPILATION ON 24-Aug-2023 AT 15:36:33';
primitive '74CBTLV3126PW-74CBTLV3126PW,SMA';body '74CBTLV3126PW';
    '2A':'(5)';BIDI;
    '3B':'(8)';BIDI;
    '1OE':'(1)';IN;
    '2OE':'(4)';OUT;
    '1B':'(3)';BIDI;
    '2B':'(6)';BIDI;
    '1A':'(2)';
    'GND':'(7)';
    '3A':'(9)';BIDI;
    '3OE':'(10)';BIDI;
    '4B':'(11)';BIDI;
    '4A':'(12)';BIDI;
    '4OE':'(13)';BIDI;
    'VCC':'(14)';BIDI;
end_primitive;
primitive '74LVC1G02GW_SMLF-74LVC1G02GW,IA';body '74LVC1G02GW';
    'B':'(1)';IN;
    'A':'(2)';IN;
    'Y':'(4)';OUT;
    'VCC':'(5)';
    'GND':'(3)';
end_primitive;
primitive '74LVC1G07GV-74LVC1G07GV,SMLF,IA';body '74LVC1G07GV';
    'VCC':'(5)';
    'A':'(2)';IN;
    'GND':'(3)';
    'Y':'(4)';OUT;
    'NC1':'(1)';OUT;
end_primitive;
primitive '74LVC1G07SE7-74LVC1G07SE-7,SMLA';body '74LVC1G07SE7';
    'VCC':'(5)';
    'A':'(2)';IN;
    'GND':'(3)';
    'Y':'(4)';OUT;
    'NC1':'(1)';OUT;
end_primitive;
primitive '74LVC1G08W57-74LVC1G08W5-7,SMLA';body '74LVC1G08W57';
    'A':'(1)';IN;
    'B':'(2)';IN;
    'GND':'(3)';
    'Y':'(4)';OUT;
    'VCC':'(5)';
end_primitive;
primitive '74LVC1G126SE7-74LVC1G126SE-7,SA';body '74LVC1G126SE7';
    'A':'(2)';IN;
    'Y':'(4)';OUT;
    'VCC':'(5)';
    'GND':'(3)';
    'OE':'(1)';IN;
end_primitive;
primitive '74LVC1G17GW-74LVC1G17GW,SMLF,IA';body '74LVC1G17GW';
    'VCC':'(5)';
    'A':'(2)';IN;
    'GND':'(3)';
    'Y':'(4)';OUT;
    'NC':'(1)';OUT;
end_primitive;
primitive '74LVC1G32GW_SMLF-74LVC1G32GW,IA';body '74LVC1G32GW';
    'I0':'(1)';IN;
    'I1':'(2)';IN;
    'O':'(4)';OUT;
    'VCC':'(5)';
    'GND':'(3)';
end_primitive;
primitive '74LVC1G66GV-74LVC1G66GV,SMLF,IA';body '74LVC1G66GV';
    'Y':'(1)';BIDI;
    'Z':'(2)';BIDI;
    'GND':'(3)';
    'E':'(4)';IN;
    'VCC':'(5)';
end_primitive;
primitive '74LVC2G07DW7-74LVC2G07DW-7,SMLA';body '74LVC2G07DW7';
    '1A':'(1)';IN;
    '2A':'(3)';IN;
    '1Y':'(6)';OUT;
    '2Y':'(4)';OUT;
    'GND':'(2)';
    'VCC':'(5)';
end_primitive;
primitive '74LVC2G07DW7-74LVC2G07DW-7,SMLB';body '74LVC2G07DW7';
    '1A':'(1)';IN;
    '2A':'(3)';IN;
    '1Y':'(6)';OUT;
    '2Y':'(4)';OUT;
    'GND':'(2)';
    'VCC':'(5)';
end_primitive;
primitive '74LVC2G08DP-74LVC2G08DP,SMLF,IA';body '74LVC2G08DP';
    'VCC':'(8,0)';$S;
    'GND':'(4,0)';$S;
    '1A':'(1,0)';$S;IN;
    '1B':'(2,0)';$S;IN;
    '1Y':'(7,0)';$S;OUT;
    '2A':'(0,5)';$S;IN;
    '2B':'(0,6)';$S;IN;
    '2Y':'(0,3)';$S;OUT;
end_primitive;
primitive '74LVC2G17GW-74LVC2G17GW,SMLF,IA';body '74LVC2G17GW';
    'VCC':'(5)';
    'B1':'(4)';OUT;
    'GND':'(2)';
    'A0':'(1)';IN;
    'A1':'(3)';IN;
    'B0':'(6)';OUT;
end_primitive;
primitive '9FGL0251DKILFT-9FGL0251DKILFT,A';body '9FGL0251DKILFT';
    'XIN||CLKIN_25':'(1)';IN;
    'X2':'(2)';OUT;
    'VDDXTAL3.3':'(3)';
    'VSADR||REF3.3':'(4)';BIDI;
    'GNDREF':'(5)';
    'GNDDIG':'(6)';
    'VDDDIG3.3':'(7)';
    'SCLK_3.3':'(8)';IN;
    'SDATA_3.3':'(9)';BIDI;
    'GND_10':'(10)';
    'VDD3.3_11':'(11)';
    'VOE0#':'(12)';IN;
    'DIF0':'(13)';OUT;
    'DIF0#':'(14)';OUT;
    'GNDA':'(15)';
    'VDDA3.3':'(16)';
    'DIF1':'(17)';OUT;
    'DIF1#':'(18)';OUT;
    'VOE1#':'(19)';IN;
    'VDD3.3_20':'(20)';
    'GND_21':'(21)';
    '^CKPWRGD_PD#':'(22)';IN;
    '^VSS_EN_TRI':'(23)';IN;
    'GNDXTAL':'(24)';
    'TH_GND':'(25)';
end_primitive;
primitive '9QXL2001BNHGI8-9QXL2001BNHGI8,A';body '9QXL2001BNHGI8';
    'DIF_IN#':'(H1)';IN;
    'NC12':'(J2)';OUT;
    'NC1':'(B3)';OUT;
    'NC10':'(G2)';OUT;
    'DIF15':'(A5)';OUT;
    'DIF17':'(A1)';OUT;
    'DIF18#':'(D1)';OUT;
    'VCKPWRGD_PD#':'(M6)';IN;
    'EPAD':'(TH)';
    'NC8':'(F2)';OUT;
    'NC11':'(G11)';OUT;
    'NC14':'(K2)';OUT;
    'NC15':'(L6)';OUT;
    'NC13':'(J11)';OUT;
    'DIF0':'(J1)';OUT;
    'DIF0#':'(K1)';OUT;
    'DIF1':'(L1)';OUT;
    'DIF1#':'(M1)';OUT;
    'DIF10':'(D12)';OUT;
    'DIF10#':'(C12)';OUT;
    'DIF11':'(B12)';OUT;
    'DIF12#':'(A10)';OUT;
    'DIF12':'(A11)';OUT;
    'DIF13#':'(A8)';OUT;
    'DIF14':'(A7)';OUT;
    'DIF14#':'(A6)';OUT;
    'DIF15#':'(A4)';OUT;
    'DIF16':'(A3)';OUT;
    'DIF16#':'(A2)';OUT;
    'DIF18':'(C1)';OUT;
    'DIF_IN':'(G1)';IN;
    'DIF11#':'(A12)';OUT;
    'DIF13':'(A9)';OUT;
    'DIF17#':'(B1)';OUT;
    'NC9':'(F11)';OUT;
    'NC7':'(D11)';OUT;
    'NC16':'(L7)';OUT;
    'NC17':'(L3)';OUT;
    'NC18':'(L9)';OUT;
    'NC2':'(B5)';OUT;
    'NC3':'(B7)';OUT;
    'NC4':'(B9)';OUT;
    'NC5':'(C2)';OUT;
    'NC6':'(D2)';OUT;
    'DIF2':'(M2)';OUT;
    'DIF2#':'(M3)';OUT;
    'DIF3':'(M4)';OUT;
    'DIF3#':'(M5)';OUT;
    'DIF4':'(M7)';OUT;
    'DIF4#':'(M8)';OUT;
    'DIF5':'(M9)';OUT;
    'DIF5#':'(M10)';OUT;
    'DIF6':'(M11)';OUT;
    'DIF6#':'(M12)';OUT;
    'DIF7':'(L12)';OUT;
    'DIF7#':'(K12)';OUT;
    'DIF8':'(J12)';OUT;
    'DIF8#':'(H12)';OUT;
    'DIF9':'(G12)';OUT;
    'DIF9#':'(F12)';OUT;
    'VSBEN':'(E2)';IN;
    'VOE5#||DATA':'(L8)';IN;
    'VOE6#||CLK':'(L10)';IN;
    'VOE7#':'(K11)';IN;
    'VOE8#':'(H11)';IN;
    'VOE9#':'(E12)';IN;
    'VOE10#||SHFT_LD#':'(E11)';IN;
    'VOE11#':'(C11)';IN;
    'VOE12#':'(B10)';IN;
    'SMBCLK':'(L5)';IN;
    'SMBDAT':'(L4)';BIDI;
    'VDDA3.3':'(B6)';
    'VDDO3.3_B2':'(B2)';
    'VDDO3.3_B11':'(B11)';
    'VDDO3.3_L2':'(L2)';
    'VDDO3.3_L11':'(L11)';
    'VDDR3.3':'(H2)';
    '^VSADR0_TRI':'(B4)';IN;
    '^VSADR1_TRI':'(B8)';IN;
    'DIF19':'(E1)';OUT;
    'DIF19#':'(F1)';OUT;
end_primitive;
primitive '9SQ440NQQI8-9SQ440NQQI8,SMLF,IA';body '9SQ440NQQI8';
    '25M1#':'(A2,0)';$S;OUT;
    'EPAD':'(C1,0)';$S;
    'GNDXTAL':'(A14,0)';$S;
    'SMB_ADR1_TRI':'(B9,0)';$S;IN;
    'SBI_CLK':'(A54,0)';$S;IN;
    'SHFT_LD#':'(B42,0)';$S;IN;
    'OE2#':'(A29,0)';$S;IN;
    'OE3#':'(A26,0)';$S;IN;
    'OE4#':'(B19,0)';$S;IN;
    'OE1#':'(A30,0)';$S;IN;
    'OE5#':'(B15,0)';$S;IN;
    '25M0#':'(A4,0)';$S;OUT;
    '25M0':'(A5,0)';$S;OUT;
    '25M1':'(A3,0)';$S;OUT;
    '25M2#':'(A55,0)';$S;OUT;
    '25M2':'(A56,0)';$S;OUT;
    '25MPG':'(A1,0)';$S;IN;
    '100M0#':'(A33,0)';$S;OUT;
    '100M0':'(A34,0)';$S;OUT;
    '100M1#':'(A31,0)';$S;OUT;
    '100M1':'(A32,0)';$S;OUT;
    '100M2#':'(A27,0)';$S;OUT;
    '100M2':'(A28,0)';$S;OUT;
    '100M3#':'(A24,0)';$S;OUT;
    '100M3':'(A25,0)';$S;OUT;
    '100M4#':'(A22,0)';$S;OUT;
    '100M4':'(A23,0)';$S;OUT;
    '100M5#':'(A20,0)';$S;OUT;
    '100M5':'(A21,0)';$S;OUT;
    '100M6#':'(A18,0)';$S;OUT;
    '100M6':'(A19,0)';$S;OUT;
    'GNDS':'(B10,0)';$S;
    'MXCK0#':'(A51,0)';$S;OUT;
    'MXCK0':'(A52,0)';$S;OUT;
    'MXCK1#':'(A49,0)';$S;OUT;
    'MXCK1':'(A50,0)';$S;OUT;
    'MXCK2#':'(A47,0)';$S;OUT;
    'MXCK2':'(A48,0)';$S;OUT;
    'MXCK3#':'(A45,0)';$S;OUT;
    'MXCK3':'(A46,0)';$S;OUT;
    'MXCK4#':'(A43,0)';$S;OUT;
    'MXCK4':'(A44,0)';$S;OUT;
    'MXCK5#':'(A41,0)';$S;OUT;
    'MXCK5':'(A42,0)';$S;OUT;
    'MXCK6#':'(A39,0)';$S;OUT;
    'MXCK6':'(A40,0)';$S;OUT;
    'MXCK7#':'(A37,0)';$S;OUT;
    'MXCK7':'(A38,0)';$S;OUT;
    'MXCK8#':'(A35,0)';$S;OUT;
    'MXCK8':'(A36,0)';$S;OUT;
    'MXCK_SEL_100M#':'(B38,0)';$S;IN;
    'NVGND':'(B12,0)';$S;
    'OE0#':'(B27,0)';$S;IN;
    'OE6#':'(B14,0)';$S;IN;
    'PFT_IN#':'(A9,0)';$S;IN;
    'PFT_IN':'(A8,0)';$S;IN;
    'PFT_LOST#':'(B4,0)';$S;OUT;
    'PFT_OUT#':'(A7,0)';$S;OUT;
    'PFT_OUT':'(A6,0)';$S;OUT;
    'PWRGD||PWRDN#':'(A17,0)';$S;IN;
    'SBI_IN':'(B43,0)';$S;IN;
    'SBI_OUT':'(A53,0)';$S;OUT;
    'SCLK':'(A10,0)';$S;IN;
    'SMBDATTA':'(B8,0)';$S;BIDI;
    'SMB_ADR0_TRI':'(A11,0)';$S;IN;
    'SS_EN_TRI':'(A16,0)';$S;IN;
    'VDDA25M':'(B1,0)';$S;
    'VDDA100M':'(B17,0)';$S;
    'VDDPT':'(B6,0)';$S;
    'VDDXTAL':'(A12,0)';$S;
    'XIN_CLKIN':'(A13,0)';$S;IN;
    'XOUT':'(B11,0)';$S;OUT;
    'VDDMXCK_B29':'(B29,0)';$S;
    'VDDMXCK_B32':'(B32,0)';$S;
    'VDDMXCK_B35':'(B35,0)';$S;
    'VDDMXCK_B40':'(B40,0)';$S;
    'VDD100M_B21':'(B21,0)';$S;
    'VDD100M_B23':'(B23,0)';$S;
    'NC_B22':'(0,B22)';$S;OUT;
    'NC_B20':'(0,B20)';$S;OUT;
    'NC_B18':'(0,B18)';$S;OUT;
    'NC_B16':'(0,B16)';$S;OUT;
    'NC_B13':'(0,B13)';$S;OUT;
    'NC_B7':'(0,B7)';$S;OUT;
    'NC_B5':'(0,B5)';$S;OUT;
    'NC_B3':'(0,B3)';$S;OUT;
    'NC_B2':'(0,B2)';$S;OUT;
    'NC_A15':'(0,A15)';$S;OUT;
    'NC_B24':'(0,B24)';$S;OUT;
    'NC_B25':'(0,B25)';$S;OUT;
    'NC_B26':'(0,B26)';$S;OUT;
    'NC_B28':'(0,B28)';$S;OUT;
    'NC_B30':'(0,B30)';$S;OUT;
    'NC_B31':'(0,B31)';$S;OUT;
    'NC_B33':'(0,B33)';$S;OUT;
    'NC_B34':'(0,B34)';$S;OUT;
    'NC_B36':'(0,B36)';$S;OUT;
    'NC_B37':'(0,B37)';$S;OUT;
    'NC_B39':'(0,B39)';$S;OUT;
    'NC_B41':'(0,B41)';$S;OUT;
    'NC_B44':'(0,B44)';$S;OUT;
end_primitive;
primitive '9ZXL0451EKILFT-9ZXL0451EKILFT,A';body '9ZXL0451EKILFT';
    'DIF_IN':'(3)';IN;
    'DIF_IN#':'(4)';IN;
    'VDDR':'(2)';
    'VDD3':'(25)';
    'VDD4':'(29)';
    'FBOUT_NC':'(9)';OUT;
    'VOE0#':'(15)';IN;
    'VOE3#':'(26)';IN;
    'SMBDAT':'(6)';BIDI;
    'NC1':'(11)';OUT;
    'FBOUT_NC#':'(8)';OUT;
    'SMBCLK':'(7)';IN;
    'VDD2':'(21)';
    '^CKPWRGD_PD#':'(1)';IN;
    'DIF0#':'(14)';OUT;
    'DIF0':'(13)';OUT;
    'VOE1#':'(18)';IN;
    'DIF1#':'(20)';OUT;
    'DIF2':'(22)';OUT;
    'VOE2#':'(24)';IN;
    'DIF2#':'(23)';OUT;
    'DIF3#':'(28)';OUT;
    'NC0':'(10)';OUT;
    'VDDA':'(31)';
    'VDD1':'(16)';
    '^HIBW_BYPM_LOBW#':'(32)';IN;
    'EPAD_GND':'(33)';
    'DIF1':'(19)';OUT;
    'DIF3':'(27)';OUT;
    'VDD0':'(12)';
    'NC3':'(30)';OUT;
    'NC2':'(17)';OUT;
    'VSADR0_TRI':'(5)';IN;
end_primitive;
primitive 'ADC128D818CIMTXNOPB-ADC128D818A';body 'ADC128D818CIMTXNOPB';
    'VREF':'(1)';IN;
    'V+':'(5)';
    'A0':'(7)';IN;
    'A1':'(8)';IN;
    'IN7':'(9)';IN;
    'IN6':'(10)';IN;
    'IN5':'(11)';IN;
    'IN4':'(12)';IN;
    'IN3':'(13)';IN;
    'IN2':'(14)';IN;
    'IN1':'(15)';IN;
    'IN0':'(16)';IN;
    'SDA':'(2)';BIDI;
    'SCL':'(3)';IN;
    'GND':'(4)';
    'INT#':'(6)';OUT;
end_primitive;
primitive 'ADM1086AKSZREEL7-ADM1086AKSZ-RA';body 'ADM1086AKSZREEL7';
    'VCC':'(6)';
    'VIN':'(3)';
    'ENIN':'(1)';IN;
    'ENOUT':'(4)';OUT;
    'CEXT':'(5)';BIDI;
    'GND':'(2)';
end_primitive;
primitive 'AP331AWG7-AP331AWG-7,SMLF,EMPTA';body 'AP331AWG7';
    'IN+':'(3)';IN;
    'IN-':'(1)';IN;
    'OUTPUT':'(4)';OUT;
    'VCC':'(5)';
    'GND':'(2)';
end_primitive;
primitive 'APX80929SAG7-APX809-29SAG-7,SMA';body 'APX80929SAG7';
    'VCC':'(3)';
    'RESET_L':'(2)';OUT;
    'GND':'(1)';
end_primitive;
primitive 'BAS70057F-BAS70-05-7-F,SMLF,ICA';body 'BAS70057F';
    'A':'(2)';IN;
    'B':'(1)';IN;
    'C':'(3)';BIDI;
end_primitive;
primitive 'BAT547F-BAT547F,SMLF,IC,BC0BATA';body 'BAT547F';
    '1':'(1)';BIDI;
    '3':'(3)';BIDI;
end_primitive;
primitive 'BC847BPN-BC847BPN,SMLF,IC,BA00A';body 'BC847BPN';
    'B1':'(2,0)';$S;IN;
    'C1':'(6,0)';$S;BIDI;
    'E1':'(1,0)';$S;BIDI;
    'B2':'(0,5)';$S;IN;
    'C2':'(0,3)';$S;BIDI;
    'E2':'(0,4)';$S;BIDI;
end_primitive;
primitive 'CONN112_10137002101LF-CONN112_A';body 'CONN112_10137002101LF';
    'A8':'(A8,0)';$S;BIDI;
    'A7':'(A7,0)';$S;BIDI;
    'A6':'(A6,0)';$S;BIDI;
    'A5':'(A5,0)';$S;BIDI;
    'B8':'(B8,0)';$S;BIDI;
    'B7':'(B7,0)';$S;BIDI;
    'B6':'(B6,0)';$S;BIDI;
    'B5':'(B5,0)';$S;BIDI;
    'C8':'(C8,0)';$S;BIDI;
    'C7':'(C7,0)';$S;BIDI;
    'C6':'(C6,0)';$S;BIDI;
    'C5':'(C5,0)';$S;BIDI;
    'D8':'(D8,0)';$S;BIDI;
    'D7':'(D7,0)';$S;BIDI;
    'D6':'(D6,0)';$S;BIDI;
    'D5':'(D5,0)';$S;BIDI;
    'E8':'(E8,0)';$S;BIDI;
    'E7':'(E7,0)';$S;BIDI;
    'E6':'(E6,0)';$S;BIDI;
    'E5':'(E5,0)';$S;BIDI;
    'F8':'(F8,0)';$S;BIDI;
    'F7':'(F7,0)';$S;BIDI;
    'F6':'(F6,0)';$S;BIDI;
    'F5':'(F5,0)';$S;BIDI;
    'G8':'(G8,0)';$S;BIDI;
    'G7':'(G7,0)';$S;BIDI;
    'G6':'(G6,0)';$S;BIDI;
    'G5':'(G5,0)';$S;BIDI;
    'H8':'(H8,0)';$S;BIDI;
    'H7':'(H7,0)';$S;BIDI;
    'H6':'(H6,0)';$S;BIDI;
    'H5':'(H5,0)';$S;BIDI;
    'I8':'(I8,0)';$S;BIDI;
    'I7':'(I7,0)';$S;BIDI;
    'I6':'(I6,0)';$S;BIDI;
    'I5':'(I5,0)';$S;BIDI;
    'J8':'(J8,0)';$S;BIDI;
    'J7':'(J7,0)';$S;BIDI;
    'J6':'(J6,0)';$S;BIDI;
    'J5':'(J5,0)';$S;BIDI;
    'K8':'(K8,0)';$S;BIDI;
    'K7':'(K7,0)';$S;BIDI;
    'K6':'(K6,0)';$S;BIDI;
    'K5':'(K5,0)';$S;BIDI;
    'L8':'(L8,0)';$S;BIDI;
    'L7':'(L7,0)';$S;BIDI;
    'L6':'(L6,0)';$S;BIDI;
    'L5':'(L5,0)';$S;BIDI;
    'M5':'(M5,0)';$S;BIDI;
    'N5':'(N5,0)';$S;BIDI;
    'M6':'(M6,0)';$S;BIDI;
    'N6':'(N6,0)';$S;BIDI;
    'M7':'(M7,0)';$S;BIDI;
    'N7':'(N7,0)';$S;BIDI;
    'M8':'(M8,0)';$S;BIDI;
    'N8':'(N8,0)';$S;BIDI;
    'A4':'(0,A4)';$S;BIDI;
    'A3':'(0,A3)';$S;BIDI;
    'A2':'(0,A2)';$S;BIDI;
    'A1':'(0,A1)';$S;BIDI;
    'B4':'(0,B4)';$S;BIDI;
    'B3':'(0,B3)';$S;BIDI;
    'B2':'(0,B2)';$S;BIDI;
    'B1':'(0,B1)';$S;BIDI;
    'C4':'(0,C4)';$S;BIDI;
    'C3':'(0,C3)';$S;BIDI;
    'C2':'(0,C2)';$S;BIDI;
    'C1':'(0,C1)';$S;BIDI;
    'D4':'(0,D4)';$S;BIDI;
    'D3':'(0,D3)';$S;BIDI;
    'D2':'(0,D2)';$S;BIDI;
    'D1':'(0,D1)';$S;BIDI;
    'E4':'(0,E4)';$S;BIDI;
    'E3':'(0,E3)';$S;BIDI;
    'E2':'(0,E2)';$S;BIDI;
    'E1':'(0,E1)';$S;BIDI;
    'F4':'(0,F4)';$S;BIDI;
    'F3':'(0,F3)';$S;BIDI;
    'F2':'(0,F2)';$S;BIDI;
    'F1':'(0,F1)';$S;BIDI;
    'G4':'(0,G4)';$S;BIDI;
    'G3':'(0,G3)';$S;BIDI;
    'G2':'(0,G2)';$S;BIDI;
    'G1':'(0,G1)';$S;BIDI;
    'H4':'(0,H4)';$S;BIDI;
    'H3':'(0,H3)';$S;BIDI;
    'H2':'(0,H2)';$S;BIDI;
    'H1':'(0,H1)';$S;BIDI;
    'I4':'(0,I4)';$S;BIDI;
    'I3':'(0,I3)';$S;BIDI;
    'I2':'(0,I2)';$S;BIDI;
    'I1':'(0,I1)';$S;BIDI;
    'J4':'(0,J4)';$S;BIDI;
    'J3':'(0,J3)';$S;BIDI;
    'J2':'(0,J2)';$S;BIDI;
    'J1':'(0,J1)';$S;BIDI;
    'K4':'(0,K4)';$S;BIDI;
    'K3':'(0,K3)';$S;BIDI;
    'K2':'(0,K2)';$S;BIDI;
    'K1':'(0,K1)';$S;BIDI;
    'L4':'(0,L4)';$S;BIDI;
    'L3':'(0,L3)';$S;BIDI;
    'L2':'(0,L2)';$S;BIDI;
    'L1':'(0,L1)';$S;BIDI;
    'M1':'(0,M1)';$S;BIDI;
    'N1':'(0,N1)';$S;BIDI;
    'M2':'(0,M2)';$S;BIDI;
    'N2':'(0,N2)';$S;BIDI;
    'M3':'(0,M3)';$S;BIDI;
    'N3':'(0,N3)';$S;BIDI;
    'M4':'(0,M4)';$S;BIDI;
    'N4':'(0,N4)';$S;BIDI;
end_primitive;
primitive 'CONN14_210HP207GBR1-CONN14_210A';body 'CONN14_210HP207GBR1';
    '1':'(1)';BIDI;
    '2':'(2)';BIDI;
    '3':'(3)';BIDI;
    '4':'(4)';BIDI;
    '5':'(5)';BIDI;
    '6':'(6)';BIDI;
    '7':'(7)';BIDI;
    '8':'(8)';BIDI;
    '9':'(9)';BIDI;
    '10':'(10)';BIDI;
    '11':'(11)';BIDI;
    '12':'(12)';BIDI;
    '13':'(13)';BIDI;
    '14':'(14)';BIDI;
end_primitive;
primitive 'CONN160_10131762101LF-CONN160_A';body 'CONN160_10131762101LF';
    'A8':'(A8,0)';$S;BIDI;
    'A7':'(A7,0)';$S;BIDI;
    'A6':'(A6,0)';$S;BIDI;
    'A5':'(A5,0)';$S;BIDI;
    'B8':'(B8,0)';$S;BIDI;
    'B7':'(B7,0)';$S;BIDI;
    'B6':'(B6,0)';$S;BIDI;
    'B5':'(B5,0)';$S;BIDI;
    'C8':'(C8,0)';$S;BIDI;
    'C7':'(C7,0)';$S;BIDI;
    'C6':'(C6,0)';$S;BIDI;
    'C5':'(C5,0)';$S;BIDI;
    'D8':'(D8,0)';$S;BIDI;
    'D7':'(D7,0)';$S;BIDI;
    'D6':'(D6,0)';$S;BIDI;
    'D5':'(D5,0)';$S;BIDI;
    'E8':'(E8,0)';$S;BIDI;
    'E7':'(E7,0)';$S;BIDI;
    'E6':'(E6,0)';$S;BIDI;
    'E5':'(E5,0)';$S;BIDI;
    'F8':'(F8,0)';$S;BIDI;
    'F7':'(F7,0)';$S;BIDI;
    'F6':'(F6,0)';$S;BIDI;
    'F5':'(F5,0)';$S;BIDI;
    'G8':'(G8,0)';$S;BIDI;
    'G7':'(G7,0)';$S;BIDI;
    'G6':'(G6,0)';$S;BIDI;
    'G5':'(G5,0)';$S;BIDI;
    'H8':'(H8,0)';$S;BIDI;
    'H7':'(H7,0)';$S;BIDI;
    'H6':'(H6,0)';$S;BIDI;
    'H5':'(H5,0)';$S;BIDI;
    'I8':'(I8,0)';$S;BIDI;
    'I7':'(I7,0)';$S;BIDI;
    'I6':'(I6,0)';$S;BIDI;
    'I5':'(I5,0)';$S;BIDI;
    'J8':'(J8,0)';$S;BIDI;
    'J7':'(J7,0)';$S;BIDI;
    'J6':'(J6,0)';$S;BIDI;
    'J5':'(J5,0)';$S;BIDI;
    'K8':'(K8,0)';$S;BIDI;
    'K7':'(K7,0)';$S;BIDI;
    'K6':'(K6,0)';$S;BIDI;
    'K5':'(K5,0)';$S;BIDI;
    'L8':'(L8,0)';$S;BIDI;
    'L7':'(L7,0)';$S;BIDI;
    'L6':'(L6,0)';$S;BIDI;
    'L5':'(L5,0)';$S;BIDI;
    'M5':'(M5,0)';$S;BIDI;
    'N5':'(N5,0)';$S;BIDI;
    'M6':'(M6,0)';$S;BIDI;
    'N6':'(N6,0)';$S;BIDI;
    'M7':'(M7,0)';$S;BIDI;
    'N7':'(N7,0)';$S;BIDI;
    'M8':'(M8,0)';$S;BIDI;
    'N8':'(N8,0)';$S;BIDI;
    'O5':'(O5,0)';$S;BIDI;
    'P5':'(P5,0)';$S;BIDI;
    'Q5':'(Q5,0)';$S;BIDI;
    'R5':'(R5,0)';$S;BIDI;
    'S5':'(S5,0)';$S;BIDI;
    'T5':'(T5,0)';$S;BIDI;
    'O6':'(O6,0)';$S;BIDI;
    'P6':'(P6,0)';$S;BIDI;
    'Q6':'(Q6,0)';$S;BIDI;
    'R6':'(R6,0)';$S;BIDI;
    'S6':'(S6,0)';$S;BIDI;
    'T6':'(T6,0)';$S;BIDI;
    'O7':'(O7,0)';$S;BIDI;
    'P7':'(P7,0)';$S;BIDI;
    'Q7':'(Q7,0)';$S;BIDI;
    'R7':'(R7,0)';$S;BIDI;
    'S7':'(S7,0)';$S;BIDI;
    'T7':'(T7,0)';$S;BIDI;
    'O8':'(O8,0)';$S;BIDI;
    'P8':'(P8,0)';$S;BIDI;
    'Q8':'(Q8,0)';$S;BIDI;
    'R8':'(R8,0)';$S;BIDI;
    'S8':'(S8,0)';$S;BIDI;
    'T8':'(T8,0)';$S;BIDI;
    'A4':'(0,A4)';$S;BIDI;
    'A3':'(0,A3)';$S;BIDI;
    'A2':'(0,A2)';$S;BIDI;
    'A1':'(0,A1)';$S;BIDI;
    'B4':'(0,B4)';$S;BIDI;
    'B3':'(0,B3)';$S;BIDI;
    'B2':'(0,B2)';$S;BIDI;
    'B1':'(0,B1)';$S;BIDI;
    'C4':'(0,C4)';$S;BIDI;
    'C3':'(0,C3)';$S;BIDI;
    'C2':'(0,C2)';$S;BIDI;
    'C1':'(0,C1)';$S;BIDI;
    'D4':'(0,D4)';$S;BIDI;
    'D3':'(0,D3)';$S;BIDI;
    'D2':'(0,D2)';$S;BIDI;
    'D1':'(0,D1)';$S;BIDI;
    'E4':'(0,E4)';$S;BIDI;
    'E3':'(0,E3)';$S;BIDI;
    'E2':'(0,E2)';$S;BIDI;
    'E1':'(0,E1)';$S;BIDI;
    'F4':'(0,F4)';$S;BIDI;
    'F3':'(0,F3)';$S;BIDI;
    'F2':'(0,F2)';$S;BIDI;
    'F1':'(0,F1)';$S;BIDI;
    'G4':'(0,G4)';$S;BIDI;
    'G3':'(0,G3)';$S;BIDI;
    'G2':'(0,G2)';$S;BIDI;
    'G1':'(0,G1)';$S;BIDI;
    'H4':'(0,H4)';$S;BIDI;
    'H3':'(0,H3)';$S;BIDI;
    'H2':'(0,H2)';$S;BIDI;
    'H1':'(0,H1)';$S;BIDI;
    'I4':'(0,I4)';$S;BIDI;
    'I3':'(0,I3)';$S;BIDI;
    'I2':'(0,I2)';$S;BIDI;
    'I1':'(0,I1)';$S;BIDI;
    'J4':'(0,J4)';$S;BIDI;
    'J3':'(0,J3)';$S;BIDI;
    'J2':'(0,J2)';$S;BIDI;
    'J1':'(0,J1)';$S;BIDI;
    'K4':'(0,K4)';$S;BIDI;
    'K3':'(0,K3)';$S;BIDI;
    'K2':'(0,K2)';$S;BIDI;
    'K1':'(0,K1)';$S;BIDI;
    'L4':'(0,L4)';$S;BIDI;
    'L3':'(0,L3)';$S;BIDI;
    'L2':'(0,L2)';$S;BIDI;
    'L1':'(0,L1)';$S;BIDI;
    'M1':'(0,M1)';$S;BIDI;
    'N1':'(0,N1)';$S;BIDI;
    'M2':'(0,M2)';$S;BIDI;
    'N2':'(0,N2)';$S;BIDI;
    'M3':'(0,M3)';$S;BIDI;
    'N3':'(0,N3)';$S;BIDI;
    'M4':'(0,M4)';$S;BIDI;
    'N4':'(0,N4)';$S;BIDI;
    'O1':'(0,O1)';$S;BIDI;
    'P1':'(0,P1)';$S;BIDI;
    'Q1':'(0,Q1)';$S;BIDI;
    'R1':'(0,R1)';$S;BIDI;
    'S1':'(0,S1)';$S;BIDI;
    'T1':'(0,T1)';$S;BIDI;
    'O2':'(0,O2)';$S;BIDI;
    'P2':'(0,P2)';$S;BIDI;
    'Q2':'(0,Q2)';$S;BIDI;
    'R2':'(0,R2)';$S;BIDI;
    'S2':'(0,S2)';$S;BIDI;
    'T2':'(0,T2)';$S;BIDI;
    'O3':'(0,O3)';$S;BIDI;
    'P3':'(0,P3)';$S;BIDI;
    'Q3':'(0,Q3)';$S;BIDI;
    'R3':'(0,R3)';$S;BIDI;
    'S3':'(0,S3)';$S;BIDI;
    'T3':'(0,T3)';$S;BIDI;
    'O4':'(0,O4)';$S;BIDI;
    'P4':'(0,P4)';$S;BIDI;
    'Q4':'(0,Q4)';$S;BIDI;
    'R4':'(0,R4)';$S;BIDI;
    'S4':'(0,S4)';$S;BIDI;
    'T4':'(0,T4)';$S;BIDI;
end_primitive;
primitive 'CONN1_10165288101LF-CONN1_1016A';body 'CONN1_10165288101LF';
    'NC1':'(SCR_H1)';BIDI;
end_primitive;
primitive 'CONN2_AAABAT029Y19-CONN2_AAA-BA';body 'CONN2_AAABAT029Y19';
    '1':'(1)';
    '2':'(2)';
end_primitive;
primitive 'CONN3_210HP1030BR1-CONN3_210-HA';body 'CONN3_210HP1030BR1';
    '3':'(3)';BIDI;
    '2':'(2)';BIDI;
    '1':'(1)';BIDI;
end_primitive;
primitive 'CONN3_210HP1030BR1-CONN3_210-HB';body 'CONN3_210HP1030BR1';
    '3':'(3)';BIDI;
    '2':'(2)';BIDI;
    '1':'(1)';BIDI;
end_primitive;
primitive 'CONN60_101062636003K02LF-CONN6A';body 'CONN60_101062636003K02LF';
    'A2':'(A2)';BIDI;
    'B2':'(B2)';BIDI;
    'C2':'(C2)';BIDI;
    'D2':'(D2)';BIDI;
    'P1_1':'(P1_1)';
    'P1_2':'(P1_2)';
    'P1_3':'(P1_3)';
    'P1_4':'(P1_4)';
    'P1_5':'(P1_5)';
    'P1_6':'(P1_6)';
    'P1_7':'(P1_7)';
    'P1_8':'(P1_8)';
    'P2_1':'(P2_1)';
    'P2_2':'(P2_2)';
    'P2_3':'(P2_3)';
    'P2_4':'(P2_4)';
    'P2_5':'(P2_5)';
    'P2_6':'(P2_6)';
    'P2_7':'(P2_7)';
    'P2_8':'(P2_8)';
    'P4_1':'(P4_1)';
    'P4_2':'(P4_2)';
    'P4_3':'(P4_3)';
    'P4_4':'(P4_4)';
    'P4_5':'(P4_5)';
    'P4_6':'(P4_6)';
    'P4_7':'(P4_7)';
    'P4_8':'(P4_8)';
    'A1':'(A1)';BIDI;
    'B1':'(B1)';BIDI;
    'C1':'(C1)';BIDI;
    'D1':'(D1)';BIDI;
    'P5_1':'(P5_1)';
    'P5_2':'(P5_2)';
    'P5_3':'(P5_3)';
    'P5_4':'(P5_4)';
    'P5_5':'(P5_5)';
    'P5_6':'(P5_6)';
    'P5_7':'(P5_7)';
    'P5_8':'(P5_8)';
    'P3_1':'(P3_1)';
    'P3_2':'(P3_2)';
    'P3_3':'(P3_3)';
    'P3_4':'(P3_4)';
    'P3_5':'(P3_5)';
    'P3_6':'(P3_6)';
    'P3_7':'(P3_7)';
    'P3_8':'(P3_8)';
    'P6_1':'(P6_1)';
    'P6_2':'(P6_2)';
    'P6_3':'(P6_3)';
    'P6_4':'(P6_4)';
    'P6_5':'(P6_5)';
    'P6_6':'(P6_6)';
    'P6_7':'(P6_7)';
    'P6_8':'(P6_8)';
    'A3':'(A3)';BIDI;
    'B3':'(B3)';BIDI;
    'C3':'(C3)';BIDI;
    'D3':'(D3)';BIDI;
end_primitive;
primitive 'CONN8_210HP1080BR1-CONN8_210-HA';body 'CONN8_210HP1080BR1';
    '1':'(1)';BIDI;
    '2':'(2)';BIDI;
    '3':'(3)';BIDI;
    '4':'(4)';BIDI;
    '5':'(5)';BIDI;
    '6':'(6)';BIDI;
    '7':'(7)';BIDI;
    '8':'(8)';BIDI;
end_primitive;
primitive 'DIODE_TVS-SMF14A,SMLF,IC,BCSMFA';body 'DIODE_TVS';
    'A':'(A)';IN;
    'C':'(C)';OUT;
end_primitive;
primitive 'DS125BR111RTWR-DS125BR111RTWR,A';body 'DS125BR111RTWR';
    'EQB0||AD3':'(1)';IN;
    'EQB1||AD2':'(2)';IN;
    'ENSMB':'(3)';IN;
    'SDA||VODA_DB':'(4)';BIDI;
    'SCL||VODB_DB':'(5)';BIDI;
    'PWDN':'(6)';IN;
    'OUTA+':'(7)';OUT;
    'OUTA-':'(8)';OUT;
    'EQA1||AD1':'(9)';IN;
    'EQA0||AD0':'(10)';IN;
    'INB+':'(11)';IN;
    'INB-':'(12)';IN;
    'RES':'(13)';IN;
    'SD_TH':'(14)';IN;
    'VIN':'(15)';
    'VDD_SEL':'(16)';IN;
    'VOD_SEL||READEN#':'(17)';IN;
    'RXDET||DONE#':'(18)';BIDI;
    'OUTB-':'(19)';OUT;
    'OUTB+':'(20)';OUT;
    'VDD_21':'(21)';
    'VDD_22':'(22)';
    'INA-':'(23)';IN;
    'INA+':'(24)';IN;
    'TH_GND':'(25)';
end_primitive;
primitive 'DUMMY_SYMBOL-BATTERY_SYMBOL,MEA';body 'DUMMY_SYMBOL';
    '1':'(1)';OUT;
end_primitive;
primitive 'DUMMY_SYMBOL-MECHANIC_SYMBOL,MA';body 'DUMMY_SYMBOL';
    '1':'(1)';OUT;
end_primitive;
primitive 'EMMITSBURG_REV0P9-GFNOCPU04302A';body 'EMMITSBURG_REV0P9';
    'RSVD_J23':'(J23,0,0,0,0,0,0,0,0,0,0)';$S;OUT;
    'RSVD_H24':'(H24,0,0,0,0,0,0,0,0,0,0)';$S;OUT;
    'XCLK_BIASREF':'(N29,0,0,0,0,0,0,0,0,0,0)';$S;BIDI;
    'CLKOUT_SRC_N_0':'(A16,0,0,0,0,0,0,0,0,0,0)';$S;OUT;
    'CLKOUT_SRC_N_1':'(G23,0,0,0,0,0,0,0,0,0,0)';$S;OUT;
    'CLKOUT_SRC_N_10':'(J16,0,0,0,0,0,0,0,0,0,0)';$S;OUT;
    'CLKOUT_SRC_N_11':'(G16,0,0,0,0,0,0,0,0,0,0)';$S;OUT;
    'CLKOUT_SRC_N_12':'(A10,0,0,0,0,0,0,0,0,0,0)';$S;OUT;
    'CLKOUT_SRC_N_13':'(A8,0,0,0,0,0,0,0,0,0,0)';$S;OUT;
    'CLKOUT_SRC_N_14':'(B7,0,0,0,0,0,0,0,0,0,0)';$S;OUT;
    'CLKOUT_SRC_N_15':'(B5,0,0,0,0,0,0,0,0,0,0)';$S;OUT;
    'CLKOUT_SRC_N_16':'(A18,0,0,0,0,0,0,0,0,0,0)';$S;OUT;
    'CLKOUT_SRC_N_2':'(H21,0,0,0,0,0,0,0,0,0,0)';$S;OUT;
    'CLKOUT_SRC_N_3':'(B17,0,0,0,0,0,0,0,0,0,0)';$S;OUT;
    'CLKOUT_SRC_N_4':'(B19,0,0,0,0,0,0,0,0,0,0)';$S;OUT;
    'CLKOUT_SRC_N_5':'(A12,0,0,0,0,0,0,0,0,0,0)';$S;OUT;
    'CLKOUT_SRC_N_6':'(B11,0,0,0,0,0,0,0,0,0,0)';$S;OUT;
    'CLKOUT_SRC_N_7':'(A14,0,0,0,0,0,0,0,0,0,0)';$S;OUT;
    'CLKOUT_SRC_N_8':'(F18,0,0,0,0,0,0,0,0,0,0)';$S;OUT;
    'CLKOUT_SRC_N_9':'(B15,0,0,0,0,0,0,0,0,0,0)';$S;OUT;
    'CLKOUT_SRC_P_0':'(C16,0,0,0,0,0,0,0,0,0,0)';$S;OUT;
    'CLKOUT_SRC_P_1':'(F21,0,0,0,0,0,0,0,0,0,0)';$S;OUT;
    'CLKOUT_SRC_P_10':'(K18,0,0,0,0,0,0,0,0,0,0)';$S;OUT;
    'CLKOUT_SRC_P_11':'(H15,0,0,0,0,0,0,0,0,0,0)';$S;OUT;
    'CLKOUT_SRC_P_12':'(C10,0,0,0,0,0,0,0,0,0,0)';$S;OUT;
    'CLKOUT_SRC_P_13':'(C8,0,0,0,0,0,0,0,0,0,0)';$S;OUT;
    'CLKOUT_SRC_P_14':'(D7,0,0,0,0,0,0,0,0,0,0)';$S;OUT;
    'CLKOUT_SRC_P_15':'(C6,0,0,0,0,0,0,0,0,0,0)';$S;OUT;
    'CLKOUT_SRC_P_16':'(C18,0,0,0,0,0,0,0,0,0,0)';$S;OUT;
    'CLKOUT_SRC_P_2':'(K21,0,0,0,0,0,0,0,0,0,0)';$S;OUT;
    'CLKOUT_SRC_P_3':'(D17,0,0,0,0,0,0,0,0,0,0)';$S;OUT;
    'CLKOUT_SRC_P_4':'(D19,0,0,0,0,0,0,0,0,0,0)';$S;OUT;
    'CLKOUT_SRC_P_5':'(C12,0,0,0,0,0,0,0,0,0,0)';$S;OUT;
    'CLKOUT_SRC_P_6':'(D11,0,0,0,0,0,0,0,0,0,0)';$S;OUT;
    'CLKOUT_SRC_P_7':'(C14,0,0,0,0,0,0,0,0,0,0)';$S;OUT;
    'CLKOUT_SRC_P_8':'(H18,0,0,0,0,0,0,0,0,0,0)';$S;OUT;
    'CLKOUT_SRC_P_9':'(D15,0,0,0,0,0,0,0,0,0,0)';$S;OUT;
    'PMSYNC_CLK_N_0':'(D27,0,0,0,0,0,0,0,0,0,0)';$S;OUT;
    'PMSYNC_CLK_N_1':'(C28,0,0,0,0,0,0,0,0,0,0)';$S;OUT;
    'PMSYNC_CLK_P_0':'(B27,0,0,0,0,0,0,0,0,0,0)';$S;OUT;
    'PMSYNC_CLK_P_1':'(A28,0,0,0,0,0,0,0,0,0,0)';$S;OUT;
    'REFCLK_INJ_NS_N':'(D25,0,0,0,0,0,0,0,0,0,0)';$S;IN;
    'REFCLK_INJ_NS_P':'(B25,0,0,0,0,0,0,0,0,0,0)';$S;IN;
    'REFCLK_INJ_S_N':'(D21,0,0,0,0,0,0,0,0,0,0)';$S;IN;
    'REFCLK_INJ_S_P':'(B21,0,0,0,0,0,0,0,0,0,0)';$S;IN;
    'RTCX1':'(BE6,0,0,0,0,0,0,0,0,0,0)';$S;IN;
    'RTCX2':'(BF7,0,0,0,0,0,0,0,0,0,0)';$S;OUT;
    'RTC_EXTCAP':'(BF5,0,0,0,0,0,0,0,0,0,0)';$S;BIDI;
    'XTAL_IN':'(B23,0,0,0,0,0,0,0,0,0,0)';$S;IN;
    'XTAL_OUT':'(D23,0,0,0,0,0,0,0,0,0,0)';$S;OUT;
    'RSVD_BC40':'(0,BC40,0,0,0,0,0,0,0,0,0)';$S;OUT;
    'USB2N_0':'(0,AR42,0,0,0,0,0,0,0,0,0)';$S;BIDI;
    'USB2N_1':'(0,AP43,0,0,0,0,0,0,0,0,0)';$S;BIDI;
    'USB2N_10':'(0,AY43,0,0,0,0,0,0,0,0,0)';$S;BIDI;
    'USB2N_11':'(0,AH42,0,0,0,0,0,0,0,0,0)';$S;BIDI;
    'USB2N_12':'(0,BA42,0,0,0,0,0,0,0,0,0)';$S;BIDI;
    'USB2N_13':'(0,AG43,0,0,0,0,0,0,0,0,0)';$S;BIDI;
    'USB2N_2':'(0,AT43,0,0,0,0,0,0,0,0,0)';$S;BIDI;
    'USB2N_3':'(0,AN42,0,0,0,0,0,0,0,0,0)';$S;BIDI;
    'USB2N_4':'(0,AU42,0,0,0,0,0,0,0,0,0)';$S;BIDI;
    'USB2N_5':'(0,AL43,0,0,0,0,0,0,0,0,0)';$S;BIDI;
    'USB2N_6':'(0,AV43,0,0,0,0,0,0,0,0,0)';$S;BIDI;
    'USB2N_7':'(0,AK42,0,0,0,0,0,0,0,0,0)';$S;BIDI;
    'USB2N_8':'(0,AW42,0,0,0,0,0,0,0,0,0)';$S;BIDI;
    'USB2N_9':'(0,AJ43,0,0,0,0,0,0,0,0,0)';$S;BIDI;
    'USB2P_0':'(0,AR40,0,0,0,0,0,0,0,0,0)';$S;BIDI;
    'USB2P_1':'(0,AP41,0,0,0,0,0,0,0,0,0)';$S;BIDI;
    'USB2P_10':'(0,AY41,0,0,0,0,0,0,0,0,0)';$S;BIDI;
    'USB2P_11':'(0,AH40,0,0,0,0,0,0,0,0,0)';$S;BIDI;
    'USB2P_12':'(0,BA40,0,0,0,0,0,0,0,0,0)';$S;BIDI;
    'USB2P_13':'(0,AG41,0,0,0,0,0,0,0,0,0)';$S;BIDI;
    'USB2P_2':'(0,AT41,0,0,0,0,0,0,0,0,0)';$S;BIDI;
    'USB2P_3':'(0,AN40,0,0,0,0,0,0,0,0,0)';$S;BIDI;
    'USB2P_4':'(0,AU40,0,0,0,0,0,0,0,0,0)';$S;BIDI;
    'USB2P_5':'(0,AL41,0,0,0,0,0,0,0,0,0)';$S;BIDI;
    'USB2P_6':'(0,AV41,0,0,0,0,0,0,0,0,0)';$S;BIDI;
    'USB2P_7':'(0,AK40,0,0,0,0,0,0,0,0,0)';$S;BIDI;
    'USB2P_8':'(0,AW40,0,0,0,0,0,0,0,0,0)';$S;BIDI;
    'USB2P_9':'(0,AJ41,0,0,0,0,0,0,0,0,0)';$S;BIDI;
    'USB2_COMP':'(0,BB41,0,0,0,0,0,0,0,0,0)';$S;BIDI;
    'DMI_0_RXN':'(0,0,A30,0,0,0,0,0,0,0,0)';$S;IN;
    'DMI_0_RXP':'(0,0,C30,0,0,0,0,0,0,0,0)';$S;IN;
    'DMI_0_TXN':'(0,0,K28,0,0,0,0,0,0,0,0)';$S;OUT;
    'DMI_0_TXP':'(0,0,H28,0,0,0,0,0,0,0,0)';$S;OUT;
    'DMI_1_RXN':'(0,0,B31,0,0,0,0,0,0,0,0)';$S;IN;
    'DMI_1_RXP':'(0,0,D31,0,0,0,0,0,0,0,0)';$S;IN;
    'DMI_1_TXN':'(0,0,G29,0,0,0,0,0,0,0,0)';$S;OUT;
    'DMI_1_TXP':'(0,0,F28,0,0,0,0,0,0,0,0)';$S;OUT;
    'DMI_2_RXN':'(0,0,A32,0,0,0,0,0,0,0,0)';$S;IN;
    'DMI_2_RXP':'(0,0,C32,0,0,0,0,0,0,0,0)';$S;IN;
    'DMI_2_TXN':'(0,0,J29,0,0,0,0,0,0,0,0)';$S;OUT;
    'DMI_2_TXP':'(0,0,H31,0,0,0,0,0,0,0,0)';$S;OUT;
    'DMI_3_RXN':'(0,0,B33,0,0,0,0,0,0,0,0)';$S;IN;
    'DMI_3_RXP':'(0,0,D33,0,0,0,0,0,0,0,0)';$S;IN;
    'DMI_3_TXN':'(0,0,L32,0,0,0,0,0,0,0,0)';$S;OUT;
    'DMI_3_TXP':'(0,0,K31,0,0,0,0,0,0,0,0)';$S;OUT;
    'DMI_4_SATA_19_PCIE3_19_RXN':'(0,0,A34,0,0,0,0,0,0,0,0)';$S;IN;
    'DMI_4_SATA_19_PCIE3_19_RXP':'(0,0,C34,0,0,0,0,0,0,0,0)';$S;IN;
    'DMI_4_SATA_19_PCIE3_19_TXN':'(0,0,J32,0,0,0,0,0,0,0,0)';$S;OUT;
    'DMI_4_SATA_19_PCIE3_19_TXP':'(0,0,G32,0,0,0,0,0,0,0,0)';$S;OUT;
    'DMI_5_SATA_18_PCIE3_18_RXN':'(0,0,B35,0,0,0,0,0,0,0,0)';$S;IN;
    'DMI_5_SATA_18_PCIE3_18_RXP':'(0,0,D35,0,0,0,0,0,0,0,0)';$S;IN;
    'DMI_5_SATA_18_PCIE3_18_TXN':'(0,0,G36,0,0,0,0,0,0,0,0)';$S;OUT;
    'DMI_5_SATA_18_PCIE3_18_TXP':'(0,0,H34,0,0,0,0,0,0,0,0)';$S;OUT;
    'DMI_6_SATA_17_PCIE3_17_RXN':'(0,0,A36,0,0,0,0,0,0,0,0)';$S;IN;
    'DMI_6_SATA_17_PCIE3_17_RXP':'(0,0,C36,0,0,0,0,0,0,0,0)';$S;IN;
    'DMI_6_SATA_17_PCIE3_17_TXN':'(0,0,K37,0,0,0,0,0,0,0,0)';$S;OUT;
    'DMI_6_SATA_17_PCIE3_17_TXP':'(0,0,J36,0,0,0,0,0,0,0,0)';$S;OUT;
    'DMI_7_SATA_16_PCIE3_16_RXN':'(0,0,B37,0,0,0,0,0,0,0,0)';$S;IN;
    'DMI_7_SATA_16_PCIE3_16_RXP':'(0,0,D37,0,0,0,0,0,0,0,0)';$S;IN;
    'DMI_7_SATA_16_PCIE3_16_TXN':'(0,0,F37,0,0,0,0,0,0,0,0)';$S;OUT;
    'DMI_7_SATA_16_PCIE3_16_TXP':'(0,0,H37,0,0,0,0,0,0,0,0)';$S;OUT;
    'PHY_PCIE3_RCOMPN':'(0,0,AP31,0,0,0,0,0,0,0,0)';$S;BIDI;
    'PHY_PCIE3_RCOMPP':'(0,0,AR29,0,0,0,0,0,0,0,0)';$S;BIDI;
    'RSVD_N42':'(0,0,N42,0,0,0,0,0,0,0,0)';$S;OUT;
    'RSVD_N40':'(0,0,N40,0,0,0,0,0,0,0,0)';$S;OUT;
    'RSVD_D39':'(0,0,D39,0,0,0,0,0,0,0,0)';$S;OUT;
    'RSVD_C40':'(0,0,C40,0,0,0,0,0,0,0,0)';$S;OUT;
    'SATA_0_PCIE3_0_USB3_0_RXN':'(0,0,AE41,0,0,0,0,0,0,0,0)';$S;IN;
    'SATA_0_PCIE3_0_USB3_0_RXP':'(0,0,AE43,0,0,0,0,0,0,0,0)';$S;IN;
    'SATA_0_PCIE3_0_USB3_0_TXN':'(0,0,AL32,0,0,0,0,0,0,0,0)';$S;OUT;
    'SATA_0_PCIE3_0_USB3_0_TXP':'(0,0,AK31,0,0,0,0,0,0,0,0)';$S;OUT;
    'SATA_10_PCIE3_10_GBE_0_RXN':'(0,0,M41,0,0,0,0,0,0,0,0)';$S;IN;
    'SATA_10_PCIE3_10_GBE_0_RXP':'(0,0,M43,0,0,0,0,0,0,0,0)';$S;IN;
    'SATA_10_PCIE3_10_GBE_0_TXN':'(0,0,W36,0,0,0,0,0,0,0,0)';$S;OUT;
    'SATA_10_PCIE3_10_GBE_0_TXP':'(0,0,Y37,0,0,0,0,0,0,0,0)';$S;OUT;
    'SATA_11_PCIE3_11_RXN':'(0,0,L40,0,0,0,0,0,0,0,0)';$S;IN;
    'SATA_11_PCIE3_11_RXP':'(0,0,L42,0,0,0,0,0,0,0,0)';$S;IN;
    'SATA_11_PCIE3_11_TXN':'(0,0,T37,0,0,0,0,0,0,0,0)';$S;OUT;
    'SATA_11_PCIE3_11_TXP':'(0,0,V37,0,0,0,0,0,0,0,0)';$S;OUT;
    'SATA_12_PCIE3_12_GBE_1_RXN':'(0,0,K41,0,0,0,0,0,0,0,0)';$S;IN;
    'SATA_12_PCIE3_12_GBE_1_RXP':'(0,0,K43,0,0,0,0,0,0,0,0)';$S;IN;
    'SATA_12_PCIE3_12_GBE_1_TXN':'(0,0,V34,0,0,0,0,0,0,0,0)';$S;OUT;
    'SATA_12_PCIE3_12_GBE_1_TXP':'(0,0,U36,0,0,0,0,0,0,0,0)';$S;OUT;
    'SATA_13_PCIE3_13_RXN':'(0,0,J40,0,0,0,0,0,0,0,0)';$S;IN;
    'SATA_13_PCIE3_13_RXP':'(0,0,J42,0,0,0,0,0,0,0,0)';$S;IN;
    'SATA_13_PCIE3_13_TXN':'(0,0,U32,0,0,0,0,0,0,0,0)';$S;OUT;
    'SATA_13_PCIE3_13_TXP':'(0,0,W32,0,0,0,0,0,0,0,0)';$S;OUT;
    'SATA_14_PCIE3_14_GBE_2_RXN':'(0,0,H41,0,0,0,0,0,0,0,0)';$S;IN;
    'SATA_14_PCIE3_14_GBE_2_RXP':'(0,0,H43,0,0,0,0,0,0,0,0)';$S;IN;
    'SATA_14_PCIE3_14_GBE_2_TXN':'(0,0,R32,0,0,0,0,0,0,0,0)';$S;OUT;
    'SATA_14_PCIE3_14_GBE_2_TXP':'(0,0,T34,0,0,0,0,0,0,0,0)';$S;OUT;
    'SATA_15_PCIE3_15_RXN':'(0,0,G40,0,0,0,0,0,0,0,0)';$S;IN;
    'SATA_15_PCIE3_15_RXP':'(0,0,G42,0,0,0,0,0,0,0,0)';$S;IN;
    'SATA_15_PCIE3_15_TXN':'(0,0,P34,0,0,0,0,0,0,0,0)';$S;OUT;
    'SATA_15_PCIE3_15_TXP':'(0,0,N36,0,0,0,0,0,0,0,0)';$S;OUT;
    'SATA_1_PCIE3_1_USB3_1_RXN':'(0,0,AD40,0,0,0,0,0,0,0,0)';$S;IN;
    'SATA_1_PCIE3_1_USB3_1_RXP':'(0,0,AD42,0,0,0,0,0,0,0,0)';$S;IN;
    'SATA_1_PCIE3_1_USB3_1_TXN':'(0,0,AN36,0,0,0,0,0,0,0,0)';$S;OUT;
    'SATA_1_PCIE3_1_USB3_1_TXP':'(0,0,AP34,0,0,0,0,0,0,0,0)';$S;OUT;
    'SATA_2_PCIE3_2_USB3_2_RXN':'(0,0,AC41,0,0,0,0,0,0,0,0)';$S;IN;
    'SATA_2_PCIE3_2_USB3_2_RXP':'(0,0,AC43,0,0,0,0,0,0,0,0)';$S;IN;
    'SATA_2_PCIE3_2_USB3_2_TXN':'(0,0,AR36,0,0,0,0,0,0,0,0)';$S;OUT;
    'SATA_2_PCIE3_2_USB3_2_TXP':'(0,0,AT37,0,0,0,0,0,0,0,0)';$S;OUT;
    'SATA_3_PCIE3_3_USB3_3_RXN':'(0,0,AB40,0,0,0,0,0,0,0,0)';$S;IN;
    'SATA_3_PCIE3_3_USB3_3_RXP':'(0,0,AB42,0,0,0,0,0,0,0,0)';$S;IN;
    'SATA_3_PCIE3_3_USB3_3_TXN':'(0,0,AK34,0,0,0,0,0,0,0,0)';$S;OUT;
    'SATA_3_PCIE3_3_USB3_3_TXP':'(0,0,AM34,0,0,0,0,0,0,0,0)';$S;OUT;
    'SATA_4_PCIE3_4_USB3_4_RXN':'(0,0,AA41,0,0,0,0,0,0,0,0)';$S;IN;
    'SATA_4_PCIE3_4_USB3_4_RXP':'(0,0,AA43,0,0,0,0,0,0,0,0)';$S;IN;
    'SATA_4_PCIE3_4_USB3_4_TXN':'(0,0,AL36,0,0,0,0,0,0,0,0)';$S;OUT;
    'SATA_4_PCIE3_4_USB3_4_TXP':'(0,0,AM37,0,0,0,0,0,0,0,0)';$S;OUT;
    'SATA_5_PCIE3_5_USB3_5_RXN':'(0,0,Y40,0,0,0,0,0,0,0,0)';$S;IN;
    'SATA_5_PCIE3_5_USB3_5_RXP':'(0,0,Y42,0,0,0,0,0,0,0,0)';$S;IN;
    'SATA_5_PCIE3_5_USB3_5_TXN':'(0,0,AH34,0,0,0,0,0,0,0,0)';$S;OUT;
    'SATA_5_PCIE3_5_USB3_5_TXP':'(0,0,AJ32,0,0,0,0,0,0,0,0)';$S;OUT;
    'SATA_6_PCIE3_6_USB3_6_RXN':'(0,0,W41,0,0,0,0,0,0,0,0)';$S;IN;
    'SATA_6_PCIE3_6_USB3_6_RXP':'(0,0,W43,0,0,0,0,0,0,0,0)';$S;IN;
    'SATA_6_PCIE3_6_USB3_6_TXN':'(0,0,AF37,0,0,0,0,0,0,0,0)';$S;OUT;
    'SATA_6_PCIE3_6_USB3_6_TXP':'(0,0,AH37,0,0,0,0,0,0,0,0)';$S;OUT;
    'SATA_7_PCIE3_7_USB3_7_RXN':'(0,0,V40,0,0,0,0,0,0,0,0)';$S;IN;
    'SATA_7_PCIE3_7_USB3_7_RXP':'(0,0,V42,0,0,0,0,0,0,0,0)';$S;IN;
    'SATA_7_PCIE3_7_USB3_7_TXN':'(0,0,AF34,0,0,0,0,0,0,0,0)';$S;OUT;
    'SATA_7_PCIE3_7_USB3_7_TXP':'(0,0,AG36,0,0,0,0,0,0,0,0)';$S;OUT;
    'SATA_8_PCIE3_8_USB3_8_RXN':'(0,0,U41,0,0,0,0,0,0,0,0)';$S;IN;
    'SATA_8_PCIE3_8_USB3_8_RXP':'(0,0,U43,0,0,0,0,0,0,0,0)';$S;IN;
    'SATA_8_PCIE3_8_USB3_8_TXN':'(0,0,AE36,0,0,0,0,0,0,0,0)';$S;OUT;
    'SATA_8_PCIE3_8_USB3_8_TXP':'(0,0,AD37,0,0,0,0,0,0,0,0)';$S;OUT;
    'SATA_9_PCIE3_9_USB3_9_RXN':'(0,0,R40,0,0,0,0,0,0,0,0)';$S;IN;
    'SATA_9_PCIE3_9_USB3_9_RXP':'(0,0,R42,0,0,0,0,0,0,0,0)';$S;IN;
    'SATA_9_PCIE3_9_USB3_9_TXN':'(0,0,AE32,0,0,0,0,0,0,0,0)';$S;OUT;
    'SATA_9_PCIE3_9_USB3_9_TXP':'(0,0,AG32,0,0,0,0,0,0,0,0)';$S;OUT;
    'ACPRESENT':'(0,0,0,AN7,0,0,0,0,0,0,0)';$S;IN;
    'CPUPWRGD':'(0,0,0,G10,0,0,0,0,0,0,0)';$S;OUT;
    'CPU_CATERR_N':'(0,0,0,F8,0,0,0,0,0,0,0)';$S;IN;
    'CPU_ERR0_N':'(0,0,0,J7,0,0,0,0,0,0,0)';$S;IN;
    'CPU_ERR1_N':'(0,0,0,G7,0,0,0,0,0,0,0)';$S;IN;
    'CPU_ERR2_N':'(0,0,0,L7,0,0,0,0,0,0,0)';$S;IN;
    'CPU_MEMTRIP_N':'(0,0,0,E4,0,0,0,0,0,0,0)';$S;IN;
    'CPU_MSMI_N':'(0,0,0,F11,0,0,0,0,0,0,0)';$S;IN;
    'CPU_PWR_DEBUG_N':'(0,0,0,F5,0,0,0,0,0,0,0)';$S;OUT;
    'CPU_THRMTRIP_N':'(0,0,0,F3,0,0,0,0,0,0,0)';$S;IN;
    'DBG_PMODE':'(0,0,0,BE40,0,0,0,0,0,0,0)';$S;OUT;
    'DSW_PWROK':'(0,0,0,BE8,0,0,0,0,0,0,0)';$S;IN;
    'GPP_O_0':'(0,0,0,AN10,0,0,0,0,0,0,0)';$S;BIDI;
    'GPP_O_7':'(0,0,0,AU10,0,0,0,0,0,0,0)';$S;BIDI;
    'INTRUDER_N':'(0,0,0,BG8,0,0,0,0,0,0,0)';$S;IN;
    'JTAGX':'(0,0,0,BD35,0,0,0,0,0,0,0)';$S;BIDI;
    'JTAG_TCK':'(0,0,0,BF35,0,0,0,0,0,0,0)';$S;BIDI;
    'JTAG_TDI':'(0,0,0,BE38,0,0,0,0,0,0,0)';$S;BIDI;
    'JTAG_TDO':'(0,0,0,BE36,0,0,0,0,0,0,0)';$S;OUT;
    'JTAG_TMS':'(0,0,0,BD37,0,0,0,0,0,0,0)';$S;BIDI;
    'LANPHYPC':'(0,0,0,AJ7,0,0,0,0,0,0,0)';$S;OUT;
    'LAN_WAKE_N':'(0,0,0,AU7,0,0,0,0,0,0,0)';$S;IN;
    'ME_PECI':'(0,0,0,J10,0,0,0,0,0,0,0)';$S;BIDI;
    'PCH_PWROK':'(0,0,0,BE4,0,0,0,0,0,0,0)';$S;IN;
    'PLTRST_CPU_N':'(0,0,0,M8,0,0,0,0,0,0,0)';$S;OUT;
    'PRDY_N':'(0,0,0,BB37,0,0,0,0,0,0,0)';$S;BIDI;
    'PREQ_N':'(0,0,0,BF37,0,0,0,0,0,0,0)';$S;BIDI;
    'PWRBTN_N':'(0,0,0,AR10,0,0,0,0,0,0,0)';$S;IN;
    'RSMRST_N':'(0,0,0,BD9,0,0,0,0,0,0,0)';$S;IN;
    'RSVD_BG36':'(0,0,0,BG36,0,0,0,0,0,0,0)';$S;OUT;
    'RSVD_BF39':'(0,0,0,BF39,0,0,0,0,0,0,0)';$S;OUT;
    'RSVD_AV21':'(0,0,0,AV21,0,0,0,0,0,0,0)';$S;OUT;
    'RSVD_AW23':'(0,0,0,AW26,0,0,0,0,0,0,0)';$S;OUT;
    'SLP_A_N':'(0,0,0,AM11,0,0,0,0,0,0,0)';$S;OUT;
    'SLP_LAN_N':'(0,0,0,AK8,0,0,0,0,0,0,0)';$S;OUT;
    'SLP_S3_N':'(0,0,0,AP8,0,0,0,0,0,0,0)';$S;OUT;
    'SLP_S4_N':'(0,0,0,AL13,0,0,0,0,0,0,0)';$S;OUT;
    'SLP_S5_N':'(0,0,0,AJ13,0,0,0,0,0,0,0)';$S;OUT;
    'SLP_SUS_N':'(0,0,0,AL7,0,0,0,0,0,0,0)';$S;OUT;
    'SUSCLK':'(0,0,0,AR7,0,0,0,0,0,0,0)';$S;OUT;
    'SYS_PWROK':'(0,0,0,AL10,0,0,0,0,0,0,0)';$S;IN;
    'SYS_RESET_N':'(0,0,0,AJ10,0,0,0,0,0,0,0)';$S;IN;
    'TRIGGER0_N':'(0,0,0,H11,0,0,0,0,0,0,0)';$S;BIDI;
    'TRIGGER1_N':'(0,0,0,K8,0,0,0,0,0,0,0)';$S;BIDI;
    'WAKE_N':'(0,0,0,AH11,0,0,0,0,0,0,0)';$S;IN;
    'GPPC_B_18_HS_UART1_RTS_N':'(0,0,0,0,BD25,0,0,0,0,0,0)';$S;BIDI;
    'GPPC_A_0_ESPI_ALERT0_N':'(0,0,0,0,BG20,0,0,0,0,0,0)';$S;BIDI;
    'GPPC_A_10_SRCCLKREQ_N_0':'(0,0,0,0,BD17,0,0,0,0,0,0)';$S;BIDI;
    'GPPC_A_11_SRCCLKREQ_N_1':'(0,0,0,0,BG18,0,0,0,0,0,0)';$S;BIDI;
    'GPPC_A_12_SRCCLKREQ_N_2':'(0,0,0,0,BG16,0,0,0,0,0,0)';$S;BIDI;
    'GPPC_A_13_SRCCLKREQ_N_3':'(0,0,0,0,BF15,0,0,0,0,0,0)';$S;BIDI;
    'GPPC_A_14_SRCCLKREQ_N_4':'(0,0,0,0,BE12,0,0,0,0,0,0)';$S;BIDI;
    'GPPC_A_15_SRCCLKREQ_N_5':'(0,0,0,0,BE14,0,0,0,0,0,0)';$S;BIDI;
    'GPPC_A_16_SRCCLKREQ_N_6':'(0,0,0,0,BD11,0,0,0,0,0,0)';$S;BIDI;
    'GPPC_A_17_SRCCLKREQ_N_7':'(0,0,0,0,BF13,0,0,0,0,0,0)';$S;BIDI;
    'GPPC_A_18_SRCCLKREQ_N_8':'(0,0,0,0,BF11,0,0,0,0,0,0)';$S;BIDI;
    'GPPC_A_19_SRCCLKREQ_N_9':'(0,0,0,0,BG14,0,0,0,0,0,0)';$S;BIDI;
    'GPPC_A_1_ESPI_ALERT1_N':'(0,0,0,0,BD15,0,0,0,0,0,0)';$S;BIDI;
    'GPPC_A_2_ESPI_IO_0':'(0,0,0,0,BG12,0,0,0,0,0,0)';$S;BIDI;
    'GPPC_A_3_ESPI_IO_1':'(0,0,0,0,BF19,0,0,0,0,0,0)';$S;BIDI;
    'GPPC_A_4_ESPI_IO_2':'(0,0,0,0,BE18,0,0,0,0,0,0)';$S;BIDI;
    'GPPC_A_5_ESPI_IO_3':'(0,0,0,0,BD19,0,0,0,0,0,0)';$S;BIDI;
    'GPPC_A_6_ESPI_CS0_N':'(0,0,0,0,BE20,0,0,0,0,0,0)';$S;BIDI;
    'GPPC_A_7_ESPI_CS1_N':'(0,0,0,0,BE16,0,0,0,0,0,0)';$S;BIDI;
    'GPPC_A_8_ESPI_RESET_N':'(0,0,0,0,BF17,0,0,0,0,0,0)';$S;BIDI;
    'GPPC_A_9_ESPI_CLK':'(0,0,0,0,BD13,0,0,0,0,0,0)';$S;BIDI;
    'GPPC_B_0_GSXDOUT':'(0,0,0,0,BD33,0,0,0,0,0,0)';$S;BIDI;
    'GPPC_B_10_USB2_OCB_5':'(0,0,0,0,BG24,0,0,0,0,0,0)';$S;BIDI;
    'GPPC_B_11_USB2_OCB_6':'(0,0,0,0,BG22,0,0,0,0,0,0)';$S;BIDI;
    'GPPC_B_12_HS_UART0_RXD':'(0,0,0,0,BD29,0,0,0,0,0,0)';$S;BIDI;
    'GPPC_B_13_HS_UART0_TXD':'(0,0,0,0,BE28,0,0,0,0,0,0)';$S;BIDI;
    'GPPC_B_14_HS_UART0_RTS_N':'(0,0,0,0,BF29,0,0,0,0,0,0)';$S;BIDI;
    'GPPC_B_15_HS_UART0_CTS_N':'(0,0,0,0,BD27,0,0,0,0,0,0)';$S;BIDI;
    'GPPC_B_16_HS_UART1_RXD':'(0,0,0,0,BE26,0,0,0,0,0,0)';$S;BIDI;
    'GPPC_B_17_HS_UART1_TXD':'(0,0,0,0,BF27,0,0,0,0,0,0)';$S;BIDI;
    'GPPC_B_19_HS_UART1_CTS_N':'(0,0,0,0,BF25,0,0,0,0,0,0)';$S;BIDI;
    'GPPC_B_1_GSXSLOAD':'(0,0,0,0,BE32,0,0,0,0,0,0)';$S;BIDI;
    'GPPC_B_20':'(0,0,0,0,BE24,0,0,0,0,0,0)';$S;BIDI;
    'GPPC_B_21':'(0,0,0,0,BF23,0,0,0,0,0,0)';$S;BIDI;
    'GPPC_B_22':'(0,0,0,0,BE22,0,0,0,0,0,0)';$S;BIDI;
    'GPPC_B_23':'(0,0,0,0,BD23,0,0,0,0,0,0)';$S;BIDI;
    'GPPC_B_2_GSXDIN':'(0,0,0,0,BF33,0,0,0,0,0,0)';$S;BIDI;
    'GPPC_B_3_GSXRESET_N':'(0,0,0,0,BD31,0,0,0,0,0,0)';$S;BIDI;
    'GPPC_B_4_GSXCLK':'(0,0,0,0,BE30,0,0,0,0,0,0)';$S;BIDI;
    'GPPC_B_5_USB2_OCB_0':'(0,0,0,0,BF31,0,0,0,0,0,0)';$S;BIDI;
    'GPPC_B_6_USB2_OCB_1':'(0,0,0,0,BG32,0,0,0,0,0,0)';$S;BIDI;
    'GPPC_B_7_USB2_OCB_2':'(0,0,0,0,BG30,0,0,0,0,0,0)';$S;BIDI;
    'GPPC_B_8_USB2_OCB_3':'(0,0,0,0,BG28,0,0,0,0,0,0)';$S;BIDI;
    'GPPC_B_9_USB2_OCB_4':'(0,0,0,0,BG26,0,0,0,0,0,0)';$S;BIDI;
    'GPPC_C_0_ME_SML0CLK':'(0,0,0,0,BC4,0,0,0,0,0,0)';$S;BIDI;
    'GPPC_C_10_ME_SML2DATA':'(0,0,0,0,AP3,0,0,0,0,0,0)';$S;BIDI;
    'GPPC_C_11_ME_SML2ALERT_N':'(0,0,0,0,AV3,0,0,0,0,0,0)';$S;BIDI;
    'GPPC_C_12_ME_SML3CLK':'(0,0,0,0,AN4,0,0,0,0,0,0)';$S;BIDI;
    'GPPC_C_13_ME_SML3DATA':'(0,0,0,0,AY1,0,0,0,0,0,0)';$S;BIDI;
    'GPPC_C_14_ME_SML3ALERT_N':'(0,0,0,0,AW2,0,0,0,0,0,0)';$S;BIDI;
    'GPPC_C_15_ME_SML4CLK':'(0,0,0,0,BA2,0,0,0,0,0,0)';$S;BIDI;
    'GPPC_C_16_ME_SML4DATA':'(0,0,0,0,AV1,0,0,0,0,0,0)';$S;BIDI;
    'GPPC_C_17_ME_SML4ALERT_N':'(0,0,0,0,AL3,0,0,0,0,0,0)';$S;BIDI;
    'GPPC_C_18':'(0,0,0,0,AL5,0,0,0,0,0,0)';$S;BIDI;
    'GPPC_C_19_MC_SMBCLK':'(0,0,0,0,AL1,0,0,0,0,0,0)';$S;BIDI;
    'GPPC_C_1_ME_SML0DATA':'(0,0,0,0,BA4,0,0,0,0,0,0)';$S;BIDI;
    'GPPC_C_20_MC_SMBDATA':'(0,0,0,0,AT1,0,0,0,0,0,0)';$S;BIDI;
    'GPPC_C_21_MC_SMBALERT_N':'(0,0,0,0,AN2,0,0,0,0,0,0)';$S;BIDI;
    'GPPC_C_2_ME_SML0ALERT_N':'(0,0,0,0,AU2,0,0,0,0,0,0)';$S;BIDI;
    'GPPC_C_3_ME_SML0BDATA':'(0,0,0,0,AU4,0,0,0,0,0,0)';$S;BIDI;
    'GPPC_C_4_ME_SML0BCLK':'(0,0,0,0,BB3,0,0,0,0,0,0)';$S;BIDI;
    'GPPC_C_5_ME_SML0BALERT_N':'(0,0,0,0,AT3,0,0,0,0,0,0)';$S;BIDI;
    'GPPC_C_6_ME_SML1CLK':'(0,0,0,0,AP1,0,0,0,0,0,0)';$S;BIDI;
    'GPPC_C_7_ME_SML1DATA':'(0,0,0,0,AW4,0,0,0,0,0,0)';$S;BIDI;
    'GPPC_C_8_ME_SML1ALERT_N':'(0,0,0,0,AR4,0,0,0,0,0,0)';$S;BIDI;
    'GPPC_C_9_ME_SML2CLK':'(0,0,0,0,AR2,0,0,0,0,0,0)';$S;BIDI;
    'GPP_D_0_HS_SMBCLK_DMA_SMBCLK':'(0,0,0,0,AF2,0,0,0,0,0,0)';$S;BIDI;
    'GPP_D_10_BM_BUSY_N_SX_EXIT_HOLDOFF_N':'(0,0,0,0,AB2,0,0,0,0,0,0)';$S;BIDI;
    'GPP_D_11_PLTRST_N':'(0,0,0,0,AB4,0,0,0,0,0,0)';$S;BIDI;
    'GPP_D_12_PCHHOT_N':'(0,0,0,0,AH2,0,0,0,0,0,0)';$S;BIDI;
    'GPP_D_13_ADR_COMPLETE':'(0,0,0,0,AC1,0,0,0,0,0,0)';$S;BIDI;
    'GPP_D_14_ADR_TRIGGER_N':'(0,0,0,0,AH4,0,0,0,0,0,0)';$S;BIDI;
    'GPP_D_15_VRALERT_N':'(0,0,0,0,AC3,0,0,0,0,0,0)';$S;BIDI;
    'GPP_D_16_ADR_ACK':'(0,0,0,0,AD4,0,0,0,0,0,0)';$S;BIDI;
    'GPP_D_17_THERMTRIP_N':'(0,0,0,0,Y2,0,0,0,0,0,0)';$S;BIDI;
    'GPP_D_18_MEMTRIP_N':'(0,0,0,0,AF4,0,0,0,0,0,0)';$S;BIDI;
    'GPP_D_19_MSMI_N':'(0,0,0,0,Y4,0,0,0,0,0,0)';$S;BIDI;
    'GPP_D_1_HS_SMBDATA_DMA_SMBDATA':'(0,0,0,0,AE1,0,0,0,0,0,0)';$S;BIDI;
    'GPP_D_20_CATERR_N':'(0,0,0,0,AG3,0,0,0,0,0,0)';$S;BIDI;
    'GPP_D_21_GLB_RST_WARN_N':'(0,0,0,0,AA1,0,0,0,0,0,0)';$S;BIDI;
    'GPP_D_22_USB2_OCB_7':'(0,0,0,0,AA3,0,0,0,0,0,0)';$S;BIDI;
    'GPP_D_23':'(0,0,0,0,W1,0,0,0,0,0,0)';$S;BIDI;
    'GPP_D_2_HS_SMBALERT_N_DMA_SMBALERT_N':'(0,0,0,0,AD2,0,0,0,0,0,0)';$S;BIDI;
    'GPP_D_6':'(0,0,0,0,AJ1,0,0,0,0,0,0)';$S;BIDI;
    'GPP_D_7':'(0,0,0,0,AG1,0,0,0,0,0,0)';$S;BIDI;
    'GPP_D_8_CRASHLOG_TRIG_N':'(0,0,0,0,AE3,0,0,0,0,0,0)';$S;BIDI;
    'GPP_D_9_PME_N':'(0,0,0,0,AJ3,0,0,0,0,0,0)';$S;BIDI;
    'GPPC_H_0':'(0,0,0,0,0,G4,0,0,0,0,0)';$S;BIDI;
    'GPPC_H_1':'(0,0,0,0,0,K1,0,0,0,0,0)';$S;BIDI;
    'GPPC_H_15_FLEX_CLK_OUT_0':'(0,0,0,0,0,J2,0,0,0,0,0)';$S;BIDI;
    'GPPC_H_16_FLEX_CLK_OUT_1':'(0,0,0,0,0,G2,0,0,0,0,0)';$S;BIDI;
    'GPPC_H_17_FLEX_CLK_OUT_2':'(0,0,0,0,0,H3,0,0,0,0,0)';$S;BIDI;
    'GPPC_H_18_PMCALERT_N':'(0,0,0,0,0,J4,0,0,0,0,0)';$S;BIDI;
    'GPPC_H_19':'(0,0,0,0,0,L4,0,0,0,0,0)';$S;BIDI;
    'GPPC_H_6':'(0,0,0,0,0,L2,0,0,0,0,0)';$S;BIDI;
    'GPPC_H_7':'(0,0,0,0,0,K3,0,0,0,0,0)';$S;BIDI;
    'GPP_E_0_SATA1_XPCIE_0':'(0,0,0,0,0,BA26,0,0,0,0,0)';$S;BIDI;
    'GPP_E_10_SATA0_SDATAOUT_SATA0_GP':'(0,0,0,0,0,AV31,0,0,0,0,0)';$S;BIDI;
    'GPP_E_11_SATA1_SCLOCK_SATA1_LED_N':'(0,0,0,0,0,AV34,0,0,0,0,0)';$S;BIDI;
    'GPP_E_12_SATA1_SLOAD_SATA1_GP':'(0,0,0,0,0,BB28,0,0,0,0,0)';$S;BIDI;
    'GPP_E_13_SATA1_SDATAOUT_SATA1_DEVSLP':'(0,0,0,0,0,BA32,0,0,0,0,0)';$S;BIDI;~

    'GPP_E_14_SATA2_SCLOCK_SATA2_LED_N':'(0,0,0,0,0,BB34,0,0,0,0,0)';$S;BIDI;
    'GPP_E_15_SATA2_SLOAD_SATA2_GP':'(0,0,0,0,0,AW20,0,0,0,0,0)';$S;BIDI;
    'GPP_E_16_SATA2_SDATAOUT_SATA2_DEVSLP':'(0,0,0,0,0,AW29,0,0,0,0,0)';$S;BIDI;~

    'GPP_E_17_ERR0_N':'(0,0,0,0,0,BA36,0,0,0,0,0)';$S;BIDI;
    'GPP_E_18_ERR1_N':'(0,0,0,0,0,BA20,0,0,0,0,0)';$S;BIDI;
    'GPP_E_19_ERR2_N':'(0,0,0,0,0,BB31,0,0,0,0,0)';$S;BIDI;
    'GPP_E_1_SATA1_XPCIE_1':'(0,0,0,0,0,BA23,0,0,0,0,0)';$S;BIDI;
    'GPP_E_2_SATA1_XPCIE_2':'(0,0,0,0,0,AW23,0,0,0,0,0)';$S;BIDI;
    'GPP_E_3_SATA1_XPCIE_3':'(0,0,0,0,0,BB21,0,0,0,0,0)';$S;BIDI;
    'GPP_E_4_SATA0_XPCIE_2':'(0,0,0,0,0,AV24,0,0,0,0,0)';$S;BIDI;
    'GPP_E_5_SATA0_XPCIE_3':'(0,0,0,0,0,AV28,0,0,0,0,0)';$S;BIDI;
    'GPP_E_6_SATA0_USB3_XPCIE_0':'(0,0,0,0,0,BB24,0,0,0,0,0)';$S;BIDI;
    'GPP_E_7_SATA0_USB3_XPCIE_1':'(0,0,0,0,0,AW32,0,0,0,0,0)';$S;BIDI;
    'GPP_E_8_SATA0_SCLOCK_SATA0_LED_N':'(0,0,0,0,0,AW36,0,0,0,0,0)';$S;BIDI;
    'GPP_E_9_SATA0_SLOAD_SATA0_DEVSLP':'(0,0,0,0,0,BA29,0,0,0,0,0)';$S;BIDI;
    'GPP_I_12_HDA_BCLK':'(0,0,0,0,0,U3,0,0,0,0,0)';$S;BIDI;
    'GPP_I_13_HDA_RST_N':'(0,0,0,0,0,N2,0,0,0,0,0)';$S;BIDI;
    'GPP_I_14_HDA_SYNC':'(0,0,0,0,0,P1,0,0,0,0,0)';$S;BIDI;
    'GPP_I_15_HDA_SDO':'(0,0,0,0,0,R2,0,0,0,0,0)';$S;BIDI;
    'GPP_I_16_HDA_SDI_0':'(0,0,0,0,0,U1,0,0,0,0,0)';$S;BIDI;
    'GPP_I_17_HDA_SDI_1':'(0,0,0,0,0,V4,0,0,0,0,0)';$S;BIDI;
    'GPP_I_21':'(0,0,0,0,0,N4,0,0,0,0,0)';$S;BIDI;
    'GPP_I_22':'(0,0,0,0,0,P3,0,0,0,0,0)';$S;BIDI;
    'GPP_I_23':'(0,0,0,0,0,R4,0,0,0,0,0)';$S;BIDI;
    'GPP_L_0_PM_SYNC_0':'(0,0,0,0,0,AF8,0,0,0,0,0)';$S;BIDI;
    'GPP_L_1_PM_DOWN_0':'(0,0,0,0,0,AE7,0,0,0,0,0)';$S;BIDI;
    'GPP_L_2':'(0,0,0,0,0,AC10,0,0,0,0,0)';$S;BIDI;
    'GPP_L_3':'(0,0,0,0,0,AF11,0,0,0,0,0)';$S;BIDI;
    'GPP_L_4':'(0,0,0,0,0,AG7,0,0,0,0,0)';$S;BIDI;
    'GPP_L_5':'(0,0,0,0,0,AB8,0,0,0,0,0)';$S;BIDI;
    'GPP_L_6':'(0,0,0,0,0,AG10,0,0,0,0,0)';$S;BIDI;
    'GPP_L_7':'(0,0,0,0,0,AC7,0,0,0,0,0)';$S;BIDI;
    'GPP_L_8':'(0,0,0,0,0,AE10,0,0,0,0,0)';$S;BIDI;
    'GPP_M_0':'(0,0,0,0,0,N7,0,0,0,0,0)';$S;BIDI;
    'GPP_M_1':'(0,0,0,0,0,AA13,0,0,0,0,0)';$S;BIDI;
    'GPP_M_11':'(0,0,0,0,0,R7,0,0,0,0,0)';$S;BIDI;
    'GPP_M_12':'(0,0,0,0,0,U7,0,0,0,0,0)';$S;BIDI;
    'GPP_M_15':'(0,0,0,0,0,T8,0,0,0,0,0)';$S;BIDI;
    'GPP_M_16':'(0,0,0,0,0,N10,0,0,0,0,0)';$S;BIDI;
    'GPP_M_17':'(0,0,0,0,0,W13,0,0,0,0,0)';$S;BIDI;
    'GPP_M_2':'(0,0,0,0,0,AA7,0,0,0,0,0)';$S;BIDI;
    'GPP_M_3':'(0,0,0,0,0,AA10,0,0,0,0,0)';$S;BIDI;
    'GPP_M_4':'(0,0,0,0,0,W7,0,0,0,0,0)';$S;BIDI;
    'GPP_M_5':'(0,0,0,0,0,V8,0,0,0,0,0)';$S;BIDI;
    'GPP_M_6':'(0,0,0,0,0,R10,0,0,0,0,0)';$S;BIDI;
    'GPP_M_7':'(0,0,0,0,0,AB11,0,0,0,0,0)';$S;BIDI;
    'GPP_M_8':'(0,0,0,0,0,W10,0,0,0,0,0)';$S;BIDI;
    'GPPC_S_0_TIME_SYNC_0':'(0,0,0,0,0,0,BB18,0,0,0,0)';$S;BIDI;
    'GPPC_S_10':'(0,0,0,0,0,0,AW10,0,0,0,0)';$S;BIDI;
    'GPPC_S_11':'(0,0,0,0,0,0,BB8,0,0,0,0)';$S;BIDI;
    'GPPC_S_1_SPKR_TIME_SYNC_1':'(0,0,0,0,0,0,AU16,0,0,0,0)';$S;BIDI;
    'GPPC_S_2_CPU_GP_0':'(0,0,0,0,0,0,AR16,0,0,0,0)';$S;BIDI;
    'GPPC_S_3_CPU_GP_1':'(0,0,0,0,0,0,AV11,0,0,0,0)';$S;BIDI;
    'GPPC_S_4_CPU_GP_2':'(0,0,0,0,0,0,AU13,0,0,0,0)';$S;BIDI;
    'GPPC_S_5_CPU_GP_3':'(0,0,0,0,0,0,AT18,0,0,0,0)';$S;BIDI;
    'GPPC_S_6_SUSWARN_N_SUSPWRDNACK':'(0,0,0,0,0,0,AR13,0,0,0,0)';$S;BIDI;
    'GPPC_S_7_SUSACK_N':'(0,0,0,0,0,0,BA7,0,0,0,0)';$S;BIDI;
    'GPPC_S_8_NMI_N':'(0,0,0,0,0,0,AP15,0,0,0,0)';$S;BIDI;
    'GPPC_S_9_SMI_N':'(0,0,0,0,0,0,AV18,0,0,0,0)';$S;BIDI;
    'GPP_N_1':'(0,0,0,0,0,0,T11,0,0,0,0)';$S;BIDI;
    'GPP_N_4':'(0,0,0,0,0,0,V11,0,0,0,0)';$S;BIDI;
    'NC_CGC_DUT_DETECT_N':'(0,0,0,0,0,0,BG3,0,0,0,0)';$S;OUT;
    'RCTRST_N':'(0,0,0,0,0,0,BD7,0,0,0,0)';$S;IN;
    'SPI0_CLK':'(0,0,0,0,0,0,BB15,0,0,0,0)';$S;OUT;
    'SPI0_FLASH_0_CS_N':'(0,0,0,0,0,0,AW13,0,0,0,0)';$S;OUT;
    'SPI0_FLASH_1_CS_N':'(0,0,0,0,0,0,BA10,0,0,0,0)';$S;OUT;
    'SPI0_IO_2':'(0,0,0,0,0,0,AV15,0,0,0,0)';$S;BIDI;
    'SPI0_IO_3':'(0,0,0,0,0,0,BA16,0,0,0,0)';$S;BIDI;
    'SPI0_MOSI_IO_0':'(0,0,0,0,0,0,BA13,0,0,0,0)';$S;BIDI;
    'SPI0_MISO_IO_1':'(0,0,0,0,0,0,AW16,0,0,0,0)';$S;BIDI;
    'SPI0_TPM_CS_N':'(0,0,0,0,0,0,BB11,0,0,0,0)';$S;OUT;
    'SRTCRST_N':'(0,0,0,0,0,0,BF9,0,0,0,0)';$S;IN;
    'VSS_A41':'(0,0,0,0,0,0,A41,0,0,0,0)';$S;
    'RSVD_AF15':'(0,0,0,0,0,0,0,AF15,0,0,0)';$S;OUT;
    'RSVD_AN26':'(0,0,0,0,0,0,0,AN26,0,0,0)';$S;OUT;
    'VCCP_1P05_W24':'(0,0,0,0,0,0,0,W24,0,0,0)';$S;
    'VCCP_1P05_W22':'(0,0,0,0,0,0,0,W22,0,0,0)';$S;
    'VCCP_1P05_W20':'(0,0,0,0,0,0,0,W20,0,0,0)';$S;
    'VCCP_1P05_W19':'(0,0,0,0,0,0,0,W19,0,0,0)';$S;
    'VCCP_1P05_W17':'(0,0,0,0,0,0,0,W17,0,0,0)';$S;
    'VCCP_1P05_AB24':'(0,0,0,0,0,0,0,AB24,0,0,0)';$S;
    'VCCP_1P05_AB22':'(0,0,0,0,0,0,0,AB22,0,0,0)';$S;
    'VCCP_1P05_AB20':'(0,0,0,0,0,0,0,AB20,0,0,0)';$S;
    'VCCP_1P05_AB19':'(0,0,0,0,0,0,0,AB19,0,0,0)';$S;
    'VCCP_1P05_AJ27':'(0,0,0,0,0,0,0,AJ27,0,0,0)';$S;
    'VCCP_1P05_AJ25':'(0,0,0,0,0,0,0,AJ25,0,0,0)';$S;
    'VCCP_1P05_AG27':'(0,0,0,0,0,0,0,AG27,0,0,0)';$S;
    'VCCP_1P05_AG25':'(0,0,0,0,0,0,0,AG25,0,0,0)';$S;
    'VCCP_1P05_AF27':'(0,0,0,0,0,0,0,AF27,0,0,0)';$S;
    'VCCP_1P05_AF25':'(0,0,0,0,0,0,0,AF25,0,0,0)';$S;
    'VCCP_1P05_AD27':'(0,0,0,0,0,0,0,AD27,0,0,0)';$S;
    'VCCP_1P05_AD25':'(0,0,0,0,0,0,0,AD25,0,0,0)';$S;
    'VCCP_1P05_FILTERED_AB27':'(0,0,0,0,0,0,0,AB27,0,0,0)';$S;
    'VCCP_1P05_N26':'(0,0,0,0,0,0,0,N26,0,0,0)';$S;
    'VCCP_1P05_N23':'(0,0,0,0,0,0,0,N23,0,0,0)';$S;
    'VCCP_1P05_AR26':'(0,0,0,0,0,0,0,AR26,0,0,0)';$S;
    'VCCP_1P05_M24':'(0,0,0,0,0,0,0,M24,0,0,0)';$S;
    'VCCP_1P05_P15':'(0,0,0,0,0,0,0,P15,0,0,0)';$S;
    'VCCP_1P05_FILTERED_AL25':'(0,0,0,0,0,0,0,AL25,0,0,0)';$S;
    'VCCP_1P05_FILTERED_AG29':'(0,0,0,0,0,0,0,AG29,0,0,0)';$S;
    'VCCP_1P05_FILTERED_AE29':'(0,0,0,0,0,0,0,AE29,0,0,0)';$S;
    'VCCP_1P05_FILTERED_R29':'(0,0,0,0,0,0,0,R29,0,0,0)';$S;
    'VCCP_1P05_FILTERED_U27':'(0,0,0,0,0,0,0,U27,0,0,0)';$S;
    'VCCP_1P05_FILTERED_AA29':'(0,0,0,0,0,0,0,AA29,0,0,0)';$S;
    'VCCP_1P05_FILTERED_R26':'(0,0,0,0,0,0,0,R26,0,0,0)';$S;
    'VCCP_1P05_FILTERED_R23':'(0,0,0,0,0,0,0,R23,0,0,0)';$S;
    'VCCP_1P8_N20':'(0,0,0,0,0,0,0,N20,0,0,0)';$S;
    'VCCP_1P8_U24':'(0,0,0,0,0,0,0,U24,0,0,0)';$S;
    'VCCP_1P8_U22':'(0,0,0,0,0,0,0,U22,0,0,0)';$S;
    'VCCP_1P8_U20':'(0,0,0,0,0,0,0,U20,0,0,0)';$S;
    'VCCP_1P8_U19':'(0,0,0,0,0,0,0,U19,0,0,0)';$S;
    'VCCP_1P8_U17':'(0,0,0,0,0,0,0,U17,0,0,0)';$S;
    'VCCP_1P8_FILTERED_AB34':'(0,0,0,0,0,0,0,AB34,0,0,0)';$S;
    'VCCP_1P8_FILTERED_W29':'(0,0,0,0,0,0,0,W29,0,0,0)';$S;
    'VCCP_1P8_FILTERED_U29':'(0,0,0,0,0,0,0,U29,0,0,0)';$S;
    'VCCP_1P8_FILTERED_W27':'(0,0,0,0,0,0,0,W27,0,0,0)';$S;
    'VCCP_1P8_FILTERED_AB31':'(0,0,0,0,0,0,0,AB31,0,0,0)';$S;
    'VCCP_3P3_P21':'(0,0,0,0,0,0,0,P21,0,0,0)';$S;
    'VCCP_3P3_AL17':'(0,0,0,0,0,0,0,AL17,0,0,0)';$S;
    'VCCP_3P3_AJ17':'(0,0,0,0,0,0,0,AJ17,0,0,0)';$S;
    'VCCP_3P3_AG17':'(0,0,0,0,0,0,0,AG17,0,0,0)';$S;
    'VCCP_3P3_AF17':'(0,0,0,0,0,0,0,AF17,0,0,0)';$S;
    'VCCP_3P3_AK15':'(0,0,0,0,0,0,0,AK15,0,0,0)';$S;
    'VCCP_3P3_DSW_AD15':'(0,0,0,0,0,0,0,AD15,0,0,0)';$S;
    'VCCP_3P3_DSW_V15':'(0,0,0,0,0,0,0,V15,0,0,0)';$S;
    'VCCP_GPPD_1P8_3P3':'(0,0,0,0,0,0,0,T15,0,0,0)';$S;
    'VCCP_GPPE_1P8_3P3':'(0,0,0,0,0,0,0,AN20,0,0,0)';$S;
    'VCCP_GPPI_1P8_3P3':'(0,0,0,0,0,0,0,AD17,0,0,0)';$S;
    'VCCP_VNN_AR23':'(0,0,0,0,0,0,0,AR23,0,0,0)';$S;
    'VCCP_VNN_AP21':'(0,0,0,0,0,0,0,AP21,0,0,0)';$S;
    'VCCP_VNN_AN23':'(0,0,0,0,0,0,0,AN23,0,0,0)';$S;
    'VCCP_VNN_AL22':'(0,0,0,0,0,0,0,AL22,0,0,0)';$S;
    'VCCP_VNN_AL20':'(0,0,0,0,0,0,0,AL20,0,0,0)';$S;
    'VCCP_VNN_AJ22':'(0,0,0,0,0,0,0,AJ22,0,0,0)';$S;
    'VCCP_VNN_AJ20':'(0,0,0,0,0,0,0,AJ20,0,0,0)';$S;
    'VCCP_VNN_AG22':'(0,0,0,0,0,0,0,AG22,0,0,0)';$S;
    'VCCP_VNN_AG20':'(0,0,0,0,0,0,0,AG20,0,0,0)';$S;
    'VCCP_VNN_AF22':'(0,0,0,0,0,0,0,AF22,0,0,0)';$S;
    'VCCP_VNN_AF20':'(0,0,0,0,0,0,0,AF20,0,0,0)';$S;
    'VCCRTC':'(0,0,0,0,0,0,0,AH15,0,0,0)';$S;
    'VSS_BG40':'(0,0,0,0,0,0,0,BG40,0,0,0)';$S;
    'GPIO_RCOMP_1P8_3P3':'(0,0,0,0,0,0,0,0,AC13,0,0)';$S;IN;
    'RSVD_L13':'(0,0,0,0,0,0,0,0,L13,0,0)';$S;OUT;
    'RSVD_N13':'(0,0,0,0,0,0,0,0,N13,0,0)';$S;OUT;
    'RSVD_BB43':'(0,0,0,0,0,0,0,0,BB43,0,0)';$S;OUT;
    'RSVD_P18':'(0,0,0,0,0,0,0,0,P18,0,0)';$S;OUT;
    'RSVD_A4':'(0,0,0,0,0,0,0,0,A4,0,0)';$S;OUT;
    'RSVD_F1':'(0,0,0,0,0,0,0,0,F1,0,0)';$S;OUT;
    'RSVD_H1':'(0,0,0,0,0,0,0,0,H1,0,0)';$S;OUT;
    'VSS_Y8':'(0,0,0,0,0,0,0,0,0,Y8,0)';$S;
    'VSS_Y34':'(0,0,0,0,0,0,0,0,0,Y34,0)';$S;
    'VSS_Y31':'(0,0,0,0,0,0,0,0,0,Y31,0)';$S;
    'VSS_Y15':'(0,0,0,0,0,0,0,0,0,Y15,0)';$S;
    'VSS_Y11':'(0,0,0,0,0,0,0,0,0,Y11,0)';$S;
    'VSS_W5':'(0,0,0,0,0,0,0,0,0,W5,0)';$S;
    'VSS_W39':'(0,0,0,0,0,0,0,0,0,W39,0)';$S;
    'VSS_W3':'(0,0,0,0,0,0,0,0,0,W3,0)';$S;
    'VSS_W25':'(0,0,0,0,0,0,0,0,0,W25,0)';$S;
    'VSS_V31':'(0,0,0,0,0,0,0,0,0,V31,0)';$S;
    'VSS_V2':'(0,0,0,0,0,0,0,0,0,V2,0)';$S;
    'VSS_U5':'(0,0,0,0,0,0,0,0,0,U5,0)';$S;
    'VSS_U39':'(0,0,0,0,0,0,0,0,0,U39,0)';$S;
    'VSS_U25':'(0,0,0,0,0,0,0,0,0,U25,0)';$S;
    'VSS_U13':'(0,0,0,0,0,0,0,0,0,U13,0)';$S;
    'VSS_U10':'(0,0,0,0,0,0,0,0,0,U10,0)';$S;
    'VSS_T31':'(0,0,0,0,0,0,0,0,0,T31,0)';$S;
    'VSS_R36':'(0,0,0,0,0,0,0,0,0,R36,0)';$S;
    'VSS_R20':'(0,0,0,0,0,0,0,0,0,R20,0)';$S;
    'VSS_R16':'(0,0,0,0,0,0,0,0,0,R16,0)';$S;
    'VSS_R13':'(0,0,0,0,0,0,0,0,0,R13,0)';$S;
    'VSS_P8':'(0,0,0,0,0,0,0,0,0,P8,0)';$S;
    'VSS_P5':'(0,0,0,0,0,0,0,0,0,P5,0)';$S;
    'VSS_P43':'(0,0,0,0,0,0,0,0,0,P43,0)';$S;
    'VSS_P41':'(0,0,0,0,0,0,0,0,0,P41,0)';$S;
    'VSS_P39':'(0,0,0,0,0,0,0,0,0,P39,0)';$S;
    'VSS_P37':'(0,0,0,0,0,0,0,0,0,P37,0)';$S;
    'VSS_P31':'(0,0,0,0,0,0,0,0,0,P31,0)';$S;
    'VSS_P28':'(0,0,0,0,0,0,0,0,0,P28,0)';$S;
    'VSS_P24':'(0,0,0,0,0,0,0,0,0,P24,0)';$S;
    'VSS_P11':'(0,0,0,0,0,0,0,0,0,P11,0)';$S;
    'VSS_N32':'(0,0,0,0,0,0,0,0,0,N32,0)';$S;
    'VSS_N16':'(0,0,0,0,0,0,0,0,0,N16,0)';$S;
    'VSS_M5':'(0,0,0,0,0,0,0,0,0,M5,0)';$S;
    'VSS_M39':'(0,0,0,0,0,0,0,0,0,M39,0)';$S;
    'VSS_M37':'(0,0,0,0,0,0,0,0,0,M37,0)';$S;
    'VSS_M34':'(0,0,0,0,0,0,0,0,0,M34,0)';$S;
    'VSS_M31':'(0,0,0,0,0,0,0,0,0,M31,0)';$S;
    'VSS_M3':'(0,0,0,0,0,0,0,0,0,M3,0)';$S;
    'VSS_M28':'(0,0,0,0,0,0,0,0,0,M28,0)';$S;
    'VSS_M21':'(0,0,0,0,0,0,0,0,0,M21,0)';$S;
    'VSS_M18':'(0,0,0,0,0,0,0,0,0,M18,0)';$S;
    'VSS_M15':'(0,0,0,0,0,0,0,0,0,M15,0)';$S;
    'VSS_M11':'(0,0,0,0,0,0,0,0,0,M11,0)';$S;
    'VSS_M1':'(0,0,0,0,0,0,0,0,0,M1,0)';$S;
    'VSS_L36':'(0,0,0,0,0,0,0,0,0,L36,0)';$S;
    'VSS_L29':'(0,0,0,0,0,0,0,0,0,L29,0)';$S;
    'VSS_L26':'(0,0,0,0,0,0,0,0,0,L26,0)';$S;
    'VSS_L23':'(0,0,0,0,0,0,0,0,0,L23,0)';$S;
    'VSS_L20':'(0,0,0,0,0,0,0,0,0,L20,0)';$S;
    'VSS_L16':'(0,0,0,0,0,0,0,0,0,L16,0)';$S;
    'VSS_L10':'(0,0,0,0,0,0,0,0,0,L10,0)';$S;
    'VSS_K5':'(0,0,0,0,0,0,0,0,0,K5,0)';$S;
    'VSS_K39':'(0,0,0,0,0,0,0,0,0,K39,0)';$S;
    'VSS_K34':'(0,0,0,0,0,0,0,0,0,K34,0)';$S;
    'VSS_K24':'(0,0,0,0,0,0,0,0,0,K24,0)';$S;
    'VSS_K15':'(0,0,0,0,0,0,0,0,0,K15,0)';$S;
    'VSS_K11':'(0,0,0,0,0,0,0,0,0,K11,0)';$S;
    'VSS_J26':'(0,0,0,0,0,0,0,0,0,J26,0)';$S;
    'VSS_J20':'(0,0,0,0,0,0,0,0,0,J20,0)';$S;
    'VSS_J13':'(0,0,0,0,0,0,0,0,0,J13,0)';$S;
    'VSS_H8':'(0,0,0,0,0,0,0,0,0,H8,0)';$S;
    'VSS_H5':'(0,0,0,0,0,0,0,0,0,H5,0)';$S;
    'VSS_H39':'(0,0,0,0,0,0,0,0,0,H39,0)';$S;
    'VSS_G26':'(0,0,0,0,0,0,0,0,0,G26,0)';$S;
    'VSS_G20':'(0,0,0,0,0,0,0,0,0,G20,0)';$S;
    'VSS_G13':'(0,0,0,0,0,0,0,0,0,G13,0)';$S;
    'VSS_F39':'(0,0,0,0,0,0,0,0,0,F39,0)';$S;
    'VSS_F34':'(0,0,0,0,0,0,0,0,0,F34,0)';$S;
    'VSS_F31':'(0,0,0,0,0,0,0,0,0,F31,0)';$S;
    'VSS_F24':'(0,0,0,0,0,0,0,0,0,F24,0)';$S;
    'VSS_F15':'(0,0,0,0,0,0,0,0,0,F15,0)';$S;
    'VSS_E6':'(0,0,0,0,0,0,0,0,0,E6,0)';$S;
    'VSS_E38':'(0,0,0,0,0,0,0,0,0,E38,0)';$S;
    'VSS_E36':'(0,0,0,0,0,0,0,0,0,E36,0)';$S;
    'VSS_E34':'(0,0,0,0,0,0,0,0,0,E34,0)';$S;
    'VSS_E32':'(0,0,0,0,0,0,0,0,0,E32,0)';$S;
    'VSS_E30':'(0,0,0,0,0,0,0,0,0,E30,0)';$S;
    'VSS_E28':'(0,0,0,0,0,0,0,0,0,E28,0)';$S;
    'VSS_E26':'(0,0,0,0,0,0,0,0,0,E26,0)';$S;
    'VSS_E24':'(0,0,0,0,0,0,0,0,0,E24,0)';$S;
    'VSS_E22':'(0,0,0,0,0,0,0,0,0,E22,0)';$S;
    'VSS_E20':'(0,0,0,0,0,0,0,0,0,E20,0)';$S;
    'VSS_E18':'(0,0,0,0,0,0,0,0,0,E18,0)';$S;
    'VSS_E16':'(0,0,0,0,0,0,0,0,0,E16,0)';$S;
    'VSS_E14':'(0,0,0,0,0,0,0,0,0,E14,0)';$S;
    'VSS_E12':'(0,0,0,0,0,0,0,0,0,E12,0)';$S;
    'VSS_E10':'(0,0,0,0,0,0,0,0,0,E10,0)';$S;
    'VSS_D9':'(0,0,0,0,0,0,0,0,0,D9,0)';$S;
    'VSS_D5':'(0,0,0,0,0,0,0,0,0,D5,0)';$S;
    'VSS_D29':'(0,0,0,0,0,0,0,0,0,D29,0)';$S;
    'VSS_D13':'(0,0,0,0,0,0,0,0,0,D13,0)';$S;
    'VSS_C4':'(0,0,0,0,0,0,0,0,0,C4,0)';$S;
    'VSS_C26':'(0,0,0,0,0,0,0,0,0,C26,0)';$S;
    'VSS_C24':'(0,0,0,0,0,0,0,0,0,C24,0)';$S;
    'VSS_C22':'(0,0,0,0,0,0,0,0,0,C22,0)';$S;
    'VSS_C20':'(0,0,0,0,0,0,0,0,0,C20,0)';$S;
    'VSS_BG34':'(0,0,0,0,0,0,0,0,0,BG34,0)';$S;
    'VSS_BG10':'(0,0,0,0,0,0,0,0,0,BG10,0)';$S;
    'VSS_BF21':'(0,0,0,0,0,0,0,0,0,BF21,0)';$S;
    'VSS_BE34':'(0,0,0,0,0,0,0,0,0,BE34,0)';$S;
    'VSS_BE10':'(0,0,0,0,0,0,0,0,0,BE10,0)';$S;
    'VSS_BD39':'(0,0,0,0,0,0,0,0,0,BD39,0)';$S;
    'VSS_BD21':'(0,0,0,0,0,0,0,0,0,BD21,0)';$S;
    'VSS_BC8':'(0,0,0,0,0,0,0,0,0,BC8,0)';$S;
    'VSS_BC6':'(0,0,0,0,0,0,0,0,0,BC6,0)';$S;
    'VSS_BC38':'(0,0,0,0,0,0,0,0,0,BC38,0)';$S;
    'VSS_BC34':'(0,0,0,0,0,0,0,0,0,BC34,0)';$S;
    'VSS_BC32':'(0,0,0,0,0,0,0,0,0,BC32,0)';$S;
    'VSS_BC30':'(0,0,0,0,0,0,0,0,0,BC30,0)';$S;
    'VSS_BC28':'(0,0,0,0,0,0,0,0,0,BC28,0)';$S;
    'VSS_BC26':'(0,0,0,0,0,0,0,0,0,BC26,0)';$S;
    'VSS_BC24':'(0,0,0,0,0,0,0,0,0,BC24,0)';$S;
    'VSS_BC22':'(0,0,0,0,0,0,0,0,0,BC22,0)';$S;
    'VSS_BC20':'(0,0,0,0,0,0,0,0,0,BC20,0)';$S;
    'VSS_BC18':'(0,0,0,0,0,0,0,0,0,BC18,0)';$S;
    'VSS_BC16':'(0,0,0,0,0,0,0,0,0,BC16,0)';$S;
    'VSS_BC14':'(0,0,0,0,0,0,0,0,0,BC14,0)';$S;
    'VSS_BC12':'(0,0,0,0,0,0,0,0,0,BC12,0)';$S;
    'VSS_BC10':'(0,0,0,0,0,0,0,0,0,BC10,0)';$S;
    'VSS_BB5':'(0,0,0,0,0,0,0,0,0,BB5,0)';$S;
    'VSS_BB39':'(0,0,0,0,0,0,0,0,0,BB39,0)';$S;
    'VSS_B9':'(0,0,0,0,0,0,0,0,0,B9,0)';$S;
    'VSS_B29':'(0,0,0,0,0,0,0,0,0,B29,0)';$S;
    'VSS_B13':'(0,0,0,0,0,0,0,0,0,B13,0)';$S;
    'VSS_AY8':'(0,0,0,0,0,0,0,0,0,AY8,0)';$S;
    'VSS_AY5':'(0,0,0,0,0,0,0,0,0,AY5,0)';$S;
    'VSS_AY37':'(0,0,0,0,0,0,0,0,0,AY37,0)';$S;
    'VSS_AY34':'(0,0,0,0,0,0,0,0,0,AY34,0)';$S;
    'VSS_AY31':'(0,0,0,0,0,0,0,0,0,AY31,0)';$S;
    'VSS_AY28':'(0,0,0,0,0,0,0,0,0,AY28,0)';$S;
    'VSS_AY39':'(0,0,0,0,0,0,0,0,0,AY39,0)';$S;
    'VSS_F41':'(0,0,0,0,0,0,0,0,0,F41,0)';$S;
    'VSS_E40':'(0,0,0,0,0,0,0,0,0,E40,0)';$S;
    'VSS_BD5':'(0,0,0,0,0,0,0,0,0,BD5,0)';$S;
    'VSS_BC36':'(0,0,0,0,0,0,0,0,0,BC36,0)';$S;
    'VSS_AY3':'(0,0,0,0,0,0,0,0,0,AY3,0)';$S;
    'VSS_C38':'(0,0,0,0,0,0,0,0,0,C38,0)';$S;
    'VSS_B39':'(0,0,0,0,0,0,0,0,0,B39,0)';$S;
    'VSS_E8':'(0,0,0,0,0,0,0,0,0,E8,0)';$S;
    'VSS_D43':'(0,0,0,0,0,0,0,0,0,0,D43)';$S;
    'VSS_D1':'(0,0,0,0,0,0,0,0,0,0,D1)';$S;
    'VSS_C43':'(0,0,0,0,0,0,0,0,0,0,C43)';$S;
    'VSS_C41':'(0,0,0,0,0,0,0,0,0,0,C41)';$S;
    'VSS_C3':'(0,0,0,0,0,0,0,0,0,0,C3)';$S;
    'VSS_BG41':'(0,0,0,0,0,0,0,0,0,0,BG41)';$S;
    'VSS_BE43':'(0,0,0,0,0,0,0,0,0,0,BE43)';$S;
    'VSS_BE41':'(0,0,0,0,0,0,0,0,0,0,BE41)';$S;
    'VSS_BE3':'(0,0,0,0,0,0,0,0,0,0,BE3)';$S;
    'VSS_BE1':'(0,0,0,0,0,0,0,0,0,0,BE1)';$S;
    'VSS_BD43':'(0,0,0,0,0,0,0,0,0,0,BD43)';$S;
    'VSS_BD1':'(0,0,0,0,0,0,0,0,0,0,BD1)';$S;
    'VSS_E42':'(0,0,0,0,0,0,0,0,0,0,E42)';$S;
    'VSS_E2':'(0,0,0,0,0,0,0,0,0,0,E2)';$S;
    'VSS_D41':'(0,0,0,0,0,0,0,0,0,0,D41)';$S;
    'VSS_D3':'(0,0,0,0,0,0,0,0,0,0,D3)';$S;
    'VSS_BD41':'(0,0,0,0,0,0,0,0,0,0,BD41)';$S;
    'VSS_BD3':'(0,0,0,0,0,0,0,0,0,0,BD3)';$S;
    'VSS_BC42':'(0,0,0,0,0,0,0,0,0,0,BC42)';$S;
    'VSS_BC2':'(0,0,0,0,0,0,0,0,0,0,BC2)';$S;
    'VSS_F43':'(0,0,0,0,0,0,0,0,0,0,F43)';$S;
    'VSS_BG6':'(0,0,0,0,0,0,0,0,0,0,BG6)';$S;
    'VSS_BG4':'(0,0,0,0,0,0,0,0,0,0,BG4)';$S;
    'VSS_BG38':'(0,0,0,0,0,0,0,0,0,0,BG38)';$S;
    'VSS_BB1':'(0,0,0,0,0,0,0,0,0,0,BB1)';$S;
    'VSS_A6':'(0,0,0,0,0,0,0,0,0,0,A6)';$S;
    'VSS_A40':'(0,0,0,0,0,0,0,0,0,0,A40)';$S;
    'VSS_A38':'(0,0,0,0,0,0,0,0,0,0,A38)';$S;
    'VSS_AY24':'(0,0,0,0,0,0,0,0,0,0,AY24)';$S;
    'VSS_AY21':'(0,0,0,0,0,0,0,0,0,0,AY21)';$S;
    'VSS_AY18':'(0,0,0,0,0,0,0,0,0,0,AY18)';$S;
    'VSS_AY15':'(0,0,0,0,0,0,0,0,0,0,AY15)';$S;
    'VSS_AY11':'(0,0,0,0,0,0,0,0,0,0,AY11)';$S;
    'VSS_AW7':'(0,0,0,0,0,0,0,0,0,0,AW7)';$S;
    'VSS_AV8':'(0,0,0,0,0,0,0,0,0,0,AV8)';$S;
    'VSS_AV5':'(0,0,0,0,0,0,0,0,0,0,AV5)';$S;
    'VSS_AV39':'(0,0,0,0,0,0,0,0,0,0,AV39)';$S;
    'VSS_AV37':'(0,0,0,0,0,0,0,0,0,0,AV37)';$S;
    'VSS_AU36':'(0,0,0,0,0,0,0,0,0,0,AU36)';$S;
    'VSS_AU32':'(0,0,0,0,0,0,0,0,0,0,AU32)';$S;
    'VSS_AU29':'(0,0,0,0,0,0,0,0,0,0,AU29)';$S;
    'VSS_AU26':'(0,0,0,0,0,0,0,0,0,0,AU26)';$S;
    'VSS_AU23':'(0,0,0,0,0,0,0,0,0,0,AU23)';$S;
    'VSS_AU20':'(0,0,0,0,0,0,0,0,0,0,AU20)';$S;
    'VSS_AT8':'(0,0,0,0,0,0,0,0,0,0,AT8)';$S;
    'VSS_AT5':'(0,0,0,0,0,0,0,0,0,0,AT5)';$S;
    'VSS_AT39':'(0,0,0,0,0,0,0,0,0,0,AT39)';$S;
    'VSS_AT34':'(0,0,0,0,0,0,0,0,0,0,AT34)';$S;
    'VSS_AT31':'(0,0,0,0,0,0,0,0,0,0,AT31)';$S;
    'VSS_AT28':'(0,0,0,0,0,0,0,0,0,0,AT28)';$S;
    'VSS_AT24':'(0,0,0,0,0,0,0,0,0,0,AT24)';$S;
    'VSS_AT21':'(0,0,0,0,0,0,0,0,0,0,AT21)';$S;
    'VSS_AT15':'(0,0,0,0,0,0,0,0,0,0,AT15)';$S;
    'VSS_AT11':'(0,0,0,0,0,0,0,0,0,0,AT11)';$S;
    'VSS_AR32':'(0,0,0,0,0,0,0,0,0,0,AR32)';$S;
    'VSS_AR20':'(0,0,0,0,0,0,0,0,0,0,AR20)';$S;
    'VSS_AP5':'(0,0,0,0,0,0,0,0,0,0,AP5)';$S;
    'VSS_AP39':'(0,0,0,0,0,0,0,0,0,0,AP39)';$S;
    'VSS_AP37':'(0,0,0,0,0,0,0,0,0,0,AP37)';$S;
    'VSS_AP28':'(0,0,0,0,0,0,0,0,0,0,AP28)';$S;
    'VSS_AP24':'(0,0,0,0,0,0,0,0,0,0,AP24)';$S;
    'VSS_AP18':'(0,0,0,0,0,0,0,0,0,0,AP18)';$S;
    'VSS_AP11':'(0,0,0,0,0,0,0,0,0,0,AP11)';$S;
    'VSS_AN32':'(0,0,0,0,0,0,0,0,0,0,AN32)';$S;
    'VSS_AN29':'(0,0,0,0,0,0,0,0,0,0,AN29)';$S;
    'VSS_AN16':'(0,0,0,0,0,0,0,0,0,0,AN16)';$S;
    'VSS_AN13':'(0,0,0,0,0,0,0,0,0,0,AN13)';$S;
    'VSS_AM8':'(0,0,0,0,0,0,0,0,0,0,AM8)';$S;
    'VSS_AM31':'(0,0,0,0,0,0,0,0,0,0,AM31)';$S;
    'VSS_AM15':'(0,0,0,0,0,0,0,0,0,0,AM15)';$S;
    'VSS_AL39':'(0,0,0,0,0,0,0,0,0,0,AL39)';$S;
    'VSS_AL29':'(0,0,0,0,0,0,0,0,0,0,AL29)';$S;
    'VSS_AL27':'(0,0,0,0,0,0,0,0,0,0,AL27)';$S;
    'VSS_AL24':'(0,0,0,0,0,0,0,0,0,0,AL24)';$S;
    'VSS_AL19':'(0,0,0,0,0,0,0,0,0,0,AL19)';$S;
    'VSS_AK4':'(0,0,0,0,0,0,0,0,0,0,AK4)';$S;
    'VSS_AK37':'(0,0,0,0,0,0,0,0,0,0,AK37)';$S;
    'VSS_AK2':'(0,0,0,0,0,0,0,0,0,0,AK2)';$S;
    'VSS_AK11':'(0,0,0,0,0,0,0,0,0,0,AK11)';$S;
    'VSS_AJ5':'(0,0,0,0,0,0,0,0,0,0,AJ5)';$S;
    'VSS_AJ39':'(0,0,0,0,0,0,0,0,0,0,AJ39)';$S;
    'VSS_AJ36':'(0,0,0,0,0,0,0,0,0,0,AJ36)';$S;
    'VSS_AJ29':'(0,0,0,0,0,0,0,0,0,0,AJ29)';$S;
    'VSS_AJ24':'(0,0,0,0,0,0,0,0,0,0,AJ24)';$S;
    'VSS_AJ19':'(0,0,0,0,0,0,0,0,0,0,AJ19)';$S;
    'VSS_AH8':'(0,0,0,0,0,0,0,0,0,0,AH8)';$S;
    'VSS_AH31':'(0,0,0,0,0,0,0,0,0,0,AH31)';$S;
    'VSS_AG5':'(0,0,0,0,0,0,0,0,0,0,AG5)';$S;
    'VSS_AG39':'(0,0,0,0,0,0,0,0,0,0,AG39)';$S;
    'VSS_AG24':'(0,0,0,0,0,0,0,0,0,0,AG24)';$S;
    'VSS_AG19':'(0,0,0,0,0,0,0,0,0,0,AG19)';$S;
    'VSS_AG13':'(0,0,0,0,0,0,0,0,0,0,AG13)';$S;
    'VSS_AF42':'(0,0,0,0,0,0,0,0,0,0,AF42)';$S;
    'VSS_AF40':'(0,0,0,0,0,0,0,0,0,0,AF40)';$S;
    'VSS_AF31':'(0,0,0,0,0,0,0,0,0,0,AF31)';$S;
    'VSS_AF24':'(0,0,0,0,0,0,0,0,0,0,AF24)';$S;
    'VSS_AF19':'(0,0,0,0,0,0,0,0,0,0,AF19)';$S;
    'VSS_AE5':'(0,0,0,0,0,0,0,0,0,0,AE5)';$S;
    'VSS_AE39':'(0,0,0,0,0,0,0,0,0,0,AE39)';$S;
    'VSS_AE13':'(0,0,0,0,0,0,0,0,0,0,AE13)';$S;
    'VSS_AD8':'(0,0,0,0,0,0,0,0,0,0,AD8)';$S;
    'VSS_AD34':'(0,0,0,0,0,0,0,0,0,0,AD34)';$S;
    'VSS_AD31':'(0,0,0,0,0,0,0,0,0,0,AD31)';$S;
    'VSS_AD24':'(0,0,0,0,0,0,0,0,0,0,AD24)';$S;
    'VSS_AD22':'(0,0,0,0,0,0,0,0,0,0,AD22)';$S;
    'VSS_AD20':'(0,0,0,0,0,0,0,0,0,0,AD20)';$S;
    'VSS_AD19':'(0,0,0,0,0,0,0,0,0,0,AD19)';$S;
    'VSS_AD11':'(0,0,0,0,0,0,0,0,0,0,AD11)';$S;
    'VSS_AC5':'(0,0,0,0,0,0,0,0,0,0,AC5)';$S;
    'VSS_AC39':'(0,0,0,0,0,0,0,0,0,0,AC39)';$S;
    'VSS_AC36':'(0,0,0,0,0,0,0,0,0,0,AC36)';$S;
    'VSS_AC32':'(0,0,0,0,0,0,0,0,0,0,AC32)';$S;
    'VSS_AC29':'(0,0,0,0,0,0,0,0,0,0,AC29)';$S;
    'VSS_AB37':'(0,0,0,0,0,0,0,0,0,0,AB37)';$S;
    'VSS_AB25':'(0,0,0,0,0,0,0,0,0,0,AB25)';$S;
    'VSS_AB17':'(0,0,0,0,0,0,0,0,0,0,AB17)';$S;
    'VSS_AB15':'(0,0,0,0,0,0,0,0,0,0,AB15)';$S;
    'VSS_AA5':'(0,0,0,0,0,0,0,0,0,0,AA5)';$S;
    'VSS_AA39':'(0,0,0,0,0,0,0,0,0,0,AA39)';$S;
    'VSS_AA36':'(0,0,0,0,0,0,0,0,0,0,AA36)';$S;
    'VSS_AA32':'(0,0,0,0,0,0,0,0,0,0,AA32)';$S;
    'VSS_AA27':'(0,0,0,0,0,0,0,0,0,0,AA27)';$S;
    'VSS_AA25':'(0,0,0,0,0,0,0,0,0,0,AA25)';$S;
    'VSS_AA24':'(0,0,0,0,0,0,0,0,0,0,AA24)';$S;
    'VSS_AA22':'(0,0,0,0,0,0,0,0,0,0,AA22)';$S;
    'VSS_AA20':'(0,0,0,0,0,0,0,0,0,0,AA20)';$S;
    'VSS_AA19':'(0,0,0,0,0,0,0,0,0,0,AA19)';$S;
    'VSS_AA17':'(0,0,0,0,0,0,0,0,0,0,AA17)';$S;
    'VSS_A26':'(0,0,0,0,0,0,0,0,0,0,A26)';$S;
    'VSS_A24':'(0,0,0,0,0,0,0,0,0,0,A24)';$S;
    'VSS_A22':'(0,0,0,0,0,0,0,0,0,0,A22)';$S;
    'VSS_A20':'(0,0,0,0,0,0,0,0,0,0,A20)';$S;
end_primitive;
primitive 'GL852GOHY60-GL852G-OHY60,SMLF,A';body 'GL852GOHY60';
    'X1':'(10)';IN;
    'X2':'(11)';OUT;
    'TEST||SCL':'(18)';BIDI;
    'SDA':'(26)';BIDI;
    'V5':'(27)';
    'V33':'(28)';
    'AVDD'<0>:'(5)';
    'AVDD'<1>:'(9)';
    'AVDD'<2>:'(14)';
    'DVDD':'(21)';
    'TH':'(TH)';
    'OVCUR1#||SMC':'(25)';IN;
    'OVCUR2#||SMD':'(24)';BIDI;
    'OVCUR3#':'(20)';IN;
    'OVCUR4#':'(19)';IN;
    'RESET#':'(17)';IN;
    'PGANG':'(23)';BIDI;
    'PSELF':'(22)';IN;
    'RREF':'(8)';IN;
    'DP0':'(2)';BIDI;
    'DM0':'(1)';BIDI;
    'DP1':'(4)';BIDI;
    'DM1':'(3)';BIDI;
    'DP2':'(7)';BIDI;
    'DM2':'(6)';BIDI;
    'DP3':'(13)';BIDI;
    'DM3':'(12)';BIDI;
    'DP4':'(16)';BIDI;
    'DM4':'(15)';BIDI;
end_primitive;
primitive 'GL852GOHY60-GL852G-OHY60,SMLF,B';body 'GL852GOHY60';
    'X1':'(10)';IN;
    'X2':'(11)';OUT;
    'TEST||SCL':'(18)';BIDI;
    'SDA':'(26)';BIDI;
    'V5':'(27)';
    'V33':'(28)';
    'AVDD'<0>:'(5)';
    'AVDD'<1>:'(9)';
    'AVDD'<2>:'(14)';
    'DVDD':'(21)';
    'TH':'(TH)';
    'OVCUR1#||SMC':'(25)';IN;
    'OVCUR2#||SMD':'(24)';BIDI;
    'OVCUR3#':'(20)';IN;
    'OVCUR4#':'(19)';IN;
    'RESET#':'(17)';IN;
    'PGANG':'(23)';BIDI;
    'PSELF':'(22)';IN;
    'RREF':'(8)';IN;
    'DP0':'(2)';BIDI;
    'DM0':'(1)';BIDI;
    'DP1':'(4)';BIDI;
    'DM1':'(3)';BIDI;
    'DP2':'(7)';BIDI;
    'DM2':'(6)';BIDI;
    'DP3':'(13)';BIDI;
    'DM3':'(12)';BIDI;
    'DP4':'(16)';BIDI;
    'DM4':'(15)';BIDI;
end_primitive;
primitive 'GND_HOLE_TH-EMPTY,GND_HOLE140';body 'GND_HOLE';
    'GND3':'(3)';
    'GND2':'(2)';
    'GND9':'(9)';
    'GND8':'(8)';
    'GND7':'(7)';
    'GND6':'(6)';
    'GND5':'(5)';
    'GND4':'(4)';
end_primitive;
primitive 'GND_HOLE_TH-EMPTY,GND_HOLE514';body 'GND_HOLE';
    'GND3':'(3)';
    'GND2':'(2)';
    'GND9':'(9)';
    'GND8':'(8)';
    'GND7':'(7)';
    'GND6':'(6)';
    'GND5':'(5)';
    'GND4':'(4)';
end_primitive;
primitive 'GND_HOLE_TH-EMPTY,TMP-QGND_HOLA';body 'GND_HOLE';
    'GND3':'(3)';
    'GND2':'(2)';
    'GND9':'(9)';
    'GND8':'(8)';
    'GND7':'(7)';
    'GND6':'(6)';
    'GND5':'(5)';
    'GND4':'(4)';
end_primitive;
primitive 'GTL2014PW-GTL2014PW,SMLF,IC,ALA';body 'GTL2014PW';
    'B0':'(2)';BIDI;
    'B1':'(3)';BIDI;
    'B2':'(5)';BIDI;
    'B3':'(6)';BIDI;
    'GND_2':'(11)';
    'GND_1':'(8)';
    'GND_0':'(7)';
    'A3':'(9)';BIDI;
    'A2':'(10)';BIDI;
    'A1':'(12)';BIDI;
    'A0':'(13)';BIDI;
    'DIR':'(1)';IN;
    'VREF':'(4)';
    'VCC':'(14)';
end_primitive;
primitive 'HOLE_TH-EMPTY,DUMMY50';body 'HOLE';
    '1':'(1)';BIDI;
end_primitive;
primitive 'HOLE_TH-EMPTY,HOLE1079';body 'HOLE';
    '1':'(1)';BIDI;
end_primitive;
primitive 'HOLE_TH-EMPTY,HOLE1187';body 'HOLE';
    '1':'(1)';BIDI;
end_primitive;
primitive 'HOLE_TH-EMPTY,HOLE1195';body 'HOLE';
    '1':'(1)';BIDI;
end_primitive;
primitive 'HOLE_TH-EMPTY,HOLE1247';body 'HOLE';
    '1':'(1)';BIDI;
end_primitive;
primitive 'HOLE_TH-EMPTY,HOLE1248';body 'HOLE';
    '1':'(1)';BIDI;
end_primitive;
primitive 'HOLE_TH-EMPTY,HOLE372';body 'HOLE';
    '1':'(1)';BIDI;
end_primitive;
primitive 'HOLE_TH-EMPTY,HOLE596';body 'HOLE';
    '1':'(1)';BIDI;
end_primitive;
primitive 'HOLE_TH-EMPTY,SP_HOLE1199';body 'HOLE';
    '1':'(1)';BIDI;
end_primitive;
primitive 'HOLE_TH-EMPTY,TMP-C_T2I_ALEX_1A';body 'HOLE';
    '1':'(1)';BIDI;
end_primitive;
primitive 'HOLE_TH-EMPTY,TMP-Q_HOLE78';body 'HOLE';
    '1':'(1)';BIDI;
end_primitive;
primitive 'INA183A1IDBVR-INA183A1IDBVR,SMA';body 'INA183A1IDBVR';
    'GND0':'(1)';
    'GND1':'(2)';
    'OUT':'(3)';OUT;
    'IN-':'(4)';IN;
    'IN+':'(5)';IN;
end_primitive;
primitive 'INA230AIRGTR-INA230AIRGTR,SMLFA';body 'INA230AIRGTR';
    'VS':'(9)';
    'A1':'(1)';IN;
    'A0':'(2)';IN;
    'SCL':'(5)';IN;
    'SDA':'(4)';BIDI;
    'BUS':'(11)';IN;
    'IN+':'(13)';IN;
    'IN-':'(12)';IN;
    'ALERT':'(3)';OUT;
    'NC0':'(6)';OUT;
    'NC1':'(7)';OUT;
    'NC2':'(8)';OUT;
    'NC3':'(14)';OUT;
    'NC4':'(15)';OUT;
    'NC5':'(16)';OUT;
    'GND':'(10)';
    'TH':'(TH)';
end_primitive;
primitive 'INA230AIRGTR-INA230AIRGTR,SMLFB';body 'INA230AIRGTR';
    'VS':'(9)';
    'A1':'(1)';IN;
    'A0':'(2)';IN;
    'SCL':'(5)';IN;
    'SDA':'(4)';BIDI;
    'BUS':'(11)';IN;
    'IN+':'(13)';IN;
    'IN-':'(12)';IN;
    'ALERT':'(3)';OUT;
    'NC0':'(6)';OUT;
    'NC1':'(7)';OUT;
    'NC2':'(8)';OUT;
    'NC3':'(14)';OUT;
    'NC4':'(15)';OUT;
    'NC5':'(16)';OUT;
    'GND':'(10)';
    'TH':'(TH)';
end_primitive;
primitive 'IR3889MTRPBF-IR3889MTRPBF,SMLFA';body 'IR3889MTRPBF';
    'NC3':'(34)';OUT;
    'TON||MODE':'(36)';IN;
    'VIN':'(3)';
    'FB':'(30)';IN;
    'BOOT':'(26)';IN;
    'ILIM':'(1)';IN;
    'PHASE':'(25)';OUT;
    'VCC||LDO':'(4)';
    'VSENM':'(31)';IN;
    'NC4':'(35)';OUT;
    'PGND':'(7_10-19)';
    'NC2':'(33)';OUT;
    'SW':'(11_18)';
    'PVIN':'(20_24)';
    'PGOOD':'(2)';OUT;
    'NC1':'(28)';OUT;
    'AGND':'(32)';
    'EN':'(27)';IN;
    'VDRV':'(5)';
    'GATEL1':'(6)';IN;
    'SS||LATCH':'(29)';IN;
    'GATEL2':'(37)';IN;
end_primitive;
primitive 'ISL69260IRAZT-ISL69260IRAZ-T,SA';body 'ISL69260IRAZT';
    'CS7':'(23)';IN;
    'VCC':'(39)';
    'EN1':'(20)';IN;
    'PMSCL':'(10)';IN;
    'SVDATA':'(18)';BIDI;
    'CS6':'(24)';IN;
    'NSVALERT#':'(19)';OUT;
    'NVRHOT#':'(14)';OUT;
    'CS5':'(25)';IN;
    'CS4':'(26)';IN;
    'PG1':'(16)';OUT;
    'SVCLK':'(17)';IN;
    'NPMALERT#':'(11)';OUT;
    'EN0':'(13)';IN;
    'RGND0':'(22)';IN;
    'PMSDA':'(9)';BIDI;
    'PWM4':'(5)';OUT;
    'PWM5':'(6)';OUT;
    'VSEN0':'(21)';IN;
    'PWM1':'(2)';OUT;
    'PG0':'(12)';OUT;
    'PWM6':'(7)';OUT;
    'VCCS':'(40)';
    'VMON||IINSEN||VSYS||ISYS':'(37)';IN;
    'VINSEN||VSYS':'(38)';IN;
    'TEMP1||ISYS':'(36)';IN;
    'NPINALERT#||NPSYSCRIT#':'(15)';OUT;
    'VSEN1':'(32)';IN;
    'RGND1':'(31)';IN;
    'CS1':'(29)';IN;
    'PWM7':'(8)';OUT;
    'PWM3':'(4)';OUT;
    'CS3':'(27)';IN;
    'PWM2':'(3)';OUT;
    'CS2':'(28)';IN;
    'CFP':'(33)';OUT;
    'TH_GND':'(TH)';
    'ADDR_CFG':'(34)';IN;
    'TEMP0':'(35)';IN;
    'PWM0':'(1)';OUT;
    'CS0':'(30)';IN;
end_primitive;
primitive 'ISL99390FRZTR5935-ISL99390FRZ-A';body 'ISL99390FRZTR5935';
    'PWM':'(34)';IN;
    'REFIN':'(39)';IN;
    'VCC':'(3)';
    'AGND':'(2)';
    'BOOT':'(33)';
    'VIN1':'(25_29)';IN;
    'PHASE':'(32)';
    'PVCC':'(4)';
    'TOUT_FLT':'(36)';OUT;
    'IOUT':'(38)';OUT;
    'LSET':'(37)';OUT;
    'SW':'(10_19)';OUT;
    'PGND1':'(5)';
    'VIN2':'(30)';IN;
    'VOS':'(1)';IN;
    'PGND3':'(40)';
    'EN':'(35)';IN;
    'DNC':'(31)';OUT;
    'GL1':'(6)';OUT;
    'GL2':'(41)';OUT;
    'PGND2':'(7_9-20_24)';
end_primitive;
primitive 'LCMXO3LF9400C5BG484C-LCMXO3LF-A';body 'LCMXO3LF9400C5BG484C';
    'PL2A':'(D3,0,0,0,0,0,0)';$S;BIDI;
    'PL2B':'(D4,0,0,0,0,0,0)';$S;BIDI;
    'PL2C':'(F6,0,0,0,0,0,0)';$S;BIDI;
    'PL2D':'(G7,0,0,0,0,0,0)';$S;BIDI;
    'PL3A||L_GPLLT_FB':'(E4,0,0,0,0,0,0)';$S;BIDI;
    'PL3B||L_GPLLC_FB':'(F5,0,0,0,0,0,0)';$S;BIDI;
    'PL3C':'(G6,0,0,0,0,0,0)';$S;BIDI;
    'PL3D':'(H7,0,0,0,0,0,0)';$S;BIDI;
    'PL4A||L_GPLLT_IN':'(C1,0,0,0,0,0,0)';$S;BIDI;
    'PL4B||L_GPLLC_IN':'(D2,0,0,0,0,0,0)';$S;BIDI;
    'PL4C':'(G5,0,0,0,0,0,0)';$S;BIDI;
    'PL4D':'(H6,0,0,0,0,0,0)';$S;BIDI;
    'PL5A':'(D1,0,0,0,0,0,0)';$S;BIDI;
    'PL5B':'(E2,0,0,0,0,0,0)';$S;BIDI;
    'PL5C':'(E3,0,0,0,0,0,0)';$S;BIDI;
    'PL5D':'(F4,0,0,0,0,0,0)';$S;BIDI;
    'PL13A':'(L7,0,0,0,0,0,0)';$S;BIDI;
    'PL13B':'(K5,0,0,0,0,0,0)';$S;BIDI;
    'PL13C':'(K4,0,0,0,0,0,0)';$S;BIDI;
    'PL13D':'(K3,0,0,0,0,0,0)';$S;BIDI;
    'PL14A':'(K2,0,0,0,0,0,0)';$S;BIDI;
    'PL14B':'(K1,0,0,0,0,0,0)';$S;BIDI;
    'PL16A||PCLKT4_0':'(L1,0,0,0,0,0,0)';$S;BIDI;
    'PL16B||PCLKC4_0':'(M2,0,0,0,0,0,0)';$S;BIDI;
    'PL20A':'(P4,0,0,0,0,0,0)';$S;BIDI;
    'PL20B':'(N5,0,0,0,0,0,0)';$S;BIDI;
    'PL20C':'(N6,0,0,0,0,0,0)';$S;BIDI;
    'PL20D':'(N7,0,0,0,0,0,0)';$S;BIDI;
    'PL21A':'(R2,0,0,0,0,0,0)';$S;BIDI;
    'PL21B':'(T1,0,0,0,0,0,0)';$S;BIDI;
    'PL21C':'(P5,0,0,0,0,0,0)';$S;BIDI;
    'PL21D':'(P6,0,0,0,0,0,0)';$S;BIDI;
    'PL26C':'(T5,0,0,0,0,0,0)';$S;BIDI;
    'PL26D':'(T6,0,0,0,0,0,0)';$S;BIDI;
    'PL14C':'(L6,0,0,0,0,0,0)';$S;BIDI;
    'PL14D':'(L5,0,0,0,0,0,0)';$S;BIDI;
    'PL16C':'(L3,0,0,0,0,0,0)';$S;BIDI;
    'PL16D':'(L4,0,0,0,0,0,0)';$S;BIDI;
    'PL6C':'(G3,0,0,0,0,0,0)';$S;BIDI;
    'PL6D':'(G4,0,0,0,0,0,0)';$S;BIDI;
    'PL6A':'(E1,0,0,0,0,0,0)';$S;BIDI;
    'PL6B':'(F1,0,0,0,0,0,0)';$S;BIDI;
    'PL25A':'(T2,0,0,0,0,0,0)';$S;BIDI;
    'PL25B':'(U1,0,0,0,0,0,0)';$S;BIDI;
    'PL24A':'(R3,0,0,0,0,0,0)';$S;BIDI;
    'PL24B':'(R4,0,0,0,0,0,0)';$S;BIDI;
    'PL24C':'(R5,0,0,0,0,0,0)';$S;BIDI;
    'PL24D':'(P7,0,0,0,0,0,0)';$S;BIDI;
    'PL25C':'(R6,0,0,0,0,0,0)';$S;BIDI;
    'PL25D':'(R7,0,0,0,0,0,0)';$S;BIDI;
    'PL26A':'(T3,0,0,0,0,0,0)';$S;BIDI;
    'PL26B':'(T4,0,0,0,0,0,0)';$S;BIDI;
    'PL17A':'(M1,0,0,0,0,0,0)';$S;BIDI;
    'PL17B':'(N1,0,0,0,0,0,0)';$S;BIDI;
    'PL17C':'(M6,0,0,0,0,0,0)';$S;BIDI;
    'PL17D':'(M5,0,0,0,0,0,0)';$S;BIDI;
    'PL18A':'(N2,0,0,0,0,0,0)';$S;BIDI;
    'PL18B':'(P1,0,0,0,0,0,0)';$S;BIDI;
    'PL18C':'(N3,0,0,0,0,0,0)';$S;BIDI;
    'PL18D':'(N4,0,0,0,0,0,0)';$S;BIDI;
    'PL19A':'(P2,0,0,0,0,0,0)';$S;BIDI;
    'PL19B':'(R1,0,0,0,0,0,0)';$S;BIDI;
    'PL19C':'(P3,0,0,0,0,0,0)';$S;BIDI;
    'PL19D':'(M7,0,0,0,0,0,0)';$S;BIDI;
    'PL27A||PCLKT3_0':'(U2,0,0,0,0,0,0)';$S;BIDI;
    'PL27B||PCLKC3_0':'(V1,0,0,0,0,0,0)';$S;BIDI;
    'PL27C':'(U3,0,0,0,0,0,0)';$S;BIDI;
    'PL27D':'(U4,0,0,0,0,0,0)';$S;BIDI;
    'PL28A':'(W1,0,0,0,0,0,0)';$S;BIDI;
    'PL28B':'(W2,0,0,0,0,0,0)';$S;BIDI;
    'PL28C':'(V4,0,0,0,0,0,0)';$S;BIDI;
    'PL28D':'(U5,0,0,0,0,0,0)';$S;BIDI;
    'PL29A':'(Y1,0,0,0,0,0,0)';$S;BIDI;
    'PL29B':'(AA1,0,0,0,0,0,0)';$S;BIDI;
    'PL29C':'(W3,0,0,0,0,0,0)';$S;BIDI;
    'PL29D':'(Y2,0,0,0,0,0,0)';$S;BIDI;
    'PL30A':'(Y3,0,0,0,0,0,0)';$S;BIDI;
    'PL30B':'(W4,0,0,0,0,0,0)';$S;BIDI;
    'PL30C':'(V5,0,0,0,0,0,0)';$S;BIDI;
    'PL30D':'(T7,0,0,0,0,0,0)';$S;BIDI;
    'PL7A||PCLKT5_0':'(G2,0,0,0,0,0,0)';$S;BIDI;
    'PL7B||PCLKC5_0':'(G1,0,0,0,0,0,0)';$S;BIDI;
    'PL7C':'(H4,0,0,0,0,0,0)';$S;BIDI;
    'PL7D':'(H3,0,0,0,0,0,0)';$S;BIDI;
    'PL10A':'(H2,0,0,0,0,0,0)';$S;BIDI;
    'PL10B':'(H1,0,0,0,0,0,0)';$S;BIDI;
    'PL10C':'(J7,0,0,0,0,0,0)';$S;BIDI;
    'PL10D':'(J6,0,0,0,0,0,0)';$S;BIDI;
    'PL11A':'(H5,0,0,0,0,0,0)';$S;BIDI;
    'PL11B':'(J5,0,0,0,0,0,0)';$S;BIDI;
    'PL11C':'(J4,0,0,0,0,0,0)';$S;BIDI;
    'PL11D':'(J3,0,0,0,0,0,0)';$S;BIDI;
    'PL12A':'(J2,0,0,0,0,0,0)';$S;BIDI;
    'PL12B':'(J1,0,0,0,0,0,0)';$S;BIDI;
    'PL12C':'(K7,0,0,0,0,0,0)';$S;BIDI;
    'PL12D':'(K6,0,0,0,0,0,0)';$S;BIDI;
    'PB5A':'(0,AA2,0,0,0,0,0)';$S;BIDI;
    'PB5B':'(0,AB2,0,0,0,0,0)';$S;BIDI;
    'PB5C':'(0,V6,0,0,0,0,0)';$S;BIDI;
    'PB5D':'(0,U6,0,0,0,0,0)';$S;BIDI;
    'PB7A||CSSPIN':'(0,AA3,0,0,0,0,0)';$S;BIDI;
    'PB7B':'(0,AB3,0,0,0,0,0)';$S;BIDI;
    'PB7C':'(0,Y4,0,0,0,0,0)';$S;BIDI;
    'PB7D':'(0,W5,0,0,0,0,0)';$S;BIDI;
    'PB8C':'(0,U7,0,0,0,0,0)';$S;BIDI;
    'PB8D':'(0,T8,0,0,0,0,0)';$S;BIDI;
    'PB8A':'(0,AA4,0,0,0,0,0)';$S;BIDI;
    'PB8B':'(0,AB4,0,0,0,0,0)';$S;BIDI;
    'PB10A':'(0,AA5,0,0,0,0,0)';$S;BIDI;
    'PB10B':'(0,AB5,0,0,0,0,0)';$S;BIDI;
    'PB10C':'(0,Y5,0,0,0,0,0)';$S;BIDI;
    'PB10D':'(0,Y6,0,0,0,0,0)';$S;BIDI;
    'PB13C':'(0,V8,0,0,0,0,0)';$S;BIDI;
    'PB13D':'(0,U8,0,0,0,0,0)';$S;BIDI;
    'PB16A||MCLK||CCLK':'(0,T9,0,0,0,0,0)';$S;BIDI;
    'PB16B||SO||SPISO':'(0,U9,0,0,0,0,0)';$S;BIDI;
    'PB18A':'(0,AA8,0,0,0,0,0)';$S;BIDI;
    'PB18B':'(0,AB8,0,0,0,0,0)';$S;BIDI;
    'PB21A':'(0,V10,0,0,0,0,0)';$S;BIDI;
    'PB21B':'(0,W10,0,0,0,0,0)';$S;BIDI;
    'PB22A||PCLKT2_0':'(0,AA10,0,0,0,0,0)';$S;BIDI;
    'PB22B||PCLKC2_0':'(0,AB10,0,0,0,0,0)';$S;BIDI;
    'PB24A':'(0,AA11,0,0,0,0,0)';$S;BIDI;
    'PB24B':'(0,AB11,0,0,0,0,0)';$S;BIDI;
    'PB24C':'(0,V11,0,0,0,0,0)';$S;BIDI;
    'PB24D':'(0,Y11,0,0,0,0,0)';$S;BIDI;
    'PB29A||PCLKT2_1':'(0,AB12,0,0,0,0,0)';$S;BIDI;
    'PB29B||PCLKC2_1':'(0,AA12,0,0,0,0,0)';$S;BIDI;
    'PB30A':'(0,AB13,0,0,0,0,0)';$S;BIDI;
    'PB30B':'(0,AA13,0,0,0,0,0)';$S;BIDI;
    'PB33A':'(0,AB14,0,0,0,0,0)';$S;BIDI;
    'PB33B':'(0,AA14,0,0,0,0,0)';$S;BIDI;
    'PB43A':'(0,AB19,0,0,0,0,0)';$S;BIDI;
    'PB43B':'(0,AA19,0,0,0,0,0)';$S;BIDI;
    'PB44A':'(0,AB20,0,0,0,0,0)';$S;BIDI;
    'PB44B':'(0,AA20,0,0,0,0,0)';$S;BIDI;
    'PB46A||SN':'(0,AB21,0,0,0,0,0)';$S;BIDI;
    'PB46B||SI||SISPI':'(0,AA21,0,0,0,0,0)';$S;BIDI;
    'PB35A':'(0,AB15,0,0,0,0,0)';$S;BIDI;
    'PB35B':'(0,AA15,0,0,0,0,0)';$S;BIDI;
    'PB11A':'(0,AA6,0,0,0,0,0)';$S;BIDI;
    'PB11B':'(0,AB6,0,0,0,0,0)';$S;BIDI;
    'PB11C':'(0,W6,0,0,0,0,0)';$S;BIDI;
    'PB11D':'(0,V7,0,0,0,0,0)';$S;BIDI;
    'PB13A':'(0,AA7,0,0,0,0,0)';$S;BIDI;
    'PB13B':'(0,AB7,0,0,0,0,0)';$S;BIDI;
    'PB16C':'(0,V9,0,0,0,0,0)';$S;BIDI;
    'PB16D':'(0,W8,0,0,0,0,0)';$S;BIDI;
    'PB18C':'(0,Y8,0,0,0,0,0)';$S;BIDI;
    'PB18D':'(0,W9,0,0,0,0,0)';$S;BIDI;
    'PB19A':'(0,AA9,0,0,0,0,0)';$S;BIDI;
    'PB19B':'(0,AB9,0,0,0,0,0)';$S;BIDI;
    'PB19C':'(0,T10,0,0,0,0,0)';$S;BIDI;
    'PB19D':'(0,U10,0,0,0,0,0)';$S;BIDI;
    'PB22C':'(0,T11,0,0,0,0,0)';$S;BIDI;
    'PB22D':'(0,U11,0,0,0,0,0)';$S;BIDI;
    'PB27A':'(0,Y12,0,0,0,0,0)';$S;BIDI;
    'PB27B':'(0,T12,0,0,0,0,0)';$S;BIDI;
    'PB27C':'(0,U12,0,0,0,0,0)';$S;BIDI;
    'PB27D':'(0,V12,0,0,0,0,0)';$S;BIDI;
    'PB29C':'(0,V13,0,0,0,0,0)';$S;BIDI;
    'PB29D':'(0,U13,0,0,0,0,0)';$S;BIDI;
    'PB30C':'(0,Y13,0,0,0,0,0)';$S;BIDI;
    'PB30D':'(0,W13,0,0,0,0,0)';$S;BIDI;
    'PB33C':'(0,Y14,0,0,0,0,0)';$S;BIDI;
    'PB33D':'(0,W14,0,0,0,0,0)';$S;BIDI;
    'PB32A':'(0,T13,0,0,0,0,0)';$S;BIDI;
    'PB32B':'(0,T14,0,0,0,0,0)';$S;BIDI;
    'PB32C':'(0,U14,0,0,0,0,0)';$S;BIDI;
    'PB32D':'(0,V14,0,0,0,0,0)';$S;BIDI;
    'PB35C':'(0,Y15,0,0,0,0,0)';$S;BIDI;
    'PB35D':'(0,W15,0,0,0,0,0)';$S;BIDI;
    'PB38A':'(0,AB16,0,0,0,0,0)';$S;BIDI;
    'PB38B':'(0,AA16,0,0,0,0,0)';$S;BIDI;
    'PB38C':'(0,V15,0,0,0,0,0)';$S;BIDI;
    'PB38D':'(0,U15,0,0,0,0,0)';$S;BIDI;
    'PB40A':'(0,AB17,0,0,0,0,0)';$S;BIDI;
    'PB40B':'(0,AA17,0,0,0,0,0)';$S;BIDI;
    'PB40C':'(0,Y17,0,0,0,0,0)';$S;BIDI;
    'PB40D':'(0,V16,0,0,0,0,0)';$S;BIDI;
    'PB41A':'(0,AB18,0,0,0,0,0)';$S;BIDI;
    'PB41B':'(0,AA18,0,0,0,0,0)';$S;BIDI;
    'PB41C':'(0,Y18,0,0,0,0,0)';$S;BIDI;
    'PB41D':'(0,W17,0,0,0,0,0)';$S;BIDI;
    'PB43C':'(0,T15,0,0,0,0,0)';$S;BIDI;
    'PB43D':'(0,U16,0,0,0,0,0)';$S;BIDI;
    'PB44C':'(0,Y19,0,0,0,0,0)';$S;BIDI;
    'PB44D':'(0,W18,0,0,0,0,0)';$S;BIDI;
    'PB46C':'(0,V17,0,0,0,0,0)';$S;BIDI;
    'PB46D':'(0,T16,0,0,0,0,0)';$S;BIDI;
    'PB21C':'(0,Y9,0,0,0,0,0)';$S;BIDI;
    'PB21D':'(0,Y10,0,0,0,0,0)';$S;BIDI;
    'PT43B||R_GPLLC':'(0,0,B21,0,0,0,0)';$S;BIDI;
    'PT43A||R_GPLLT':'(0,0,A20,0,0,0,0)';$S;BIDI;
    'PT41B':'(0,0,B19,0,0,0,0)';$S;BIDI;
    'PT41A':'(0,0,A18,0,0,0,0)';$S;BIDI;
    'PT31B':'(0,0,F14,0,0,0,0)';$S;BIDI;
    'PT31A':'(0,0,G14,0,0,0,0)';$S;BIDI;
    'PT28B':'(0,0,F12,0,0,0,0)';$S;BIDI;
    'PT28A':'(0,0,G12,0,0,0,0)';$S;BIDI;
    'PT27D||SDA||PCLKC0_0':'(0,0,A12,0,0,0,0)';$S;BIDI;
    'PT27C||SCL||PCLKT0_0':'(0,0,B12,0,0,0,0)';$S;BIDI;
    'PT44B||R_GPLLC':'(0,0,B22,0,0,0,0)';$S;BIDI;
    'PT44A||R_GPLLT':'(0,0,A21,0,0,0,0)';$S;BIDI;
    'PT23B||PCLKC0_1':'(0,0,A10,0,0,0,0)';$S;BIDI;
    'PT23A||PCLKT0_1':'(0,0,B10,0,0,0,0)';$S;BIDI;
    'PT15B':'(0,0,D8,0,0,0,0)';$S;BIDI;
    'PT9D':'(0,0,F7,0,0,0,0)';$S;BIDI;
    'PT9B||L_GPLLC':'(0,0,A2,0,0,0,0)';$S;BIDI;
    'PT9C':'(0,0,E6,0,0,0,0)';$S;BIDI;
    'PT9A||L_GPLLT':'(0,0,B1,0,0,0,0)';$S;BIDI;
    'PT15A':'(0,0,C8,0,0,0,0)';$S;BIDI;
    'PT11A':'(0,0,B3,0,0,0,0)';$S;BIDI;
    'PT11B':'(0,0,A4,0,0,0,0)';$S;BIDI;
    'PT22A':'(0,0,F10,0,0,0,0)';$S;BIDI;
    'PT22B':'(0,0,E10,0,0,0,0)';$S;BIDI;
    'PT11C':'(0,0,F8,0,0,0,0)';$S;BIDI;
    'PT11D':'(0,0,G8,0,0,0,0)';$S;BIDI;
    'PT10A':'(0,0,B2,0,0,0,0)';$S;BIDI;
    'PT10B':'(0,0,A3,0,0,0,0)';$S;BIDI;
    'PT10C':'(0,0,C3,0,0,0,0)';$S;BIDI;
    'PT10D':'(0,0,C4,0,0,0,0)';$S;BIDI;
    'PT12A':'(0,0,B4,0,0,0,0)';$S;BIDI;
    'PT12B':'(0,0,A5,0,0,0,0)';$S;BIDI;
    'PT12C':'(0,0,D5,0,0,0,0)';$S;BIDI;
    'PT12D':'(0,0,C5,0,0,0,0)';$S;BIDI;
    'PT13A':'(0,0,B5,0,0,0,0)';$S;BIDI;
    'PT13B':'(0,0,A6,0,0,0,0)';$S;BIDI;
    'PT13C':'(0,0,D6,0,0,0,0)';$S;BIDI;
    'PT13D':'(0,0,E7,0,0,0,0)';$S;BIDI;
    'PT14A':'(0,0,B6,0,0,0,0)';$S;BIDI;
    'PT14B':'(0,0,A7,0,0,0,0)';$S;BIDI;
    'PT14C':'(0,0,C6,0,0,0,0)';$S;BIDI;
    'PT14D':'(0,0,D7,0,0,0,0)';$S;BIDI;
    'PT20A':'(0,0,B8,0,0,0,0)';$S;BIDI;
    'PT20B':'(0,0,A8,0,0,0,0)';$S;BIDI;
    'PT20C':'(0,0,C9,0,0,0,0)';$S;BIDI;
    'PT20D':'(0,0,D9,0,0,0,0)';$S;BIDI;
    'PT21A':'(0,0,B9,0,0,0,0)';$S;BIDI;
    'PT21B':'(0,0,A9,0,0,0,0)';$S;BIDI;
    'PT21C':'(0,0,F9,0,0,0,0)';$S;BIDI;
    'PT21D':'(0,0,G9,0,0,0,0)';$S;BIDI;
    'PT23C':'(0,0,G11,0,0,0,0)';$S;BIDI;
    'PT23D':'(0,0,F11,0,0,0,0)';$S;BIDI;
    'PT24A':'(0,0,B11,0,0,0,0)';$S;BIDI;
    'PT24B':'(0,0,A11,0,0,0,0)';$S;BIDI;
    'PT24C':'(0,0,E11,0,0,0,0)';$S;BIDI;
    'PT24D':'(0,0,D11,0,0,0,0)';$S;BIDI;
    'PT27A':'(0,0,D12,0,0,0,0)';$S;BIDI;
    'PT27B':'(0,0,E12,0,0,0,0)';$S;BIDI;
    'PT28C':'(0,0,E13,0,0,0,0)';$S;BIDI;
    'PT28D':'(0,0,F13,0,0,0,0)';$S;BIDI;
    'PT29A':'(0,0,A13,0,0,0,0)';$S;BIDI;
    'PT29B':'(0,0,B13,0,0,0,0)';$S;BIDI;
    'PT29C':'(0,0,C13,0,0,0,0)';$S;BIDI;
    'PT29D':'(0,0,D13,0,0,0,0)';$S;BIDI;
    'PT30A':'(0,0,A14,0,0,0,0)';$S;BIDI;
    'PT30B':'(0,0,B14,0,0,0,0)';$S;BIDI;
    'PT30C':'(0,0,C14,0,0,0,0)';$S;BIDI;
    'PT30D':'(0,0,D14,0,0,0,0)';$S;BIDI;
    'PT38A':'(0,0,A15,0,0,0,0)';$S;BIDI;
    'PT38B':'(0,0,B15,0,0,0,0)';$S;BIDI;
    'PT38C':'(0,0,C15,0,0,0,0)';$S;BIDI;
    'PT38D':'(0,0,D15,0,0,0,0)';$S;BIDI;
    'PT39A':'(0,0,A16,0,0,0,0)';$S;BIDI;
    'PT39B':'(0,0,B17,0,0,0,0)';$S;BIDI;
    'PT39C':'(0,0,C17,0,0,0,0)';$S;BIDI;
    'PT39D':'(0,0,D16,0,0,0,0)';$S;BIDI;
    'PT40A':'(0,0,A17,0,0,0,0)';$S;BIDI;
    'PT40B':'(0,0,B18,0,0,0,0)';$S;BIDI;
    'PT40C':'(0,0,E16,0,0,0,0)';$S;BIDI;
    'PT40D':'(0,0,D17,0,0,0,0)';$S;BIDI;
    'PT41C':'(0,0,C18,0,0,0,0)';$S;BIDI;
    'PT41D':'(0,0,D18,0,0,0,0)';$S;BIDI;
    'PT42A':'(0,0,A19,0,0,0,0)';$S;BIDI;
    'PT42B':'(0,0,B20,0,0,0,0)';$S;BIDI;
    'PT42C':'(0,0,F15,0,0,0,0)';$S;BIDI;
    'PT42D':'(0,0,G15,0,0,0,0)';$S;BIDI;
    'PT43C':'(0,0,C19,0,0,0,0)';$S;BIDI;
    'PT43D':'(0,0,C20,0,0,0,0)';$S;BIDI;
    'PT15C||TDO':'(0,0,0,E8,0,0,0)';$S;BIDI;
    'PT15D||TDI':'(0,0,0,E9,0,0,0)';$S;BIDI;
    'PT22C||TCK':'(0,0,0,D10,0,0,0)';$S;BIDI;
    'PT22D||TMS':'(0,0,0,C10,0,0,0)';$S;BIDI;
    'PT31D||PROGRAMN':'(0,0,0,E15,0,0,0)';$S;BIDI;
    'PT44C||INITN':'(0,0,0,F16,0,0,0)';$S;BIDI;
    'PT44D||DONE':'(0,0,0,E17,0,0,0)';$S;BIDI;
    'PT31C||JTAGENB':'(0,0,0,E14,0,0,0)';$S;BIDI;
    'VCC1':'(0,0,0,0,K10,0,0)';$S;
    'VCC2':'(0,0,0,0,K11,0,0)';$S;
    'VCC3':'(0,0,0,0,K12,0,0)';$S;
    'VCC4':'(0,0,0,0,K13,0,0)';$S;
    'VCC5':'(0,0,0,0,L11,0,0)';$S;
    'VCC6':'(0,0,0,0,L12,0,0)';$S;
    'VCC7':'(0,0,0,0,M11,0,0)';$S;
    'VCC8':'(0,0,0,0,M12,0,0)';$S;
    'VCC9':'(0,0,0,0,N10,0,0)';$S;
    'VCC10':'(0,0,0,0,N11,0,0)';$S;
    'VCC11':'(0,0,0,0,N12,0,0)';$S;
    'VCC12':'(0,0,0,0,N13,0,0)';$S;
    'VCCIO5_1':'(0,0,0,0,F3,0,0)';$S;
    'VCCIO5_2':'(0,0,0,0,J8,0,0)';$S;
    'VCCIO5_3':'(0,0,0,0,K8,0,0)';$S;
    'VCCIO4_1':'(0,0,0,0,L8,0,0)';$S;
    'VCCIO4_2':'(0,0,0,0,M8,0,0)';$S;
    'VCCIO4_3':'(0,0,0,0,M3,0,0)';$S;
    'VCCIO3_1':'(0,0,0,0,N8,0,0)';$S;
    'VCCIO3_2':'(0,0,0,0,P8,0,0)';$S;
    'VCCIO3_3':'(0,0,0,0,V3,0,0)';$S;
    'VCCIO2_1':'(0,0,0,0,R9,0,0)';$S;
    'VCCIO2_2':'(0,0,0,0,R10,0,0)';$S;
    'VCCIO2_3':'(0,0,0,0,R11,0,0)';$S;
    'VCCIO2_4':'(0,0,0,0,R12,0,0)';$S;
    'VCCIO2_5':'(0,0,0,0,R13,0,0)';$S;
    'VCCIO2_6':'(0,0,0,0,R14,0,0)';$S;
    'VCCIO2_7':'(0,0,0,0,W7,0,0)';$S;
    'VCCIO2_8':'(0,0,0,0,W11,0,0)';$S;
    'VCCIO2_9':'(0,0,0,0,W16,0,0)';$S;
    'VCCIO1_1':'(0,0,0,0,F20,0,0)';$S;
    'VCCIO1_2':'(0,0,0,0,J15,0,0)';$S;
    'VCCIO1_3':'(0,0,0,0,K15,0,0)';$S;
    'VCCIO1_4':'(0,0,0,0,L15,0,0)';$S;
    'VCCIO1_5':'(0,0,0,0,M15,0,0)';$S;
    'VCCIO1_6':'(0,0,0,0,M18,0,0)';$S;
    'VCCIO1_7':'(0,0,0,0,N15,0,0)';$S;
    'VCCIO1_8':'(0,0,0,0,P15,0,0)';$S;
    'VCCIO1_9':'(0,0,0,0,V20,0,0)';$S;
    'VCCIO0_1':'(0,0,0,0,C7,0,0)';$S;
    'VCCIO0_2':'(0,0,0,0,C12,0,0)';$S;
    'VCCIO0_3':'(0,0,0,0,C16,0,0)';$S;
    'VCCIO0_4':'(0,0,0,0,G10,0,0)';$S;
    'VCCIO0_7':'(0,0,0,0,H11,0,0)';$S;
    'VCCIO0_8':'(0,0,0,0,H12,0,0)';$S;
    'VCCIO0_9':'(0,0,0,0,H14,0,0)';$S;
    'VCCIO0_6':'(0,0,0,0,H9,0,0)';$S;
    'VCCIO0_5':'(0,0,0,0,G13,0,0)';$S;
    'GND1':'(0,0,0,0,0,A1,0)';$S;
    'GND2':'(0,0,0,0,0,A22,0)';$S;
    'GND3':'(0,0,0,0,0,B7,0)';$S;
    'GND4':'(0,0,0,0,0,B16,0)';$S;
    'GND5':'(0,0,0,0,0,C2,0)';$S;
    'GND6':'(0,0,0,0,0,C11,0)';$S;
    'GND7':'(0,0,0,0,0,E5,0)';$S;
    'GND8':'(0,0,0,0,0,E18,0)';$S;
    'GND9':'(0,0,0,0,0,F2,0)';$S;
    'GND10':'(0,0,0,0,0,F21,0)';$S;
    'GND11':'(0,0,0,0,0,H8,0)';$S;
    'GND12':'(0,0,0,0,0,H10,0)';$S;
    'GND13':'(0,0,0,0,0,H13,0)';$S;
    'GND14':'(0,0,0,0,0,H15,0)';$S;
    'GND15':'(0,0,0,0,0,J9,0)';$S;
    'GND16':'(0,0,0,0,0,J10,0)';$S;
    'GND17':'(0,0,0,0,0,J11,0)';$S;
    'GND18':'(0,0,0,0,0,J12,0)';$S;
    'GND19':'(0,0,0,0,0,J13,0)';$S;
    'GND20':'(0,0,0,0,0,J14,0)';$S;
    'GND21':'(0,0,0,0,0,K9,0)';$S;
    'GND22':'(0,0,0,0,0,K14,0)';$S;
    'GND23':'(0,0,0,0,0,K21,0)';$S;
    'GND24':'(0,0,0,0,0,L2,0)';$S;
    'GND25':'(0,0,0,0,0,L9,0)';$S;
    'GND26':'(0,0,0,0,0,L10,0)';$S;
    'GND27':'(0,0,0,0,0,L13,0)';$S;
    'GND28':'(0,0,0,0,0,L14,0)';$S;
    'GND29':'(0,0,0,0,0,L18,0)';$S;
    'GND30':'(0,0,0,0,0,M4,0)';$S;
    'GND31':'(0,0,0,0,0,M9,0)';$S;
    'GND32':'(0,0,0,0,0,M10,0)';$S;
    'GND33':'(0,0,0,0,0,M13,0)';$S;
    'GND34':'(0,0,0,0,0,M14,0)';$S;
    'GND35':'(0,0,0,0,0,N9,0)';$S;
    'GND36':'(0,0,0,0,0,N14,0)';$S;
    'GND37':'(0,0,0,0,0,N21,0)';$S;
    'GND38':'(0,0,0,0,0,P9,0)';$S;
    'GND39':'(0,0,0,0,0,P10,0)';$S;
    'GND40':'(0,0,0,0,0,P11,0)';$S;
    'GND41':'(0,0,0,0,0,P12,0)';$S;
    'GND42':'(0,0,0,0,0,P13,0)';$S;
    'GND43':'(0,0,0,0,0,P14,0)';$S;
    'GND44':'(0,0,0,0,0,R8,0)';$S;
    'GND45':'(0,0,0,0,0,R15,0)';$S;
    'GND46':'(0,0,0,0,0,V2,0)';$S;
    'GND47':'(0,0,0,0,0,V21,0)';$S;
    'GND48':'(0,0,0,0,0,W12,0)';$S;
    'GND50':'(0,0,0,0,0,Y16,0)';$S;
    'GND49':'(0,0,0,0,0,Y7,0)';$S;
    'GND51':'(0,0,0,0,0,AB1,0)';$S;
    'GND52':'(0,0,0,0,0,AB22,0)';$S;
    'PR30B':'(0,0,0,0,0,0,W20)';$S;BIDI;
    'PR30A':'(0,0,0,0,0,0,V18)';$S;BIDI;
    'PR29D':'(0,0,0,0,0,0,V19)';$S;BIDI;
    'PR29B':'(0,0,0,0,0,0,Y21)';$S;BIDI;
    'PR29C':'(0,0,0,0,0,0,U17)';$S;BIDI;
    'PR29A':'(0,0,0,0,0,0,AA22)';$S;BIDI;
    'PR25B':'(0,0,0,0,0,0,W22)';$S;BIDI;
    'PR25A':'(0,0,0,0,0,0,V22)';$S;BIDI;
    'PR20B':'(0,0,0,0,0,0,R21)';$S;BIDI;
    'PR20A':'(0,0,0,0,0,0,R22)';$S;BIDI;
    'PR19B':'(0,0,0,0,0,0,P21)';$S;BIDI;
    'PR19A':'(0,0,0,0,0,0,N22)';$S;BIDI;
    'PR17B||PCLKC1_0':'(0,0,0,0,0,0,M21)';$S;BIDI;
    'PR17A||PCLKT1_0':'(0,0,0,0,0,0,M22)';$S;BIDI;
    'PR16B':'(0,0,0,0,0,0,L21)';$S;BIDI;
    'PR16A':'(0,0,0,0,0,0,K22)';$S;BIDI;
    'PR14B':'(0,0,0,0,0,0,L16)';$S;BIDI;
    'PR14A':'(0,0,0,0,0,0,L17)';$S;BIDI;
    'PR7B':'(0,0,0,0,0,0,H21)';$S;BIDI;
    'PR7A':'(0,0,0,0,0,0,H22)';$S;BIDI;
    'PR3B||R_GPLLC_IN':'(0,0,0,0,0,0,D21)';$S;BIDI;
    'PR3A||R_GPLLT_IN':'(0,0,0,0,0,0,D22)';$S;BIDI;
    'PR2B||R_GPLLC_FB':'(0,0,0,0,0,0,C22)';$S;BIDI;
    'PR2A||R_GPLLT_FB':'(0,0,0,0,0,0,C21)';$S;BIDI;
    'PR2C':'(0,0,0,0,0,0,F17)';$S;BIDI;
    'PR2D':'(0,0,0,0,0,0,G16)';$S;BIDI;
    'PR3C':'(0,0,0,0,0,0,D19)';$S;BIDI;
    'PR3D':'(0,0,0,0,0,0,D20)';$S;BIDI;
    'PR4C':'(0,0,0,0,0,0,E19)';$S;BIDI;
    'PR4D':'(0,0,0,0,0,0,E20)';$S;BIDI;
    'PR4A':'(0,0,0,0,0,0,E22)';$S;BIDI;
    'PR4B':'(0,0,0,0,0,0,E21)';$S;BIDI;
    'PR5A':'(0,0,0,0,0,0,F22)';$S;BIDI;
    'PR5B':'(0,0,0,0,0,0,G22)';$S;BIDI;
    'PR5C':'(0,0,0,0,0,0,F18)';$S;BIDI;
    'PR5D':'(0,0,0,0,0,0,F19)';$S;BIDI;
    'PR6A':'(0,0,0,0,0,0,G21)';$S;BIDI;
    'PR6B':'(0,0,0,0,0,0,G20)';$S;BIDI;
    'PR6C':'(0,0,0,0,0,0,G19)';$S;BIDI;
    'PR6D':'(0,0,0,0,0,0,G18)';$S;BIDI;
    'PR7C':'(0,0,0,0,0,0,G17)';$S;BIDI;
    'PR7D':'(0,0,0,0,0,0,H20)';$S;BIDI;
    'PR10A':'(0,0,0,0,0,0,H19)';$S;BIDI;
    'PR10B':'(0,0,0,0,0,0,H18)';$S;BIDI;
    'PR10C':'(0,0,0,0,0,0,H17)';$S;BIDI;
    'PR10D':'(0,0,0,0,0,0,H16)';$S;BIDI;
    'PR11A':'(0,0,0,0,0,0,J16)';$S;BIDI;
    'PR11B':'(0,0,0,0,0,0,J17)';$S;BIDI;
    'PR11C':'(0,0,0,0,0,0,J18)';$S;BIDI;
    'PR11D':'(0,0,0,0,0,0,J19)';$S;BIDI;
    'PR12A':'(0,0,0,0,0,0,J21)';$S;BIDI;
    'PR12B':'(0,0,0,0,0,0,J22)';$S;BIDI;
    'PR12C':'(0,0,0,0,0,0,J20)';$S;BIDI;
    'PR12D':'(0,0,0,0,0,0,K20)';$S;BIDI;
    'PR13A':'(0,0,0,0,0,0,K19)';$S;BIDI;
    'PR13B':'(0,0,0,0,0,0,K18)';$S;BIDI;
    'PR13C':'(0,0,0,0,0,0,K17)';$S;BIDI;
    'PR13D':'(0,0,0,0,0,0,K16)';$S;BIDI;
    'PR14C':'(0,0,0,0,0,0,L19)';$S;BIDI;
    'PR14D':'(0,0,0,0,0,0,L20)';$S;BIDI;
    'PR16C':'(0,0,0,0,0,0,L22)';$S;BIDI;
    'PR16D':'(0,0,0,0,0,0,M17)';$S;BIDI;
    'PR17C':'(0,0,0,0,0,0,M20)';$S;BIDI;
    'PR17D':'(0,0,0,0,0,0,M19)';$S;BIDI;
    'PR18A':'(0,0,0,0,0,0,M16)';$S;BIDI;
    'PR18B':'(0,0,0,0,0,0,N16)';$S;BIDI;
    'PR18C':'(0,0,0,0,0,0,N17)';$S;BIDI;
    'PR18D':'(0,0,0,0,0,0,N18)';$S;BIDI;
    'PR19C':'(0,0,0,0,0,0,N20)';$S;BIDI;
    'PR19D':'(0,0,0,0,0,0,N19)';$S;BIDI;
    'PR20C':'(0,0,0,0,0,0,P22)';$S;BIDI;
    'PR20D':'(0,0,0,0,0,0,P20)';$S;BIDI;
    'PR21A':'(0,0,0,0,0,0,T22)';$S;BIDI;
    'PR21B':'(0,0,0,0,0,0,T21)';$S;BIDI;
    'PR21C':'(0,0,0,0,0,0,P19)';$S;BIDI;
    'PR21D':'(0,0,0,0,0,0,P18)';$S;BIDI;
    'PR24A':'(0,0,0,0,0,0,P17)';$S;BIDI;
    'PR24B':'(0,0,0,0,0,0,P16)';$S;BIDI;
    'PR24C':'(0,0,0,0,0,0,U22)';$S;BIDI;
    'PR24D':'(0,0,0,0,0,0,U21)';$S;BIDI;
    'PR25C':'(0,0,0,0,0,0,R20)';$S;BIDI;
    'PR25D':'(0,0,0,0,0,0,R19)';$S;BIDI;
    'PR26A':'(0,0,0,0,0,0,R18)';$S;BIDI;
    'PR26B':'(0,0,0,0,0,0,R17)';$S;BIDI;
    'PR26C':'(0,0,0,0,0,0,R16)';$S;BIDI;
    'PR26D':'(0,0,0,0,0,0,T20)';$S;BIDI;
    'PR27A':'(0,0,0,0,0,0,T19)';$S;BIDI;
    'PR27B':'(0,0,0,0,0,0,T18)';$S;BIDI;
    'PR27C':'(0,0,0,0,0,0,T17)';$S;BIDI;
    'PR27D':'(0,0,0,0,0,0,U20)';$S;BIDI;
    'PR28A':'(0,0,0,0,0,0,Y22)';$S;BIDI;
    'PR28B':'(0,0,0,0,0,0,W21)';$S;BIDI;
    'PR28C':'(0,0,0,0,0,0,U19)';$S;BIDI;
    'PR28D':'(0,0,0,0,0,0,U18)';$S;BIDI;
    'PR30C':'(0,0,0,0,0,0,W19)';$S;BIDI;
    'PR30D':'(0,0,0,0,0,0,Y20)';$S;BIDI;
end_primitive;
primitive 'LM4040AIM3X25NOPB-LM4040AIM3X-A';body 'LM4040AIM3X25NOPB';
    '1+':'(1)';BIDI;
    '2-':'(2)';OUT;
    '3':'(3)';BIDI;
end_primitive;
primitive 'LM75BD-LM75BD,SMLF,IC,AL0075BDA';body 'LM75BD';
    'SDA':'(1)';BIDI;
    'SCL':'(2)';IN;
    'OS':'(3)';OUT;
    'GND':'(4)';
    'A2':'(5)';IN;
    'A1':'(6)';IN;
    'A0':'(7)';IN;
    'VCC':'(8)';
end_primitive;
primitive 'LT6700CS61TRPBF-LT6700CS6-1#TRA';body 'LT6700CS61TRPBF';
    'VS':'(5)';
    'INB-':'(4)';IN;
    'GND':'(2)';
    'OUTA':'(1)';OUT;
    'INA+':'(3)';IN;
    'OUTB':'(6)';OUT;
end_primitive;
primitive 'LTC4307CMS8-LTC4307CMS8,SMLF,EA';body 'LTC4307CMS8';
    'ENABLE':'(1)';IN;
    'SCL_IN':'(3)';BIDI;
    'SDA_IN':'(6)';BIDI;
    'SCL_OUT':'(2)';BIDI;
    'SDA_OUT':'(7)';BIDI;
    'READY':'(5)';OUT;
    'GND':'(4)';
    'VCC':'(8)';
end_primitive;
primitive 'LTC4307CMS8-LTC4307CMS8,SMLF,IA';body 'LTC4307CMS8';
    'ENABLE':'(1)';IN;
    'SCL_IN':'(3)';BIDI;
    'SDA_IN':'(6)';BIDI;
    'SCL_OUT':'(2)';BIDI;
    'SDA_OUT':'(7)';BIDI;
    'READY':'(5)';OUT;
    'GND':'(4)';
    'VCC':'(8)';
end_primitive;
primitive 'M24128BWMN6TP-M24128-BWMN6TP,SA';body 'M24128BWMN6TP';
    'VCC':'(8)';
    'WC#':'(7)';IN;
    'SCL':'(6)';IN;
    'SDA':'(5)';BIDI;
    'VSS':'(4)';
    'E2':'(3)';IN;
    'E1':'(2)';IN;
    'E0':'(1)';IN;
end_primitive;
primitive 'MAX11617EEET-MAX11617EEE+T,SMLA';body 'MAX11617EEET';
    'AIN11||REF':'(1)';BIDI;
    'AIN10':'(2)';BIDI;
    'AIN9':'(3)';BIDI;
    'AIN8':'(4)';BIDI;
    'AIN0':'(5)';BIDI;
    'AIN1':'(6)';BIDI;
    'AIN2':'(7)';BIDI;
    'AIN3':'(8)';BIDI;
    'AIN4':'(9)';BIDI;
    'AIN5':'(10)';BIDI;
    'AIN6':'(11)';BIDI;
    'AIN7':'(12)';BIDI;
    'SCL':'(13)';BIDI;
    'SDA':'(14)';BIDI;
    'GND':'(15)';
    'VDD':'(16)';
end_primitive;
primitive 'MAX15090BEWIT-MAX15090BEWI+T,SA';body 'MAX15090BEWIT';
    'VCC':'(A2)';
    'IN_A3':'(A3)';IN;
    'IN_A5':'(A5)';IN;
    'IN_B3':'(B3)';IN;
    'IN_B5':'(B5)';IN;
    'IN_C3':'(C3)';IN;
    'IN_C5':'(C5)';IN;
    'IN_D5':'(D5)';IN;
    'CB':'(B1)';BIDI;
    'EN#':'(B7)';IN;
    'REG':'(D1)';OUT;
    'UV':'(D2)';IN;
    'OV':'(D3)';IN;
    'ISENSE':'(A1)';OUT;
    'OUT_A4':'(A4)';OUT;
    'OUT_B4':'(B4)';OUT;
    'OUT_B6':'(B6)';OUT;
    'OUT_C4':'(C4)';OUT;
    'OUT_C6':'(C6)';OUT;
    'OUT_D4':'(D4)';OUT;
    'OUT_D6':'(D6)';OUT;
    'GATE':'(A6)';BIDI;
    'CDLY':'(A7)';IN;
    'GND_B2':'(B2)';
    'GND_C1':'(C1)';
    'GND_C2':'(C2)';
    'FAULT#':'(C7)';OUT;
    'PG':'(D7)';OUT;
end_primitive;
primitive 'MAX15090BEWIT-MAX15090BEWI+T,SB';body 'MAX15090BEWIT';
    'VCC':'(A2)';
    'IN_A3':'(A3)';IN;
    'IN_A5':'(A5)';IN;
    'IN_B3':'(B3)';IN;
    'IN_B5':'(B5)';IN;
    'IN_C3':'(C3)';IN;
    'IN_C5':'(C5)';IN;
    'IN_D5':'(D5)';IN;
    'CB':'(B1)';BIDI;
    'EN#':'(B7)';IN;
    'REG':'(D1)';OUT;
    'UV':'(D2)';IN;
    'OV':'(D3)';IN;
    'ISENSE':'(A1)';OUT;
    'OUT_A4':'(A4)';OUT;
    'OUT_B4':'(B4)';OUT;
    'OUT_B6':'(B6)';OUT;
    'OUT_C4':'(C4)';OUT;
    'OUT_C6':'(C6)';OUT;
    'OUT_D4':'(D4)';OUT;
    'OUT_D6':'(D6)';OUT;
    'GATE':'(A6)';BIDI;
    'CDLY':'(A7)';IN;
    'GND_B2':'(B2)';
    'GND_C1':'(C1)';
    'GND_C2':'(C2)';
    'FAULT#':'(C7)';OUT;
    'PG':'(D7)';OUT;
end_primitive;
primitive 'ME_DUMMY_SYMBOL-CBS_3X558-8,MEA';body 'ME_DUMMY_SYMBOL';
end_primitive;
primitive 'ME_DUMMY_SYMBOL-EFI BIOS LABELA';body 'ME_DUMMY_SYMBOL';
end_primitive;
primitive 'ME_DUMMY_SYMBOL-PB-E1_SMALL,MEA';body 'ME_DUMMY_SYMBOL';
end_primitive;
primitive 'ME_DUMMY_SYMBOL-PCB_VENDOR_LOGA';body 'ME_DUMMY_SYMBOL';
end_primitive;
primitive 'ME_DUMMY_SYMBOL-PICKUP_SMDC20,A';body 'ME_DUMMY_SYMBOL';
end_primitive;
primitive 'ME_DUMMY_SYMBOL-QUANTA_LOGO_7XA';body 'ME_DUMMY_SYMBOL';
end_primitive;
primitive 'ME_DUMMY_SYMBOL-SNLABEL_15X5,MA';body 'ME_DUMMY_SYMBOL';
end_primitive;
primitive 'ME_DUMMY_SYMBOL-SNLABEL_27X6,MA';body 'ME_DUMMY_SYMBOL';
end_primitive;
primitive 'ME_DUMMY_SYMBOL-WEEE,MECH,EMPTA';body 'ME_DUMMY_SYMBOL';
end_primitive;
primitive 'MMBT3904_SMLF-MMBT3904    ,EMPA';body 'MMBT3904';
    '1':'(B)';IN;
    '2':'(E)';BIDI;
    '3':'(C)';BIDI;
end_primitive;
primitive 'MOSFET_NCH_1D3S-PSMNR58-30YLH,A';body 'MOSFET_NCH_1D3S';
    '3':'(3)';BIDI;
    '5':'(5)';BIDI;
    '2':'(2)';BIDI;
    '4':'(4)';IN;
    '1':'(1)';BIDI;
end_primitive;
primitive 'MOSFET_NCH_1D3S-PSMNR58-30YLH,B';body 'MOSFET_NCH_1D3S';
    '3':'(3)';BIDI;
    '5':'(5)';BIDI;
    '2':'(2)';BIDI;
    '4':'(4)';IN;
    '1':'(1)';BIDI;
end_primitive;
primitive 'MOSFET_NCH_DUAL-NX6008NBKS,SMLA';body 'MOSFET_NCH_DUAL';
    'S1':'(1,0)';$S;BIDI;
    'G1':'(2,0)';$S;BIDI;
    'D1':'(6,0)';$S;BIDI;
    'D2':'(0,3)';$S;BIDI;
    'G2':'(0,5)';$S;BIDI;
    'S2':'(0,4)';$S;BIDI;
end_primitive;
primitive 'MOSFET_NCH_DUAL-PJT138K,SMLF,EA';body 'MOSFET_NCH_DUAL';
    'S1':'(1,0)';$S;BIDI;
    'G1':'(2,0)';$S;BIDI;
    'D1':'(6,0)';$S;BIDI;
    'D2':'(0,3)';$S;BIDI;
    'G2':'(0,5)';$S;BIDI;
    'S2':'(0,4)';$S;BIDI;
end_primitive;
primitive 'MOSFET_NCH_DUAL-PJT138K,SMLF,IA';body 'MOSFET_NCH_DUAL';
    'S1':'(1,0)';$S;BIDI;
    'G1':'(2,0)';$S;BIDI;
    'D1':'(6,0)';$S;BIDI;
    'D2':'(0,3)';$S;BIDI;
    'G2':'(0,5)';$S;BIDI;
    'S2':'(0,4)';$S;BIDI;
end_primitive;
primitive 'MOSFET_NCH_GDS_ESD_PROTECTED-2A';body 'MOSFET_NCH_GDS_ESD_PROTECTED';
    'D':'(D)';BIDI;
    'G':'(G)';IN;
    'S':'(S)';BIDI;
end_primitive;
primitive 'MOSFET_NCH_GDS_ESD_PROTECTED-2B';body 'MOSFET_NCH_GDS_ESD_PROTECTED';
    'D':'(D)';BIDI;
    'G':'(G)';IN;
    'S':'(S)';BIDI;
end_primitive;
primitive 'MOSFET_N_SMLF-BSS138K,BSS138K,A';body 'MOSFET_N';
    'GATE':'(G)';IN;
    'DRAIN':'(D)';OUT;
    'SOURCE':'(S)';BIDI;
end_primitive;
primitive 'MOSFET_N_SMLF-BSS138K,BSS138K,B';body 'MOSFET_N';
    'GATE':'(G)';IN;
    'DRAIN':'(D)';OUT;
    'SOURCE':'(S)';BIDI;
end_primitive;
primitive 'MP5016GQHLZ-MP5016GQH-L-Z,SMLFA';body 'MP5016GQHLZ';
    'EN':'(9)';IN;
    'MODE':'(5)';IN;
    'ILIMIT':'(4)';OUT;
    'GND':'(3)';
    'VCC':'(1_2)';
    'DV_DT':'(10)';OUT;
    'GATE':'(8)';OUT;
    'SOURCE':'(6_7)';OUT;
end_primitive;
primitive 'MP5990GMA1111Z-MP5990GMA-1111-A';body 'MP5990GMA1111Z';
    'VOUT3':'(29)';OUT;
    'VOUT2':'(28)';OUT;
    'VOUT1':'(27)';OUT;
    'VIN2':'(2)';IN;
    'EN':'(26)';IN;
    'VIN3':'(3)';IN;
    'VIN4':'(4)';IN;
    'GND1':'(18)';
    'SDA':'(12)';BIDI;
    'VIN_UVW#':'(14)';OUT;
    'SCL':'(11)';IN;
    'D_OC':'(37)';OUT;
    'VOUT5':'(31)';OUT;
    'VOUT9':'(35)';OUT;
    'ALT#':'(10)';OUT;
    'GOK':'(39)';BIDI;
    'VIN7':'(7)';IN;
    'VOUT7':'(33)';OUT;
    'MODE':'(41)';IN;
    'VIN8':'(8)';IN;
    'PG||OCW#':'(13)';OUT;
    'VOUT8':'(34)';OUT;
    'ON':'(38)';OUT;
    'VIN5':'(5)';IN;
    'VIN6':'(6)';IN;
    'VTEMP':'(15)';IN;
    'OCREF':'(22)';OUT;
    'SCREF_OCWREF':'(25)';OUT;
    'SS':'(16)';OUT;
    'VOUT6':'(32)';OUT;
    'IMON':'(21)';BIDI;
    'CS':'(20)';OUT;
    'VIN9':'(42)';IN;
    'VOUT10':'(36)';OUT;
    'VOSEN':'(24)';IN;
    'VOUT4':'(30)';OUT;
    'VIN1':'(1)';IN;
    'GND2':'(44)';
    'FLT_TYPE':'(40)';IN;
    'VIN10':'(43)';IN;
    'VINSEN':'(9)';IN;
    'VDD33_1':'(17)';
    'VDD33_2':'(45)';
    'VDD18':'(19)';
    'ADDR':'(23)';IN;
end_primitive;
primitive 'MP5991GLUZ-MP5991GLU-Z,SMLF,ICA';body 'MP5991GLUZ';
    'VIN1':'(9)';IN;
    'VIN2':'(10)';IN;
    'VIN3':'(11)';IN;
    'VIN4':'(12)';IN;
    'VIN5':'(13)';IN;
    'ON':'(4)';IN;
    'OCREF':'(24)';OUT;
    'CS':'(23)';OUT;
    'IMON':'(22)';OUT;
    'VDD33':'(21)';
    'GND':'(20)';
    'SS':'(19)';IN;
    'GOK':'(5)';OUT;
    'VTEMP':'(18)';OUT;
    'VOUT1':'(1)';OUT;
    'VOUT2':'(2)';OUT;
    'VOUT3':'(25)';OUT;
    'VOUT4':'(26)';OUT;
    'D_OC':'(3)';OUT;
    'VIN6':'(14)';IN;
    'VIN7':'(15)';IN;
    'VIN8':'(16)';IN;
    'VIN9':'(33)';IN;
    'VOUT5':'(27)';OUT;
    'VOUT6':'(28)';OUT;
    'VOUT7':'(29)';OUT;
    'VOUT8':'(30)';OUT;
    'VOUT9':'(31)';OUT;
    'VOUT10':'(32)';OUT;
    'MODE':'(8)';IN;
    'SCREF_OCWREF':'(17)';IN;
    'FLT_TYPE':'(6)';IN;
    'NC1':'(7)';OUT;
end_primitive;
primitive 'NB682GDZ-NB682GD-Z,SMLF,IC,AL0A';body 'NB682GDZ';
    'VIN':'(1)';
    'PG':'(13)';OUT;
    'PGND':'(2)';
    'EN':'(5)';IN;
    'BST':'(9)';
    'AGND':'(11)';
    'LP#':'(6)';IN;
    'C1':'(3)';IN;
    'C0':'(4)';IN;
    'MODE':'(7)';IN;
    'VOUT':'(12)';
    'SW':'(8)';
    '3V3':'(10)';
end_primitive;
primitive 'NC7SB3157_SMLF-NC7SB3157P6X,NCA';body 'NC7SB3157';
    'B1':'(1)';BIDI;
    'GND':'(2)';
    'B0':'(3)';BIDI;
    'S':'(6)';IN;
    'VCC':'(5)';
    'A':'(4)';BIDI;
end_primitive;
primitive 'NC7SB3157_SMLF-NC7SB3157P6X,NCB';body 'NC7SB3157';
    'B1':'(1)';BIDI;
    'GND':'(2)';
    'B0':'(3)';BIDI;
    'S':'(6)';IN;
    'VCC':'(5)';
    'A':'(4)';BIDI;
end_primitive;
primitive 'NCT7718W-NCT7718W,SMLF,EMPTY,AA';body 'NCT7718W';
    'VDD':'(1)';
    'D+':'(2)';IN;
    'D-':'(3)';IN;
    'T_CRIT#':'(4)';OUT;
    'GND':'(5)';
    'ALERT#':'(6)';OUT;
    'SDA':'(7)';BIDI;
    'SCL':'(8)';IN;
end_primitive;
primitive 'NX3L2267GM-NX3L2267GM,SMLF,IC,A';body 'NX3L2267GM';
    'VCC':'(10)';
    '2Z':'(6)';BIDI;
    '1Y0':'(1)';BIDI;
    'GND':'(5)';
    '1Y1':'(2)';BIDI;
    '2S':'(7)';IN;
    '2Y1':'(4)';BIDI;
    '1Z':'(9)';BIDI;
    '1S':'(8)';IN;
    '2Y0':'(3)';BIDI;
end_primitive;
primitive 'PCA9306DP1-PCA9306DP1,SMLF,IC,A';body 'PCA9306DP1';
    'VREF1':'(2)';
    'SCL1':'(3)';BIDI;
    'SDA1':'(4)';BIDI;
    'SDA2':'(5)';BIDI;
    'SCL2':'(6)';BIDI;
    'VREF2':'(7)';
    'EN':'(8)';IN;
    'GND':'(1)';
end_primitive;
primitive 'PCA9517AD-PCA9517AD,SMLF,IC,ALA';body 'PCA9517AD';
    'ENABLE':'(5)';BIDI;
    'VCCA':'(1)';
    'VCCB':'(8)';BIDI;
    'SCLA':'(2)';BIDI;
    'SDAA':'(3)';BIDI;
    'SDAB':'(6)';BIDI;
    'SCLB':'(7)';BIDI;
    'GND':'(4)';
end_primitive;
primitive 'PCA9539RPW-PCA9539RPW,SMLF,IC,A';body 'PCA9539RPW';
    'INT':'(1)';BIDI;
    'A1':'(2)';IN;
    'RESET':'(3)';BIDI;
    'IO0_0':'(4)';BIDI;
    'IO0_1':'(5)';BIDI;
    'IO0_2':'(6)';BIDI;
    'IO0_3':'(7)';BIDI;
    'IO0_4':'(8)';BIDI;
    'IO0_5':'(9)';BIDI;
    'IO0_6':'(10)';BIDI;
    'IO0_7':'(11)';BIDI;
    'VSS':'(12)';
    'IO1_0':'(13)';BIDI;
    'IO1_1':'(14)';BIDI;
    'IO1_2':'(15)';BIDI;
    'IO1_3':'(16)';BIDI;
    'IO1_4':'(17)';BIDI;
    'IO1_5':'(18)';BIDI;
    'IO1_6':'(19)';BIDI;
    'IO1_7':'(20)';BIDI;
    'A0':'(21)';IN;
    'SCL':'(22)';BIDI;
    'SDA':'(23)';BIDI;
    'VDD':'(24)';
end_primitive;
primitive 'PCA9545APW-PCA9545APW,SMLF,IC,A';body 'PCA9545APW';
    'A0':'(1)';IN;
    'A1':'(2)';IN;
    'RESET#':'(3)';IN;
    'INT#':'(17)';OUT;
    'SCL':'(18)';IN;
    'SDA':'(19)';BIDI;
    'VSS':'(10)';
    'VDD':'(20)';
    'SD0':'(5)';BIDI;
    'SC0':'(6)';IN;
    'INT0#':'(4)';IN;
    'SD1':'(8)';BIDI;
    'SC1':'(9)';IN;
    'INT1#':'(7)';IN;
    'SD2':'(12)';BIDI;
    'SC2':'(13)';IN;
    'INT2#':'(11)';IN;
    'SD3':'(15)';BIDI;
    'SC3':'(16)';IN;
    'INT3#':'(14)';IN;
end_primitive;
primitive 'PCA9555APW-PCA9555APW,SMLF,IC,A';body 'PCA9555APW';
    'VDD':'(24)';
    'VSS':'(12)';
    'INT#':'(1)';OUT;
    'SDA':'(23)';BIDI;
    'SCL':'(22)';IN;
    'P0_0':'(4)';BIDI;
    'P0_1':'(5)';BIDI;
    'P0_2':'(6)';BIDI;
    'P0_3':'(7)';BIDI;
    'P0_4':'(8)';BIDI;
    'P0_5':'(9)';BIDI;
    'P0_6':'(10)';BIDI;
    'P0_7':'(11)';BIDI;
    'P1_0':'(13)';BIDI;
    'P1_1':'(14)';BIDI;
    'P1_2':'(15)';BIDI;
    'P1_3':'(16)';BIDI;
    'P1_4':'(17)';BIDI;
    'P1_5':'(18)';BIDI;
    'P1_6':'(19)';BIDI;
    'P1_7':'(20)';BIDI;
    'A0':'(21)';IN;
    'A1':'(2)';IN;
    'A2':'(3)';IN;
end_primitive;
primitive 'PCA9617ADP-PCA9617ADP,SMLF,IC,A';body 'PCA9617ADP';
    'EN':'(5)';IN;
    'VCCA':'(1)';
    'VCCB':'(8)';
    'SCLA':'(2)';BIDI;
    'SDAA':'(3)';BIDI;
    'SDAB':'(6)';BIDI;
    'SCLB':'(7)';BIDI;
    'GND':'(4)';
end_primitive;
primitive 'PI3EQX1002EZREX-PI3EQX1002EZREA';body 'PI3EQX1002EZREX';
    'GND_2':'(9)';
    'VDD_2':'(17)';
    'EN':'(4)';IN;
    'VDD_1':'(5)';
    'AON':'(23)';OUT;
    'AOP':'(24)';OUT;
    'GND_6':'(22)';
    'AIN':'(7)';IN;
    'EQA':'(1)';IN;
    'FGA':'(2)';IN;
    'RXDET_EN':'(13)';IN;
    'AIP':'(6)';IN;
    'TH_GND':'(TH)';
    'FGB':'(15)';IN;
    'BIN':'(19)';IN;
    'SWB':'(14)';IN;
    'BIP':'(18)';IN;
    'SWA':'(3)';IN;
    'GND_1':'(8)';
    'EQB':'(16)';IN;
    'GND_3':'(10)';
    'GND_5':'(21)';
    'BON':'(11)';OUT;
    'BOP':'(12)';OUT;
    'GND_4':'(20)';
end_primitive;
primitive 'PI3EQX12902AZLEX-PI3EQX12902AZA';body 'PI3EQX12902AZLEX';
    'VDD1':'(1)';
    'AIP':'(2)';IN;
    'AIN':'(3)';IN;
    'GND1':'(4)';
    'TEST#':'(5)';IN;
    'GND2':'(6)';
    'GND3':'(7)';
    'BON':'(8)';OUT;
    'BOP':'(9)';OUT;
    'VDD2':'(10)';
    'EN#':'(11)';IN;
    'SWB':'(12)';IN;
    'GND4':'(13)';
    'FGB':'(14)';IN;
    'EQB1':'(15)';IN;
    'VDD3':'(16)';
    'BIP':'(17)';IN;
    'BIN':'(18)';IN;
    'GND5':'(19)';
    'EQB0':'(20)';IN;
    'EQA0':'(21)';IN;
    'GND6':'(22)';
    'AON':'(23)';OUT;
    'AOP':'(24)';OUT;
    'VDD4':'(25)';
    'EQA1':'(26)';IN;
    'FGA':'(27)';IN;
    'GND7':'(28)';
    'SWA':'(29)';IN;
    'MODE':'(30)';IN;
    'GND_TH':'(TH)';
end_primitive;
primitive 'PI6CV304LE-PI6CV304LE,SMLF,IC,A';body 'PI6CV304LE';
    'CLK_IN':'(1)';IN;
    'OE':'(2)';IN;
    'Y0':'(3)';OUT;
    'Y1':'(5)';OUT;
    'Y2':'(7)';OUT;
    'Y3':'(8)';OUT;
    'VDD':'(6)';
    'GND':'(4)';
end_primitive;
primitive 'PICOPROBE_BXA-DELTA-L 4.0,SMLFA';body 'PICOPROBE_BXA';
    '2_N':'(2)';
    '3_G':'(3)';
    '1_P':'(1)';
end_primitive;
primitive 'QS3VH257QG8_SMLF-QS3VH257QG8,IA';body 'QS3VH257QG8';
    'S':'(1)';IN;
    'E*':'(15)';IN;
    'YA':'(4)';OUT;
    'I0A':'(2)';IN;
    'I1A':'(3)';IN;
    'I0B':'(5)';IN;
    'I1B':'(6)';IN;
    'YB':'(7)';OUT;
    'I0C':'(11)';IN;
    'I1C':'(10)';IN;
    'YC':'(9)';OUT;
    'YD':'(12)';OUT;
    'I0D':'(14)';IN;
    'I1D':'(13)';IN;
    'GND':'(8)';
    'VCC':'(16)';
end_primitive;
primitive 'Q_CAPP_SMLF-100UF,16V,20%,OSCOA';body 'Q_CAPP';
    'A':'(1)';
    'B':'(2)';
end_primitive;
primitive 'Q_CAPP_SMLF-220UF,6.3V,20%,ALUA';body 'Q_CAPP';
    'A':'(1)';
    'B':'(2)';
end_primitive;
primitive 'Q_CAPP_SMLF-330UF,2.5V,+10/-35A';body 'Q_CAPP';
    'A':'(1)';
    'B':'(2)';
end_primitive;
primitive 'Q_CAPP_SMLF-330UF,2.5V,+10/-35B';body 'Q_CAPP';
    'A':'(1)';
    'B':'(2)';
end_primitive;
primitive 'Q_CAPP_SMLF-330UF,2V,35%,SPCAPA';body 'Q_CAPP';
    'A':'(1)';
    'B':'(2)';
end_primitive;
primitive 'Q_CAPP_THLF-270UF,16V,20%,OSCOA';body 'Q_CAPP';
    'A':'(1)';
    'B':'(2)';
end_primitive;
primitive 'Q_CAPP_THLF-560UF,2.5V,20%,OSCA';body 'Q_CAPP';
    'A':'(1)';
    'B':'(2)';
end_primitive;
primitive 'Q_CAPP_THLF-560UF,6.3V,20%,OSCA';body 'Q_CAPP';
    'A':'(1)';
    'B':'(2)';
end_primitive;
primitive 'Q_CAP_0402-0.01UF,25V,10%,X7R,A';body 'Q_CAP';
    'A':'(1)';
    'B':'(2)';
end_primitive;
primitive 'Q_CAP_0402-0.022UF,16V,10%,X7RA';body 'Q_CAP';
    'A':'(1)';
    'B':'(2)';
end_primitive;
primitive 'Q_CAP_0402-0.068UF,16V,10%,EMPA';body 'Q_CAP';
    'A':'(1)';
    'B':'(2)';
end_primitive;
primitive 'Q_CAP_0402-0.068UF,16V,10%,X7RA';body 'Q_CAP';
    'A':'(1)';
    'B':'(2)';
end_primitive;
primitive 'Q_CAP_0402-0.1UF,25V,10%,EMPTYA';body 'Q_CAP';
    'A':'(1)';
    'B':'(2)';
end_primitive;
primitive 'Q_CAP_0402-0.1UF,25V,10%,X7R,CA';body 'Q_CAP';
    'A':'(1)';
    'B':'(2)';
end_primitive;
primitive 'Q_CAP_0402-0.22UF,16V,10%,X7R,A';body 'Q_CAP';
    'A':'(1)';
    'B':'(2)';
end_primitive;
primitive 'Q_CAP_0402-1000PF,50V,5%,EMPTYA';body 'Q_CAP';
    'A':'(1)';
    'B':'(2)';
end_primitive;
primitive 'Q_CAP_0402-1000PF,50V,5%,X7R,TA';body 'Q_CAP';
    'A':'(1)';
    'B':'(2)';
end_primitive;
primitive 'Q_CAP_0402-100PF,50V,5%,EMPTY,A';body 'Q_CAP';
    'A':'(1)';
    'B':'(2)';
end_primitive;
primitive 'Q_CAP_0402-100PF,50V,5%,NPO,CHA';body 'Q_CAP';
    'A':'(1)';
    'B':'(2)';
end_primitive;
primitive 'Q_CAP_0402-100PF,50V,5%,X7R,CHA';body 'Q_CAP';
    'A':'(1)';
    'B':'(2)';
end_primitive;
primitive 'Q_CAP_0402-18PF,50V,5%,C0G,CH0A';body 'Q_CAP';
    'A':'(1)';
    'B':'(2)';
end_primitive;
primitive 'Q_CAP_0402-1NF,50V,10%,EMPTY,CA';body 'Q_CAP';
    'A':'(1)';
    'B':'(2)';
end_primitive;
primitive 'Q_CAP_0402-1UF,6.3V,10%,EMPTY,A';body 'Q_CAP';
    'A':'(1)';
    'B':'(2)';
end_primitive;
primitive 'Q_CAP_0402-220PF,50V,10%,EMPTYA';body 'Q_CAP';
    'A':'(1)';
    'B':'(2)';
end_primitive;
primitive 'Q_CAP_0402-220PF,50V,10%,X7R,TA';body 'Q_CAP';
    'A':'(1)';
    'B':'(2)';
end_primitive;
primitive 'Q_CAP_0402-27PF  ,50V ,5% ,EMPA';body 'Q_CAP';
    'A':'(1)';
    'B':'(2)';
end_primitive;
primitive 'Q_CAP_0402-3300PF,50V,10%,X7R,A';body 'Q_CAP';
    'A':'(1)';
    'B':'(2)';
end_primitive;
primitive 'Q_CAP_0402-470PF,50V,10%,X7R,TA';body 'Q_CAP';
    'A':'(1)';
    'B':'(2)';
end_primitive;
primitive 'Q_CAP_0402-47PF,50V,5%,NPO,TMPA';body 'Q_CAP';
    'A':'(1)';
    'B':'(2)';
end_primitive;
primitive 'Q_CAP_0402-680PF,50V,10%,X7R,TA';body 'Q_CAP';
    'A':'(1)';
    'B':'(2)';
end_primitive;
primitive 'Q_CAP_0603-1000PF,50V,10%,EMPTA';body 'Q_CAP';
    'A':'(1)';
    'B':'(2)';
end_primitive;
primitive 'Q_CAP_C0201-0.1UF,6.3V,10%,X6SA';body 'Q_CAP';
    'A':'(1)';
    'B':'(2)';
end_primitive;
primitive 'Q_CAP_C0201-0.22UF,6.3V,10%,X6A';body 'Q_CAP';
    'A':'(1)';
    'B':'(2)';
end_primitive;
primitive 'Q_CAP_C0402-0.001UF,50V,10%,X7A';body 'Q_CAP';
    'A':'(1)';
    'B':'(2)';
end_primitive;
primitive 'Q_CAP_C0402-0.01UF,50V,10%,EMPA';body 'Q_CAP';
    'A':'(1)';
    'B':'(2)';
end_primitive;
primitive 'Q_CAP_C0402-0.01UF,50V,10%,X7RA';body 'Q_CAP';
    'A':'(1)';
    'B':'(2)';
end_primitive;
primitive 'Q_CAP_C0402-0.047UF,25V,10%,X7A';body 'Q_CAP';
    'A':'(1)';
    'B':'(2)';
end_primitive;
primitive 'Q_CAP_C0402-0.22UF,25V,10%,X7RA';body 'Q_CAP';
    'A':'(1)';
    'B':'(2)';
end_primitive;
primitive 'Q_CAP_C0402-100NF,50V,10%,EMPTA';body 'Q_CAP';
    'A':'(1)';
    'B':'(2)';
end_primitive;
primitive 'Q_CAP_C0402-100NF,50V,10%,X7R,A';body 'Q_CAP';
    'A':'(1)';
    'B':'(2)';
end_primitive;
primitive 'Q_CAP_C0402-10UF,6.3V,20%,EMPTA';body 'Q_CAP';
    'A':'(1)';
    'B':'(2)';
end_primitive;
primitive 'Q_CAP_C0402-10UF,6.3V,20%,X6S,A';body 'Q_CAP';
    'A':'(1)';
    'B':'(2)';
end_primitive;
primitive 'Q_CAP_C0402-10UF,6.3V,20%,X6S,B';body 'Q_CAP';
    'A':'(1)';
    'B':'(2)';
end_primitive;
primitive 'Q_CAP_C0402-12PF,50V,5%,EMPTY,A';body 'Q_CAP';
    'A':'(1)';
    'B':'(2)';
end_primitive;
primitive 'Q_CAP_C0402-1UF,16V,10%,X6S,CHA';body 'Q_CAP';
    'A':'(1)';
    'B':'(2)';
end_primitive;
primitive 'Q_CAP_C0402-1UF,25V,10%,EMPTY,A';body 'Q_CAP';
    'A':'(1)';
    'B':'(2)';
end_primitive;
primitive 'Q_CAP_C0402-1UF,25V,10%,X6S,CHA';body 'Q_CAP';
    'A':'(1)';
    'B':'(2)';
end_primitive;
primitive 'Q_CAP_C0402-2.2UF,10V,10%,X6S,A';body 'Q_CAP';
    'A':'(1)';
    'B':'(2)';
end_primitive;
primitive 'Q_CAP_C0402-2.2UF,6.3V,20%,X6SA';body 'Q_CAP';
    'A':'(1)';
    'B':'(2)';
end_primitive;
primitive 'Q_CAP_C0402-22UF,4V,20%,X6S,CHA';body 'Q_CAP';
    'A':'(1)';
    'B':'(2)';
end_primitive;
primitive 'Q_CAP_C0402-33NF,25V,10%,EMPTYA';body 'Q_CAP';
    'A':'(1)';
    'B':'(2)';
end_primitive;
primitive 'Q_CAP_C0402-3900PF,50V,10%,EMPA';body 'Q_CAP';
    'A':'(1)';
    'B':'(2)';
end_primitive;
primitive 'Q_CAP_C0402-39PF,50V,5%,EMPTY,A';body 'Q_CAP';
    'A':'(1)';
    'B':'(2)';
end_primitive;
primitive 'Q_CAP_C0402-560PF,50V,10%,X7R,A';body 'Q_CAP';
    'A':'(1)';
    'B':'(2)';
end_primitive;
primitive 'Q_CAP_C0402-6800PF,50V,10%,X7RA';body 'Q_CAP';
    'A':'(1)';
    'B':'(2)';
end_primitive;
primitive 'Q_CAP_C0402-680PF,50V,10%,X7R,A';body 'Q_CAP';
    'A':'(1)';
    'B':'(2)';
end_primitive;
primitive 'Q_CAP_C0402-8.2PF,50V,0.1P,NP0A';body 'Q_CAP';
    'A':'(1)';
    'B':'(2)';
end_primitive;
primitive 'Q_CAP_C0603-10UF,4V,20%,EMPTY,A';body 'Q_CAP';
    'A':'(1)';
    'B':'(2)';
end_primitive;
primitive 'Q_CAP_C0603-10UF,6.3V,20%,X6S,A';body 'Q_CAP';
    'A':'(1)';
    'B':'(2)';
end_primitive;
primitive 'Q_CAP_C0603-2.2UF,16V,10%,X6S,A';body 'Q_CAP';
    'A':'(1)';
    'B':'(2)';
end_primitive;
primitive 'Q_CAP_C0603-2.2UF,16V,20%,X7R,A';body 'Q_CAP';
    'A':'(1)';
    'B':'(2)';
end_primitive;
primitive 'Q_CAP_C0603-22UF,4V,20%,X6S,CHA';body 'Q_CAP';
    'A':'(1)';
    'B':'(2)';
end_primitive;
primitive 'Q_CAP_C0603-22UF,6.3V,20%,X6S,A';body 'Q_CAP';
    'A':'(1)';
    'B':'(2)';
end_primitive;
primitive 'Q_CAP_C0603-4.7UF,16V,10%,X6S,A';body 'Q_CAP';
    'A':'(1)';
    'B':'(2)';
end_primitive;
primitive 'Q_CAP_C0603-47UF,2.5V,20%,X6S,A';body 'Q_CAP';
    'A':'(1)';
    'B':'(2)';
end_primitive;
primitive 'Q_CAP_C0805-10UF,16V,10%,EMPTYA';body 'Q_CAP';
    'A':'(1)';
    'B':'(2)';
end_primitive;
primitive 'Q_CAP_C0805-10UF,16V,10%,EMPTYB';body 'Q_CAP';
    'A':'(1)';
    'B':'(2)';
end_primitive;
primitive 'Q_CAP_C0805-10UF,16V,10%,X6S,CA';body 'Q_CAP';
    'A':'(1)';
    'B':'(2)';
end_primitive;
primitive 'Q_CAP_C0805-10UF,16V,10%,X6S,CB';body 'Q_CAP';
    'A':'(1)';
    'B':'(2)';
end_primitive;
primitive 'Q_CAP_C0805-10UF,16V,10%,X6S,CC';body 'Q_CAP';
    'A':'(1)';
    'B':'(2)';
end_primitive;
primitive 'Q_CAP_C0805-10UF,25V,10%,X6S,CA';body 'Q_CAP';
    'A':'(1)';
    'B':'(2)';
end_primitive;
primitive 'Q_CAP_C0805-22UF,10V,20%,X6S,CA';body 'Q_CAP';
    'A':'(1)';
    'B':'(2)';
end_primitive;
primitive 'Q_CAP_C0805-22UF,16V,20%,X6S,CA';body 'Q_CAP';
    'A':'(1)';
    'B':'(2)';
end_primitive;
primitive 'Q_CAP_C0805-22UF,16V,20%,X6S,CB';body 'Q_CAP';
    'A':'(1)';
    'B':'(2)';
end_primitive;
primitive 'Q_CAP_C0805-22UF,16V,20%,X6S,CC';body 'Q_CAP';
    'A':'(1)';
    'B':'(2)';
end_primitive;
primitive 'Q_CAP_C0805-22UF,4V,20%,X6S,CHA';body 'Q_CAP';
    'A':'(1)';
    'B':'(2)';
end_primitive;
primitive 'Q_CAP_C0805-47UF,4V,20%,X6S,CHA';body 'Q_CAP';
    'A':'(1)';
    'B':'(2)';
end_primitive;
primitive 'Q_CAP_C0805-47UF,6.3V,20%,X6S,A';body 'Q_CAP';
    'A':'(1)';
    'B':'(2)';
end_primitive;
primitive 'Q_CAP_DIFFBUS_C0201-DIFF BUS_0A';body 'Q_CAP_DIFFBUS';
    '1':'(1)';BIDI;
    '2':'(2)';BIDI;
end_primitive;
primitive 'Q_CAP_DIFFBUS_C0402-DIFF BUS_0A';body 'Q_CAP_DIFFBUS';
    '1':'(1)';BIDI;
    '2':'(2)';BIDI;
end_primitive;
primitive 'Q_CRYSTAL_SMLF-32.768KHZ,IC,BGA';body 'Q_CRYSTAL';
    '1':'(1)';BIDI;
    '2':'(2)';BIDI;
end_primitive;
primitive 'Q_DIODE_SMLF-SDMK0340L-7-F,IC,A';body 'Q_DIODE';
    '1':'(1)';BIDI;
    '2':'(2)';BIDI;
end_primitive;
primitive 'Q_FUSE_SMLF-20A/125V,IC,DKK00XA';body 'Q_FUSE';
    '1':'(1)';BIDI;
    '2':'(2)';BIDI;
end_primitive;
primitive 'Q_INDUCTOR4P_14-150NH,SMLF,INDA';body 'Q_INDUCTOR4P_14';
    '2':'(2)';BIDI;
    '3':'(3)';BIDI;
    '4':'(4)';BIDI;
    '1':'(1)';BIDI;
end_primitive;
primitive 'Q_INDUCTOR_SMLF-0.68UH,IND,CV+A';body 'Q_INDUCTOR';
    '2':'(2)';BIDI;
    '1':'(1)';BIDI;
end_primitive;
primitive 'Q_INDUCTOR_SMLF-1.5UH/53A,IND,A';body 'Q_INDUCTOR';
    '2':'(2)';BIDI;
    '1':'(1)';BIDI;
end_primitive;
primitive 'Q_INDUCTOR_SMLF-100NH/16A,IND,A';body 'Q_INDUCTOR';
    '2':'(2)';BIDI;
    '1':'(1)';BIDI;
end_primitive;
primitive 'Q_INDUCTOR_SMLF-120NH/69A,IND,A';body 'Q_INDUCTOR';
    '2':'(2)';BIDI;
    '1':'(1)';BIDI;
end_primitive;
primitive 'Q_INDUCTOR_SMLF-130NH/106A,INDA';body 'Q_INDUCTOR';
    '2':'(2)';BIDI;
    '1':'(1)';BIDI;
end_primitive;
primitive 'Q_INDUCTOR_SMLF-2.2UH,IND,CV-2A';body 'Q_INDUCTOR';
    '2':'(2)';BIDI;
    '1':'(1)';BIDI;
end_primitive;
primitive 'Q_INDUCTOR_SMLF-300NH/33A,IND,A';body 'Q_INDUCTOR';
    '2':'(2)';BIDI;
    '1':'(1)';BIDI;
end_primitive;
primitive 'Q_INDUCTOR_SMLF-4.7UH,IND,CV-4A';body 'Q_INDUCTOR';
    '2':'(2)';BIDI;
    '1':'(1)';BIDI;
end_primitive;
primitive 'Q_INDUCTOR_SMLF-4.7UH,IND,CV-4B';body 'Q_INDUCTOR';
    '2':'(2)';BIDI;
    '1':'(1)';BIDI;
end_primitive;
primitive 'Q_INDUCTOR_SMLF-50NH/148A,IND,A';body 'Q_INDUCTOR';
    '2':'(2)';BIDI;
    '1':'(1)';BIDI;
end_primitive;
primitive 'Q_INDUCTOR_SMLF-BLM15PX121SN1DA';body 'Q_INDUCTOR';
    '2':'(2)';BIDI;
    '1':'(1)';BIDI;
end_primitive;
primitive 'Q_INDUCTOR_SMLF-BLM15PX121SN1DB';body 'Q_INDUCTOR';
    '2':'(2)';BIDI;
    '1':'(1)';BIDI;
end_primitive;
primitive 'Q_INDUCTOR_SMLF-BLM18PG121SN1DA';body 'Q_INDUCTOR';
    '2':'(2)';BIDI;
    '1':'(1)';BIDI;
end_primitive;
primitive 'Q_INDUCTOR_SMLF-BLM18PG300SN1DA';body 'Q_INDUCTOR';
    '2':'(2)';BIDI;
    '1':'(1)';BIDI;
end_primitive;
primitive 'Q_INDUCTOR_SMLF-BLM18PG300SN1DB';body 'Q_INDUCTOR';
    '2':'(2)';BIDI;
    '1':'(1)';BIDI;
end_primitive;
primitive 'Q_INDUCTOR_SMLF-BLM18SG331TN1DA';body 'Q_INDUCTOR';
    '2':'(2)';BIDI;
    '1':'(1)';BIDI;
end_primitive;
primitive 'Q_INDUCTOR_SMLF-BLM18SN220TN1DA';body 'Q_INDUCTOR';
    '2':'(2)';BIDI;
    '1':'(1)';BIDI;
end_primitive;
primitive 'Q_INDUCTOR_SMLF-FCM2012KF-601TA';body 'Q_INDUCTOR';
    '2':'(2)';BIDI;
    '1':'(1)';BIDI;
end_primitive;
primitive 'Q_LED_SMLF-LED_BLUE,LTST-C281TA';body 'Q_LED';
    'A':'(A)';BIDI;
    'C':'(C)';BIDI;
end_primitive;
primitive 'Q_LED_SMLF-LED_YELLOW,LTST-C19A';body 'Q_LED';
    'A':'(A)';BIDI;
    'C':'(C)';BIDI;
end_primitive;
primitive 'Q_OSC4P_SMLF-25MHZ,OSC,BF62500A';body 'Q_OSC4P';
    'OE':'(1)';IN;
    'OUT':'(3)';OUT;
    'GND':'(2)';
    'VDD':'(4)';
end_primitive;
primitive 'Q_OSC4P_SMLF-50MHZ,OSC,BF65000A';body 'Q_OSC4P';
    'OE':'(1)';IN;
    'OUT':'(3)';OUT;
    'GND':'(2)';
    'VDD':'(4)';
end_primitive;
primitive 'Q_RES_0402LF-0,5%,1/16W,CHIP,CA';body 'Q_RES';
    'A':'(1)';
    'B':'(2)';
end_primitive;
primitive 'Q_RES_0402LF-0,5%,1/16W,EMPTY,A';body 'Q_RES';
    'A':'(1)';
    'B':'(2)';
end_primitive;
primitive 'Q_RES_0402LF-1,1%,1/16W,CHIP,CA';body 'Q_RES';
    'A':'(1)';
    'B':'(2)';
end_primitive;
primitive 'Q_RES_0402LF-1,1%,1/16W,EMPTY,A';body 'Q_RES';
    'A':'(1)';
    'B':'(2)';
end_primitive;
primitive 'Q_RES_0402LF-1.21K,1%,1/16W,CHA';body 'Q_RES';
    'A':'(1)';
    'B':'(2)';
end_primitive;
primitive 'Q_RES_0402LF-1.33K,1%,1/16W,EMA';body 'Q_RES';
    'A':'(1)';
    'B':'(2)';
end_primitive;
primitive 'Q_RES_0402LF-1.5K,1%,1/16W,CHIA';body 'Q_RES';
    'A':'(1)';
    'B':'(2)';
end_primitive;
primitive 'Q_RES_0402LF-1.5K,1%,1/16W,EMPA';body 'Q_RES';
    'A':'(1)';
    'B':'(2)';
end_primitive;
primitive 'Q_RES_0402LF-10,1%,1/16W,CHIP,A';body 'Q_RES';
    'A':'(1)';
    'B':'(2)';
end_primitive;
primitive 'Q_RES_0402LF-10,1%,1/16W,EMPTYA';body 'Q_RES';
    'A':'(1)';
    'B':'(2)';
end_primitive;
primitive 'Q_RES_0402LF-10.5K,1%,1/16W,EMA';body 'Q_RES';
    'A':'(1)';
    'B':'(2)';
end_primitive;
primitive 'Q_RES_0402LF-100,1%,1/16W,CHIPA';body 'Q_RES';
    'A':'(1)';
    'B':'(2)';
end_primitive;
primitive 'Q_RES_0402LF-100,1%,1/16W,EMPTA';body 'Q_RES';
    'A':'(1)';
    'B':'(2)';
end_primitive;
primitive 'Q_RES_0402LF-100K,1%,1/16W,CHIA';body 'Q_RES';
    'A':'(1)';
    'B':'(2)';
end_primitive;
primitive 'Q_RES_0402LF-100K,1%,1/16W,EMPA';body 'Q_RES';
    'A':'(1)';
    'B':'(2)';
end_primitive;
primitive 'Q_RES_0402LF-10K,0.1%,1/16W,CHA';body 'Q_RES';
    'A':'(1)';
    'B':'(2)';
end_primitive;
primitive 'Q_RES_0402LF-10K,1%,1/16W,CHIPA';body 'Q_RES';
    'A':'(1)';
    'B':'(2)';
end_primitive;
primitive 'Q_RES_0402LF-10K,1%,1/16W,EMPTA';body 'Q_RES';
    'A':'(1)';
    'B':'(2)';
end_primitive;
primitive 'Q_RES_0402LF-10M,1%,1/16W,CHIPA';body 'Q_RES';
    'A':'(1)';
    'B':'(2)';
end_primitive;
primitive 'Q_RES_0402LF-10M,1%,1/16W,EMPTA';body 'Q_RES';
    'A':'(1)';
    'B':'(2)';
end_primitive;
primitive 'Q_RES_0402LF-11.3K,0.1%,1/16W,A';body 'Q_RES';
    'A':'(1)';
    'B':'(2)';
end_primitive;
primitive 'Q_RES_0402LF-11.8K,0.1%,1/16W,A';body 'Q_RES';
    'A':'(1)';
    'B':'(2)';
end_primitive;
primitive 'Q_RES_0402LF-113,1%,1/16W,CHIPA';body 'Q_RES';
    'A':'(1)';
    'B':'(2)';
end_primitive;
primitive 'Q_RES_0402LF-12.4K,0.1%,1/16W,A';body 'Q_RES';
    'A':'(1)';
    'B':'(2)';
end_primitive;
primitive 'Q_RES_0402LF-120,1%,1/16W,CHIPA';body 'Q_RES';
    'A':'(1)';
    'B':'(2)';
end_primitive;
primitive 'Q_RES_0402LF-120K,1%,1/16W,CHIA';body 'Q_RES';
    'A':'(1)';
    'B':'(2)';
end_primitive;
primitive 'Q_RES_0402LF-127K,1%,1/16W,CHIA';body 'Q_RES';
    'A':'(1)';
    'B':'(2)';
end_primitive;
primitive 'Q_RES_0402LF-12K,1%,1/16W,EMPTA';body 'Q_RES';
    'A':'(1)';
    'B':'(2)';
end_primitive;
primitive 'Q_RES_0402LF-130,1%,1/16W,CHIPA';body 'Q_RES';
    'A':'(1)';
    'B':'(2)';
end_primitive;
primitive 'Q_RES_0402LF-14.3K,1%,1/16W,CHA';body 'Q_RES';
    'A':'(1)';
    'B':'(2)';
end_primitive;
primitive 'Q_RES_0402LF-15.4K,1%,1/16W,CHA';body 'Q_RES';
    'A':'(1)';
    'B':'(2)';
end_primitive;
primitive 'Q_RES_0402LF-150,1%,1/16W,CHIPA';body 'Q_RES';
    'A':'(1)';
    'B':'(2)';
end_primitive;
primitive 'Q_RES_0402LF-150K,1%,1/16W,CHIA';body 'Q_RES';
    'A':'(1)';
    'B':'(2)';
end_primitive;
primitive 'Q_RES_0402LF-15K,0.1%,1/16W,CHA';body 'Q_RES';
    'A':'(1)';
    'B':'(2)';
end_primitive;
primitive 'Q_RES_0402LF-15K,1%,1/16W,CHIPA';body 'Q_RES';
    'A':'(1)';
    'B':'(2)';
end_primitive;
primitive 'Q_RES_0402LF-15K,1%,1/16W,EMPTA';body 'Q_RES';
    'A':'(1)';
    'B':'(2)';
end_primitive;
primitive 'Q_RES_0402LF-16.9K,1%,1/16W,CHA';body 'Q_RES';
    'A':'(1)';
    'B':'(2)';
end_primitive;
primitive 'Q_RES_0402LF-160K,1%,1/16W,EMPA';body 'Q_RES';
    'A':'(1)';
    'B':'(2)';
end_primitive;
primitive 'Q_RES_0402LF-17.4K,1%,1/16W,CHA';body 'Q_RES';
    'A':'(1)';
    'B':'(2)';
end_primitive;
primitive 'Q_RES_0402LF-17.8K,1%,1/16W,EMA';body 'Q_RES';
    'A':'(1)';
    'B':'(2)';
end_primitive;
primitive 'Q_RES_0402LF-18K,1%,1/16W,CHIPA';body 'Q_RES';
    'A':'(1)';
    'B':'(2)';
end_primitive;
primitive 'Q_RES_0402LF-196K,1%,1/16W,CHIA';body 'Q_RES';
    'A':'(1)';
    'B':'(2)';
end_primitive;
primitive 'Q_RES_0402LF-1K,1%,1/16W,CHIP,A';body 'Q_RES';
    'A':'(1)';
    'B':'(2)';
end_primitive;
primitive 'Q_RES_0402LF-1K,1%,1/16W,EMPTYA';body 'Q_RES';
    'A':'(1)';
    'B':'(2)';
end_primitive;
primitive 'Q_RES_0402LF-1M,1%,1/16W,CHIP,A';body 'Q_RES';
    'A':'(1)';
    'B':'(2)';
end_primitive;
primitive 'Q_RES_0402LF-1M,1%,1/16W,EMPTYA';body 'Q_RES';
    'A':'(1)';
    'B':'(2)';
end_primitive;
primitive 'Q_RES_0402LF-2.2,1%,1/16W,CHIPA';body 'Q_RES';
    'A':'(1)';
    'B':'(2)';
end_primitive;
primitive 'Q_RES_0402LF-2.21K,1%,1/16W,EMA';body 'Q_RES';
    'A':'(1)';
    'B':'(2)';
end_primitive;
primitive 'Q_RES_0402LF-2.2K,5%,1/16W,CHIA';body 'Q_RES';
    'A':'(1)';
    'B':'(2)';
end_primitive;
primitive 'Q_RES_0402LF-2.2K,5%,1/16W,EMPA';body 'Q_RES';
    'A':'(1)';
    'B':'(2)';
end_primitive;
primitive 'Q_RES_0402LF-2.49K,1%,1/16W,CHA';body 'Q_RES';
    'A':'(1)';
    'B':'(2)';
end_primitive;
primitive 'Q_RES_0402LF-2.67K,1%,1/16W,EMA';body 'Q_RES';
    'A':'(1)';
    'B':'(2)';
end_primitive;
primitive 'Q_RES_0402LF-2.8K,1%,1/16W,EMPA';body 'Q_RES';
    'A':'(1)';
    'B':'(2)';
end_primitive;
primitive 'Q_RES_0402LF-200,1%,1/16W,CHIPA';body 'Q_RES';
    'A':'(1)';
    'B':'(2)';
end_primitive;
primitive 'Q_RES_0402LF-200,1%,1/16W,EMPTA';body 'Q_RES';
    'A':'(1)';
    'B':'(2)';
end_primitive;
primitive 'Q_RES_0402LF-200K,1%,1/16W,CHIA';body 'Q_RES';
    'A':'(1)';
    'B':'(2)';
end_primitive;
primitive 'Q_RES_0402LF-200K,1%,1/16W,EMPA';body 'Q_RES';
    'A':'(1)';
    'B':'(2)';
end_primitive;
primitive 'Q_RES_0402LF-20K,1%,1/16W,CHIPA';body 'Q_RES';
    'A':'(1)';
    'B':'(2)';
end_primitive;
primitive 'Q_RES_0402LF-20K,1%,1/16W,EMPTA';body 'Q_RES';
    'A':'(1)';
    'B':'(2)';
end_primitive;
primitive 'Q_RES_0402LF-21.5K,1%,1/16W,CHA';body 'Q_RES';
    'A':'(1)';
    'B':'(2)';
end_primitive;
primitive 'Q_RES_0402LF-22,1%,1/16W,CHIP,A';body 'Q_RES';
    'A':'(1)';
    'B':'(2)';
end_primitive;
primitive 'Q_RES_0402LF-22,1%,1/16W,EMPTYA';body 'Q_RES';
    'A':'(1)';
    'B':'(2)';
end_primitive;
primitive 'Q_RES_0402LF-22,5%,1/16W,CHIP,A';body 'Q_RES';
    'A':'(1)';
    'B':'(2)';
end_primitive;
primitive 'Q_RES_0402LF-22.6K,1%,1/16W,CHA';body 'Q_RES';
    'A':'(1)';
    'B':'(2)';
end_primitive;
primitive 'Q_RES_0402LF-23.2K,1%,1/16W,CHA';body 'Q_RES';
    'A':'(1)';
    'B':'(2)';
end_primitive;
primitive 'Q_RES_0402LF-24.3K,1%,1/16W,CHA';body 'Q_RES';
    'A':'(1)';
    'B':'(2)';
end_primitive;
primitive 'Q_RES_0402LF-240,1%,1/16W,CHIPA';body 'Q_RES';
    'A':'(1)';
    'B':'(2)';
end_primitive;
primitive 'Q_RES_0402LF-240,1%,1/16W,EMPTA';body 'Q_RES';
    'A':'(1)';
    'B':'(2)';
end_primitive;
primitive 'Q_RES_0402LF-249,1%,1/16W,CHIPA';body 'Q_RES';
    'A':'(1)';
    'B':'(2)';
end_primitive;
primitive 'Q_RES_0402LF-25.5K,1%,1/16W,CHA';body 'Q_RES';
    'A':'(1)';
    'B':'(2)';
end_primitive;
primitive 'Q_RES_0402LF-26.1K,0.1%,1/16W,A';body 'Q_RES';
    'A':'(1)';
    'B':'(2)';
end_primitive;
primitive 'Q_RES_0402LF-26.7K,1%,1/16W,CHA';body 'Q_RES';
    'A':'(1)';
    'B':'(2)';
end_primitive;
primitive 'Q_RES_0402LF-27.4,1%,1/16W,CHIA';body 'Q_RES';
    'A':'(1)';
    'B':'(2)';
end_primitive;
primitive 'Q_RES_0402LF-28K,1%,1/16W,EMPTA';body 'Q_RES';
    'A':'(1)';
    'B':'(2)';
end_primitive;
primitive 'Q_RES_0402LF-2K,0.1%,1/16W,CHIA';body 'Q_RES';
    'A':'(1)';
    'B':'(2)';
end_primitive;
primitive 'Q_RES_0402LF-2K,1%,1/16W,CHIP,A';body 'Q_RES';
    'A':'(1)';
    'B':'(2)';
end_primitive;
primitive 'Q_RES_0402LF-2K,1%,1/16W,EMPTYA';body 'Q_RES';
    'A':'(1)';
    'B':'(2)';
end_primitive;
primitive 'Q_RES_0402LF-3.3,1%,1/16W,CHIPA';body 'Q_RES';
    'A':'(1)';
    'B':'(2)';
end_primitive;
primitive 'Q_RES_0402LF-3.57K,1%,1/16W,CHA';body 'Q_RES';
    'A':'(1)';
    'B':'(2)';
end_primitive;
primitive 'Q_RES_0402LF-3.9K,5%,1/16W,EMPA';body 'Q_RES';
    'A':'(1)';
    'B':'(2)';
end_primitive;
primitive 'Q_RES_0402LF-30.1K,1%,1/16W,CHA';body 'Q_RES';
    'A':'(1)';
    'B':'(2)';
end_primitive;
primitive 'Q_RES_0402LF-30.1K,1%,1/16W,EMA';body 'Q_RES';
    'A':'(1)';
    'B':'(2)';
end_primitive;
primitive 'Q_RES_0402LF-301,1%,1/16W,CHIPA';body 'Q_RES';
    'A':'(1)';
    'B':'(2)';
end_primitive;
primitive 'Q_RES_0402LF-31.6K,1%,1/16W,CHA';body 'Q_RES';
    'A':'(1)';
    'B':'(2)';
end_primitive;
primitive 'Q_RES_0402LF-33.2,1%,1/16W,CHIA';body 'Q_RES';
    'A':'(1)';
    'B':'(2)';
end_primitive;
primitive 'Q_RES_0402LF-33.2,1%,1/16W,EMPA';body 'Q_RES';
    'A':'(1)';
    'B':'(2)';
end_primitive;
primitive 'Q_RES_0402LF-33K,1%,1/16W,CHIPA';body 'Q_RES';
    'A':'(1)';
    'B':'(2)';
end_primitive;
primitive 'Q_RES_0402LF-34.8K,1%,1/16W,CHA';body 'Q_RES';
    'A':'(1)';
    'B':'(2)';
end_primitive;
primitive 'Q_RES_0402LF-35.7K,1%,1/16W,CHA';body 'Q_RES';
    'A':'(1)';
    'B':'(2)';
end_primitive;
primitive 'Q_RES_0402LF-38.3K,0.1%,1/16W,A';body 'Q_RES';
    'A':'(1)';
    'B':'(2)';
end_primitive;
primitive 'Q_RES_0402LF-4.32K,1%,1/16W,CHA';body 'Q_RES';
    'A':'(1)';
    'B':'(2)';
end_primitive;
primitive 'Q_RES_0402LF-4.53K,1%,1/16W,CHA';body 'Q_RES';
    'A':'(1)';
    'B':'(2)';
end_primitive;
primitive 'Q_RES_0402LF-4.75K,1%,1/16W,CHA';body 'Q_RES';
    'A':'(1)';
    'B':'(2)';
end_primitive;
primitive 'Q_RES_0402LF-4.75K,1%,1/16W,EMA';body 'Q_RES';
    'A':'(1)';
    'B':'(2)';
end_primitive;
primitive 'Q_RES_0402LF-4.7K,1%,1/16W,CHIA';body 'Q_RES';
    'A':'(1)';
    'B':'(2)';
end_primitive;
primitive 'Q_RES_0402LF-4.7K,1%,1/16W,EMPA';body 'Q_RES';
    'A':'(1)';
    'B':'(2)';
end_primitive;
primitive 'Q_RES_0402LF-4.7K,5%,1/16W,CHIA';body 'Q_RES';
    'A':'(1)';
    'B':'(2)';
end_primitive;
primitive 'Q_RES_0402LF-4.7K,5%,1/16W,EMPA';body 'Q_RES';
    'A':'(1)';
    'B':'(2)';
end_primitive;
primitive 'Q_RES_0402LF-4.99K,0.1%,1/16W,A';body 'Q_RES';
    'A':'(1)';
    'B':'(2)';
end_primitive;
primitive 'Q_RES_0402LF-4.99K,1%,1/16W,EMA';body 'Q_RES';
    'A':'(1)';
    'B':'(2)';
end_primitive;
primitive 'Q_RES_0402LF-46.4K,1%,1/16W,CHA';body 'Q_RES';
    'A':'(1)';
    'B':'(2)';
end_primitive;
primitive 'Q_RES_0402LF-470,1%,1/16W,CHIPA';body 'Q_RES';
    'A':'(1)';
    'B':'(2)';
end_primitive;
primitive 'Q_RES_0402LF-47K,0.1%,1/16W,CHA';body 'Q_RES';
    'A':'(1)';
    'B':'(2)';
end_primitive;
primitive 'Q_RES_0402LF-47K,0.1%,1/16W,EMA';body 'Q_RES';
    'A':'(1)';
    'B':'(2)';
end_primitive;
primitive 'Q_RES_0402LF-49.9,1%,1/16W,CHIA';body 'Q_RES';
    'A':'(1)';
    'B':'(2)';
end_primitive;
primitive 'Q_RES_0402LF-49.9,1%,1/16W,EMPA';body 'Q_RES';
    'A':'(1)';
    'B':'(2)';
end_primitive;
primitive 'Q_RES_0402LF-499,1%,1/16W,CHIPA';body 'Q_RES';
    'A':'(1)';
    'B':'(2)';
end_primitive;
primitive 'Q_RES_0402LF-5.1,5%,1/16W,CHIPA';body 'Q_RES';
    'A':'(1)';
    'B':'(2)';
end_primitive;
primitive 'Q_RES_0402LF-5.11K,1%,1/16W,CHA';body 'Q_RES';
    'A':'(1)';
    'B':'(2)';
end_primitive;
primitive 'Q_RES_0402LF-5.11K,1%,1/16W,EMA';body 'Q_RES';
    'A':'(1)';
    'B':'(2)';
end_primitive;
primitive 'Q_RES_0402LF-5.23K,1%,1/16W,CHA';body 'Q_RES';
    'A':'(1)';
    'B':'(2)';
end_primitive;
primitive 'Q_RES_0402LF-5.36K,1%,1/16W,CHA';body 'Q_RES';
    'A':'(1)';
    'B':'(2)';
end_primitive;
primitive 'Q_RES_0402LF-510K,5%,1/16W,EMPA';body 'Q_RES';
    'A':'(1)';
    'B':'(2)';
end_primitive;
primitive 'Q_RES_0402LF-54.9K,1%,1/16W,CHA';body 'Q_RES';
    'A':'(1)';
    'B':'(2)';
end_primitive;
primitive 'Q_RES_0402LF-54.9K,1%,1/16W,EMA';body 'Q_RES';
    'A':'(1)';
    'B':'(2)';
end_primitive;
primitive 'Q_RES_0402LF-560,1%,1/16W,CHIPA';body 'Q_RES';
    'A':'(1)';
    'B':'(2)';
end_primitive;
primitive 'Q_RES_0402LF-56K,1%,1/16W,CHIPA';body 'Q_RES';
    'A':'(1)';
    'B':'(2)';
end_primitive;
primitive 'Q_RES_0402LF-6.19K,1%,1/16W,CHA';body 'Q_RES';
    'A':'(1)';
    'B':'(2)';
end_primitive;
primitive 'Q_RES_0402LF-6.8K,1%,1/16W,EMPA';body 'Q_RES';
    'A':'(1)';
    'B':'(2)';
end_primitive;
primitive 'Q_RES_0402LF-60.4,1%,1/16W,CHIA';body 'Q_RES';
    'A':'(1)';
    'B':'(2)';
end_primitive;
primitive 'Q_RES_0402LF-60.4K,1%,1/16W,CHA';body 'Q_RES';
    'A':'(1)';
    'B':'(2)';
end_primitive;
primitive 'Q_RES_0402LF-63.4K,1%,1/16W,CHA';body 'Q_RES';
    'A':'(1)';
    'B':'(2)';
end_primitive;
primitive 'Q_RES_0402LF-680,1%,1/16W,CHIPA';body 'Q_RES';
    'A':'(1)';
    'B':'(2)';
end_primitive;
primitive 'Q_RES_0402LF-680,1%,1/16W,EMPTA';body 'Q_RES';
    'A':'(1)';
    'B':'(2)';
end_primitive;
primitive 'Q_RES_0402LF-681,1%,1/16W,CHIPA';body 'Q_RES';
    'A':'(1)';
    'B':'(2)';
end_primitive;
primitive 'Q_RES_0402LF-68K,1%,1/16W,CHIPA';body 'Q_RES';
    'A':'(1)';
    'B':'(2)';
end_primitive;
primitive 'Q_RES_0402LF-68K,1%,1/16W,EMPTA';body 'Q_RES';
    'A':'(1)';
    'B':'(2)';
end_primitive;
primitive 'Q_RES_0402LF-7.15K,1%,1/16W,CHA';body 'Q_RES';
    'A':'(1)';
    'B':'(2)';
end_primitive;
primitive 'Q_RES_0402LF-7.32K,0.1%,1/16W,A';body 'Q_RES';
    'A':'(1)';
    'B':'(2)';
end_primitive;
primitive 'Q_RES_0402LF-7.87K,1%,1/16W,CHA';body 'Q_RES';
    'A':'(1)';
    'B':'(2)';
end_primitive;
primitive 'Q_RES_0402LF-71.5K,1%,1/16W,EMA';body 'Q_RES';
    'A':'(1)';
    'B':'(2)';
end_primitive;
primitive 'Q_RES_0402LF-75,1%,1/16W,CHIP,A';body 'Q_RES';
    'A':'(1)';
    'B':'(2)';
end_primitive;
primitive 'Q_RES_0402LF-75,1%,1/16W,EMPTYA';body 'Q_RES';
    'A':'(1)';
    'B':'(2)';
end_primitive;
primitive 'Q_RES_0402LF-75K,0.1%,1/16W,CHA';body 'Q_RES';
    'A':'(1)';
    'B':'(2)';
end_primitive;
primitive 'Q_RES_0402LF-8.25K,0.1%,1/16W,A';body 'Q_RES';
    'A':'(1)';
    'B':'(2)';
end_primitive;
primitive 'Q_RES_0402LF-8.45K,1%,1/16W,CHA';body 'Q_RES';
    'A':'(1)';
    'B':'(2)';
end_primitive;
primitive 'Q_RES_0402LF-8.45K,1%,1/16W,EMA';body 'Q_RES';
    'A':'(1)';
    'B':'(2)';
end_primitive;
primitive 'Q_RES_0402LF-8.87K,1%,1/16W,EMA';body 'Q_RES';
    'A':'(1)';
    'B':'(2)';
end_primitive;
primitive 'Q_RES_0402LF-82K,1%,1/16W,CHIPA';body 'Q_RES';
    'A':'(1)';
    'B':'(2)';
end_primitive;
primitive 'Q_RES_0402LF-84.5K,1%,1/16W,CHA';body 'Q_RES';
    'A':'(1)';
    'B':'(2)';
end_primitive;
primitive 'Q_RES_0402LF-845,1%,1/16W,EMPTA';body 'Q_RES';
    'A':'(1)';
    'B':'(2)';
end_primitive;
primitive 'Q_RES_0402LF-86.6K,1%,1/16W,EMA';body 'Q_RES';
    'A':'(1)';
    'B':'(2)';
end_primitive;
primitive 'Q_RES_0402LF-88.7K,1%,1/16W,CHA';body 'Q_RES';
    'A':'(1)';
    'B':'(2)';
end_primitive;
primitive 'Q_RES_0402LF-9.09K,1%,1/16W,CHA';body 'Q_RES';
    'A':'(1)';
    'B':'(2)';
end_primitive;
primitive 'Q_RES_0402LF-9.31K,1%,1/16W,EMA';body 'Q_RES';
    'A':'(1)';
    'B':'(2)';
end_primitive;
primitive 'Q_RES_0402LF-9.76K,1%,1/16W,CHA';body 'Q_RES';
    'A':'(1)';
    'B':'(2)';
end_primitive;
primitive 'Q_RES_0603LF-1,1%,1/10W,CHIP,CA';body 'Q_RES';
    'A':'(1)';
    'B':'(2)';
end_primitive;
primitive 'Q_RES_0603LF-10M,1%,1/10W,CHIPA';body 'Q_RES';
    'A':'(1)';
    'B':'(2)';
end_primitive;
primitive 'Q_RES_0603LF-2.2,1%,1/10W,CHIPA';body 'Q_RES';
    'A':'(1)';
    'B':'(2)';
end_primitive;
primitive 'Q_RES_0603LF-200K,0.1%,1/10W,EA';body 'Q_RES';
    'A':'(1)';
    'B':'(2)';
end_primitive;
primitive 'Q_RES_0603LF-49.9,1%,1/10W,CHIA';body 'Q_RES';
    'A':'(1)';
    'B':'(2)';
end_primitive;
primitive 'Q_RES_0805LF-0,5%,1/8W,CHIP,CSA';body 'Q_RES';
    'A':'(1)';
    'B':'(2)';
end_primitive;
primitive 'Q_RES_0805LF-0,5%,1/8W,EMPTY,CA';body 'Q_RES';
    'A':'(1)';
    'B':'(2)';
end_primitive;
primitive 'Q_RES_1206LF-0,,1/2W,CHIP,CS00A';body 'Q_RES';
    'A':'(1)';
    'B':'(2)';
end_primitive;
primitive 'Q_RES_1206LF-0,,1/2W,EMPTY,CS0A';body 'Q_RES';
    'A':'(1)';
    'B':'(2)';
end_primitive;
primitive 'Q_RES_1206LF-243,1%,1/4W,CHIP,A';body 'Q_RES';
    'A':'(1)';
    'B':'(2)';
end_primitive;
primitive 'Q_RES_2512LF-0.01,1%,1W,CHIP,CA';body 'Q_RES';
    'A':'(1)';
    'B':'(2)';
end_primitive;
primitive 'Q_RES_2512LF-0.03,0.1%,1W,EMPTA';body 'Q_RES';
    'A':'(1)';
    'B':'(2)';
end_primitive;
primitive 'Q_RES_4P_12-0.001,1%,3W,SMLF,CA';body 'Q_RES_4P_12';
    '1':'(1)';
    '2':'(2)';
    '3':'(3)';
    '4':'(4)';
end_primitive;
primitive 'Q_RES_4P_12-0.003,1%,3W,SMLF,EA';body 'Q_RES_4P_12';
    '1':'(1)';
    '2':'(2)';
    '3':'(3)';
    '4':'(4)';
end_primitive;
primitive 'Q_SHORT_SM-EMPTY,SHORT6';body 'Q_SHORT';
    '1':'(1)';BIDI;
    '2':'(2)';BIDI;
end_primitive;
primitive 'Q_SP_RES4P-0.0003,1%,4W,SMLF,EA';body 'Q_SP_RES4P';
    '2B':'(2B)';BIDI;
    '1B':'(1B)';BIDI;
    '2A':'(2A)';BIDI;
    '1A':'(1A)';BIDI;
end_primitive;
primitive 'Q_XTAL_4P_13BI_24GND-12MHZ,SMLA';body 'Q_XTAL_4P_13BI_24GND';
    'X1':'(1)';BIDI;
    'G1':'(2)';
    'G2':'(4)';
    'X2':'(3)';BIDI;
end_primitive;
primitive 'Q_XTAL_4P_13BI_24GND-12MHZ,SMLB';body 'Q_XTAL_4P_13BI_24GND';
    'X1':'(1)';BIDI;
    'G1':'(2)';
    'G2':'(4)';
    'X2':'(3)';BIDI;
end_primitive;
primitive 'Q_XTAL_4P_13BI_24GND-25MHZ,SMLA';body 'Q_XTAL_4P_13BI_24GND';
    'X1':'(1)';BIDI;
    'G1':'(2)';
    'G2':'(4)';
    'X2':'(3)';BIDI;
end_primitive;
primitive 'Q_XTAL_4P_13BI_24GND-25MHZ,SMLB';body 'Q_XTAL_4P_13BI_24GND';
    'X1':'(1)';BIDI;
    'G1':'(2)';
    'G2':'(4)';
    'X2':'(3)';BIDI;
end_primitive;
primitive 'RAA2213404GNPHB0-RAA2213404GNPA';body 'RAA2213404GNPHB0';
    'PWM':'(21)';IN;
    'REFIN':'(24)';IN;
    'GND2':'(23)';
    'BOOT':'(20)';
    'VIN':'(16_18-28)';
    'PHASE':'(19)';
    'VCC':'(4)';
    'TMON':'(1)';OUT;
    'IMON':'(25)';OUT;
    'GND1':'(6_7-13_15-29)';
    'GL2':'(27)';OUT;
    'SW':'(8_12)';OUT;
    'FAULT#':'(2)';OUT;
    'GND3':'(26)';
    'NC1':'(22)';OUT;
    'GL1':'(5)';OUT;
    'LGCTRL':'(3)';IN;
end_primitive;
primitive 'RAA229126GNPHA0-RAA229126GNP#HA';body 'RAA229126GNPHA0';
    'CS11':'(27)';IN;
    'VCC':'(47)';
    'EN1':'(24)';IN;
    'PMSCL':'(14)';IN;
    'SVDATA':'(22)';BIDI;
    'CS6':'(32)';IN;
    'NSVALERT':'(23)';OUT;
    'NVRHOT':'(18)';OUT;
    'CS5':'(33)';IN;
    'CS4':'(34)';IN;
    'PG1':'(20)';OUT;
    'SVCLK':'(21)';IN;
    'NPMALERT':'(15)';OUT;
    'EN0':'(17)';IN;
    'RGND0':'(26)';IN;
    'PMSDA':'(13)';BIDI;
    'PWM4':'(5)';OUT;
    'PWM5':'(6)';OUT;
    'VSEN0':'(25)';IN;
    'PWM1':'(2)';OUT;
    'PG0':'(16)';OUT;
    'PWM6':'(7)';OUT;
    'VCCS':'(48)';
    'VMON||IINSEN||VSYS||ISYS':'(45)';IN;
    'VINSEN||VSYS':'(46)';IN;
    'TEMP1||ISYS':'(44)';IN;
    'NPINALERT||NPSYS_CRIT':'(19)';OUT;
    'VSEN1':'(40)';IN;
    'RGND1':'(39)';IN;
    'CS1':'(37)';IN;
    'PWM11':'(12)';OUT;
    'PWM3':'(4)';OUT;
    'CS3':'(35)';IN;
    'PWM2':'(3)';OUT;
    'CS2':'(36)';IN;
    'CFP':'(41)';OUT;
    'TH_GND':'(TH)';
    'ADDR_CFG':'(42)';IN;
    'TEMP0':'(43)';IN;
    'PWM0':'(1)';OUT;
    'CS0':'(38)';IN;
    'PWM7':'(8)';OUT;
    'CS7':'(31)';IN;
    'PWM8':'(9)';OUT;
    'CS8':'(30)';IN;
    'PWM9':'(10)';OUT;
    'CS9':'(29)';IN;
    'PWM10':'(11)';OUT;
    'CS10':'(28)';IN;
end_primitive;
primitive 'RS31312R-RS31312R,SMLF,IC,AL03A';body 'RS31312R';
    'VOUT_20':'(20)';OUT;
    'VIN_21_22':'(21_22)';IN;
    'VOUT_19':'(19)';OUT;
    'VOUT_18':'(18)';OUT;
    'VOUT_17':'(17)';OUT;
    'VOUT_16':'(16)';OUT;
    'VOUT_15':'(15)';OUT;
    'VOUT_14':'(14)';OUT;
    'AVIN':'(12)';IN;
    'VOUT_13':'(13)';OUT;
    'OV':'(11)';IN;
    'PG':'(10)';OUT;
    'FLTB':'(9)';OUT;
    'IMON':'(8)';OUT;
    'VIN_23':'(23)';IN;
    'VIN_24':'(24)';IN;
    'VIN_25':'(25)';IN;
    'VIN_26':'(26)';IN;
    'EN':'(1)';IN;
    'LOADEN':'(2)';IN;
    'ENTM':'(3)';IN;
    'TIMER':'(4)';IN;
    'ISET':'(5)';IN;
    'SS':'(6)';IN;
    'GND':'(7)';
end_primitive;
primitive 'RS53317LR-RS53317LR,SMLF,IC,ALA';body 'RS53317LR';
    'VIN':'(3)';IN;
    'PGOOD':'(9)';OUT;
    'PGND2':'(14)';
    'EN':'(5)';IN;
    'BST':'(10)';BIDI;
    'FB':'(6)';IN;
    'AGND':'(7)';
    'VCC':'(13)';
    'PGND1':'(1)';
    'SW2':'(11)';OUT;
    'REF':'(8)';BIDI;
    'MODE':'(12)';IN;
    'CS':'(4)';BIDI;
    'SW1':'(2)';OUT;
end_primitive;
primitive 'RS53318LR-RS53318LR,SMLF,IC,ALA';body 'RS53318LR';
    'VIN1':'(10)';
    'PGOOD':'(9)';OUT;
    'PGND':'(11_18)';
    'EN':'(8)';IN;
    'BST':'(1)';IN;
    'FB':'(7)';IN;
    'AGND':'(2)';
    'VCC':'(19)';
    'RTN':'(6)';
    'SW':'(20)';OUT;
    'REF':'(5)';IN;
    'MODE':'(4)';IN;
    'CS':'(3)';IN;
    'VIN2':'(21)';
end_primitive;
primitive 'RS53319LR-RS53319LR,SMLF,IC,ALA';body 'RS53319LR';
    'VIN1':'(10)';
    'PGOOD':'(9)';OUT;
    'PGND':'(11_18)';
    'EN':'(8)';IN;
    'BST':'(1)';IN;
    'FB':'(7)';IN;
    'AGND':'(2)';
    'VCC':'(19)';
    'RTN':'(6)';
    'SW':'(20)';OUT;
    'REF':'(5)';IN;
    'MODE':'(4)';IN;
    'CS':'(3)';IN;
    'VIN2':'(21)';
end_primitive;
primitive 'RT9818C44GV-RT9818C-44GV,SMLF,A';body 'RT9818C44GV';
    'VDD':'(3)';
    'RESET#':'(1)';OUT;
    'GND':'(2)';
end_primitive;
primitive 'SCHOTTKY_12-1N5819HW,SMLF,IC,BA';body 'SCHOTTKY_12';
    'A':'(1)';IN;
    'C':'(2)';BIDI;
end_primitive;
primitive 'SCHOTTKY_12-B0530WS7F,SMLF,IC,A';body 'SCHOTTKY_12';
    'A':'(1)';IN;
    'C':'(2)';BIDI;
end_primitive;
primitive 'SCHOTTKY_AC-B340A-13-F,SMLF,ICA';body 'SCHOTTKY_AC';
    'A':'(A)';IN;
    'C':'(C)';BIDI;
end_primitive;
primitive 'SCONN168_ME1016810202011-SCONNA';body 'SCONN168_ME1016810202011';
    'NIC_PWR_GOOD':'(OB1)';IN;
    'MAIN_PWR_EN':'(OB2)';OUT;
    'LD#':'(OB3)';OUT;
    'DATA_IN':'(OB4)';IN;
    'DATA_OUT':'(OB5)';OUT;
    'CLK':'(OB6)';OUT;
    'SLOT_ID0':'(OB7)';OUT;
    'RBT_RXD1':'(OB8)';IN;
    'RBT_RXD0':'(OB9)';IN;
    'GND_OB10':'(OB10)';
    'REFCLKN2':'(OB11)';OUT;
    'REFCLKP2':'(OB12)';OUT;
    'GND_OB13':'(OB13)';
    'RBT_CRS_DV':'(OB14)';OUT;
    '+12V_EDGE_B1':'(B1)';
    '+12V_EDGE_B2':'(B2)';
    '+12V_EDGE_B3':'(B3)';
    '+12V_EDGE_B4':'(B4)';
    '+12V_EDGE_B5':'(B5)';
    '+12V_EDGE_B6':'(B6)';
    'BIF0#':'(B7)';OUT;
    'BIF1#':'(B8)';OUT;
    'BIF2#':'(B9)';OUT;
    'PERST0#':'(B10)';OUT;
    '+3.3V_EDGE':'(B11)';
    'AUX_PWR_EN':'(B12)';OUT;
    'GND_B13':'(B13)';
    'REFCLKN0':'(B14)';IN;
    'REFCLKP0':'(B15)';OUT;
    'GND_B16':'(B16)';
    'PETN0':'(B17)';OUT;
    'PETP0':'(B18)';OUT;
    'GND_B19':'(B19)';
    'PETN1':'(B20)';OUT;
    'PETP1':'(B21)';OUT;
    'GND_B22':'(B22)';
    'PETN2':'(B23)';OUT;
    'PETP2':'(B24)';OUT;
    'GND_B25':'(B25)';
    'PETN3':'(B26)';OUT;
    'PETP3':'(B27)';OUT;
    'GND_B28':'(B28)';
    'GND_B29':'(B29)';
    'PETN4':'(B30)';OUT;
    'PETP4':'(B31)';OUT;
    'GND_B32':'(B32)';
    'PETN5':'(B33)';OUT;
    'PETP5':'(B34)';OUT;
    'GND_B35':'(B35)';
    'PETN6':'(B36)';OUT;
    'PETP6':'(B37)';OUT;
    'GND_B38':'(B38)';
    'PETN7':'(B39)';OUT;
    'PETP7':'(B40)';OUT;
    'GND_B41':'(B41)';
    'PRSNTB0#':'(B42)';IN;
    'GND_B43':'(B43)';
    'PETN8':'(B44)';OUT;
    'PETP8':'(B45)';OUT;
    'GND_B46':'(B46)';
    'PETN9':'(B47)';OUT;
    'PETP9':'(B48)';OUT;
    'GND_B49':'(B49)';
    'PETN10':'(B50)';OUT;
    'PETP10':'(B51)';OUT;
    'GND_B52':'(B52)';
    'PETN11':'(B53)';OUT;
    'PETP11':'(B54)';OUT;
    'GND_B55':'(B55)';
    'PETN12':'(B56)';OUT;
    'PERST2#':'(OA1)';OUT;
    'PERST3#':'(OA2)';OUT;
    'WAKE#':'(OA3)';IN;
    'RBT_ARB_IN':'(OA4)';IN;
    'RBT_ARB_OUT':'(OA5)';OUT;
    'SLOT_ID1':'(OA6)';OUT;
    'RBT_TX_EN':'(OA7)';OUT;
    'RBT_TXD1':'(OA8)';OUT;
    'RBT_TXD0':'(OA9)';OUT;
    'GND_OA10':'(OA10)';
    'REFCLKN3':'(OA11)';OUT;
    'REFCLKP3':'(OA12)';OUT;
    'GND_OA13':'(OA13)';
    'RBT_CLK_IN':'(OA14)';OUT;
    'GND_A1':'(A1)';
    'GND_A2':'(A2)';
    'GND_A3':'(A3)';
    'GND_A4':'(A4)';
    'GND_A5':'(A5)';
    'GND_A6':'(A6)';
    'SMCLK':'(A7)';OUT;
    'SMDAT':'(A8)';BIDI;
    'SMRST#':'(A9)';OUT;
    'PRSNTA#':'(A10)';OUT;
    'PERST1#':'(A11)';OUT;
    'PRSNTB2#':'(A12)';IN;
    'GND_A13':'(A13)';
    'REFCLKN1':'(A14)';OUT;
    'REFCLKP1':'(A15)';OUT;
    'GND_A16':'(A16)';
    'PERN0':'(A17)';IN;
    'PERP0':'(A18)';IN;
    'GND_A19':'(A19)';
    'PERN1':'(A20)';IN;
    'PERP1':'(A21)';IN;
    'GND_A22':'(A22)';
    'PERN2':'(A23)';IN;
    'PERP2':'(A24)';IN;
    'GND_A25':'(A25)';
    'PERN3':'(A26)';IN;
    'PERP3':'(A27)';IN;
    'GND_A28':'(A28)';
    'GND_A29':'(A29)';
    'PERN4':'(A30)';IN;
    'PERP4':'(A31)';IN;
    'GND_A32':'(A32)';
    'PERN5':'(A33)';IN;
    'PERP5':'(A34)';IN;
    'GND_A35':'(A35)';
    'PERN6':'(A36)';IN;
    'PERP6':'(A37)';IN;
    'GND_A38':'(A38)';
    'PERN7':'(A39)';IN;
    'PERP7':'(A40)';IN;
    'GND_A41':'(A41)';
    'PRSNTB1#':'(A42)';IN;
    'GND_A43':'(A43)';
    'PERN8':'(A44)';IN;
    'PERP8':'(A45)';IN;
    'GND_A46':'(A46)';
    'PERN9':'(A47)';IN;
    'PERP9':'(A48)';IN;
    'GND_A49':'(A49)';
    'PERN10':'(A50)';IN;
    'PERP10':'(A51)';IN;
    'GND_A52':'(A52)';
    'PERN11':'(A53)';IN;
    'PERP11':'(A54)';IN;
    'GND_A55':'(A55)';
    'PERN12':'(A56)';IN;
    'PERP12':'(A57)';IN;
    'GND_A58':'(A58)';
    'PERN13':'(A59)';IN;
    'PERP13':'(A60)';IN;
    'GND_A61':'(A61)';
    'PERN14':'(A62)';IN;
    'PERP14':'(A63)';IN;
    'GND_A64':'(A64)';
    'PERN15':'(A65)';IN;
    'PERP15':'(A66)';IN;
    'GND_A67':'(A67)';
    'USB_DATN':'(A68)';BIDI;
    'USB_DATP':'(A69)';BIDI;
    'PWRBRK0#':'(A70)';BIDI;
    'PETP12':'(B57)';OUT;
    'GND_B58':'(B58)';
    'PETN13':'(B59)';OUT;
    'PETP13':'(B60)';OUT;
    'GND_B61':'(B61)';
    'PETN14':'(B62)';OUT;
    'PETP14':'(B63)';OUT;
    'GND_B64':'(B64)';
    'PETN15':'(B65)';OUT;
    'PETP15':'(B66)';OUT;
    'GND_B67':'(B67)';
    'RFU1_NC_B68':'(B68)';OUT;
    'RFU1_NC_B69':'(B69)';OUT;
    'PRSNTB3#':'(B70)';IN;
    'G1':'(G1)';
    'G2':'(G2)';
    'G3':'(G3)';
    'G4':'(G4)';
    'G5':'(G5)';
end_primitive;
primitive 'SCONN20_513860200CV01-SCONN20_A';body 'SCONN20_513860200CV01';
    '1':'(1)';BIDI;
    '2':'(2)';BIDI;
    '3':'(3)';BIDI;
    '4':'(4)';BIDI;
    '5':'(5)';BIDI;
    '6':'(6)';BIDI;
    '7':'(7)';BIDI;
    '8':'(8)';BIDI;
    '9':'(9)';BIDI;
    '10':'(10)';BIDI;
    '11':'(11)';BIDI;
    '12':'(12)';BIDI;
    '13':'(13)';BIDI;
    '14':'(14)';BIDI;
    '15':'(15)';BIDI;
    '16':'(16)';BIDI;
    '17':'(17)';BIDI;
    '18':'(18)';BIDI;
    '19':'(19)';BIDI;
    '20':'(20)';BIDI;
end_primitive;
primitive 'SCONN21_9193031121LF-SCONN21_9A';body 'SCONN21_9193031121LF';
    '1':'(1)';BIDI;
    '3':'(3)';BIDI;
    '4':'(4)';BIDI;
    '5':'(5)';BIDI;
    '2':'(2)';BIDI;
    'G1':'(G1)';
    'G2':'(G2)';
    '6':'(6)';BIDI;
    '7':'(7)';BIDI;
    '8':'(8)';BIDI;
    '9':'(9)';BIDI;
    '10':'(10)';BIDI;
    '11':'(11)';BIDI;
    '12':'(12)';BIDI;
    '13':'(13)';BIDI;
    '14':'(14)';BIDI;
    '15':'(15)';BIDI;
    '16':'(16)';BIDI;
    '17':'(17)';BIDI;
    '18':'(18)';BIDI;
    '19':'(19)';BIDI;
    '20':'(20)';BIDI;
    '21':'(21)';BIDI;
end_primitive;
primitive 'SCONN288_ADR50017P087CC-SCONN2A';body 'SCONN288_ADR50017P087CC';
    'VIN_MGMT':'(3,0,0)';$S;
    'RFU0':'(2,0,0)';$S;OUT;
    'RFU1':'(144,0,0)';$S;OUT;
    'RFU2':'(149,0,0)';$S;OUT;
    'RFU3':'(150,0,0)';$S;OUT;
    'RFU4':'(220,0,0)';$S;OUT;
    'RFU5':'(231,0,0)';$S;OUT;
    'RFU6':'(232,0,0)';$S;OUT;
    'RESET_N':'(207,0,0)';$S;IN;
    'PWR_GOOD||FAIL_N':'(147,0,0)';$S;BIDI;
    'PAR_B':'(227,0,0)';$S;IN;
    'PAR_A':'(74,0,0)';$S;IN;
    'LBS||RSP_B_N':'(87,0,0)';$S;OUT;
    'LBD||RSP_A_N':'(86,0,0)';$S;OUT;
    'HSDA':'(5,0,0)';$S;BIDI;
    'HSCL':'(4,0,0)';$S;IN;
    'HSA':'(148,0,0)';$S;IN;
    'DQ0_B':'(100,0,0)';$S;BIDI;
    'DQ1_B':'(102,0,0)';$S;BIDI;
    'DQ2_B':'(245,0,0)';$S;BIDI;
    'DQ3_B':'(247,0,0)';$S;BIDI;
    'DQ4_B':'(107,0,0)';$S;BIDI;
    'DQ5_B':'(109,0,0)';$S;BIDI;
    'DQ6_B':'(252,0,0)';$S;BIDI;
    'DQ7_B':'(254,0,0)';$S;BIDI;
    'DQ8_B':'(111,0,0)';$S;BIDI;
    'DQ9_B':'(113,0,0)';$S;BIDI;
    'DQ10_B':'(256,0,0)';$S;BIDI;
    'DQ11_B':'(258,0,0)';$S;BIDI;
    'DQ12_B':'(118,0,0)';$S;BIDI;
    'DQ13_B':'(120,0,0)';$S;BIDI;
    'DQ14_B':'(263,0,0)';$S;BIDI;
    'DQ15_B':'(265,0,0)';$S;BIDI;
    'DQ16_B':'(122,0,0)';$S;BIDI;
    'DQ17_B':'(124,0,0)';$S;BIDI;
    'DQ18_B':'(267,0,0)';$S;BIDI;
    'DQ19_B':'(269,0,0)';$S;BIDI;
    'DQ20_B':'(129,0,0)';$S;BIDI;
    'DQ21_B':'(131,0,0)';$S;BIDI;
    'DQ22_B':'(274,0,0)';$S;BIDI;
    'DQ23_B':'(276,0,0)';$S;BIDI;
    'DQ24_B':'(133,0,0)';$S;BIDI;
    'DQ25_B':'(135,0,0)';$S;BIDI;
    'DQ26_B':'(278,0,0)';$S;BIDI;
    'DQ27_B':'(280,0,0)';$S;BIDI;
    'DQ28_B':'(140,0,0)';$S;BIDI;
    'DQ29_B':'(142,0,0)';$S;BIDI;
    'DQ30_B':'(285,0,0)';$S;BIDI;
    'DQ31_B':'(287,0,0)';$S;BIDI;
    'DQ0_A':'(7,0,0)';$S;BIDI;
    'DQ1_A':'(9,0,0)';$S;BIDI;
    'DQ2_A':'(152,0,0)';$S;BIDI;
    'DQ3_A':'(154,0,0)';$S;BIDI;
    'DQ4_A':'(14,0,0)';$S;BIDI;
    'DQ5_A':'(16,0,0)';$S;BIDI;
    'DQ6_A':'(159,0,0)';$S;BIDI;
    'DQ7_A':'(161,0,0)';$S;BIDI;
    'DQ8_A':'(18,0,0)';$S;BIDI;
    'DQ9_A':'(20,0,0)';$S;BIDI;
    'DQ10_A':'(163,0,0)';$S;BIDI;
    'DQ11_A':'(165,0,0)';$S;BIDI;
    'DQ12_A':'(25,0,0)';$S;BIDI;
    'DQ13_A':'(27,0,0)';$S;BIDI;
    'DQ14_A':'(170,0,0)';$S;BIDI;
    'DQ15_A':'(172,0,0)';$S;BIDI;
    'DQ16_A':'(29,0,0)';$S;BIDI;
    'DQ17_A':'(31,0,0)';$S;BIDI;
    'DQ18_A':'(174,0,0)';$S;BIDI;
    'DQ19_A':'(176,0,0)';$S;BIDI;
    'DQ20_A':'(36,0,0)';$S;BIDI;
    'DQ21_A':'(38,0,0)';$S;BIDI;
    'DQ22_A':'(181,0,0)';$S;BIDI;
    'DQ23_A':'(183,0,0)';$S;BIDI;
    'DQ24_A':'(40,0,0)';$S;BIDI;
    'DQ25_A':'(42,0,0)';$S;BIDI;
    'DQ26_A':'(185,0,0)';$S;BIDI;
    'DQ27_A':'(187,0,0)';$S;BIDI;
    'DQ28_A':'(47,0,0)';$S;BIDI;
    'DQ29_A':'(49,0,0)';$S;BIDI;
    'DQ30_A':'(192,0,0)';$S;BIDI;
    'CS1_B_N':'(229,0,0)';$S;IN;
    'CS1_A_N':'(209,0,0)';$S;IN;
    'CS0_B_N':'(84,0,0)';$S;IN;
    'CS0_A_N':'(64,0,0)';$S;IN;
    'CK_T':'(217,0,0)';$S;IN;
    'CK_C':'(218,0,0)';$S;IN;
    'CB0_B':'(96,0,0)';$S;BIDI;
    'CB1_B':'(98,0,0)';$S;BIDI;
    'CB2_B':'(241,0,0)';$S;BIDI;
    'CB3_B':'(243,0,0)';$S;BIDI;
    'CB4_B':'(89,0,0)';$S;BIDI;
    'CB5_B':'(91,0,0)';$S;BIDI;
    'CB6_B':'(234,0,0)';$S;BIDI;
    'CB0_A':'(51,0,0)';$S;BIDI;
    'CB2_A':'(196,0,0)';$S;BIDI;
    'CB3_A':'(198,0,0)';$S;BIDI;
    'CB5_A':'(60,0,0)';$S;BIDI;
    'CB6_A':'(203,0,0)';$S;BIDI;
    'CA6_B':'(82,0,0)';$S;IN;
    'CA6_A':'(72,0,0)';$S;IN;
    'CA5_B':'(225,0,0)';$S;IN;
    'CA5_A':'(215,0,0)';$S;IN;
    'CA4_B':'(80,0,0)';$S;IN;
    'CA4_A':'(70,0,0)';$S;IN;
    'CA3_B':'(223,0,0)';$S;IN;
    'CA3_A':'(213,0,0)';$S;IN;
    'CA2_B':'(78,0,0)';$S;IN;
    'CA2_A':'(68,0,0)';$S;IN;
    'CA1_B':'(221,0,0)';$S;IN;
    'CA1_A':'(211,0,0)';$S;IN;
    'CA0_B':'(76,0,0)';$S;IN;
    'CA0_A':'(66,0,0)';$S;IN;
    'ALERT_N':'(62,0,0)';$S;OUT;
    'CB7_B':'(236,0,0)';$S;BIDI;
    'CB1_A':'(53,0,0)';$S;BIDI;
    'CB4_A':'(58,0,0)';$S;BIDI;
    'CB7_A':'(205,0,0)';$S;BIDI;
    'DQ31_A':'(194,0,0)';$S;BIDI;
    'DQS9_B_T||TDQS9_B_T||DBI4_B_N':'(0,93,0)';$S;BIDI;
    'DQS9_B_C||TDQS9_B_C':'(0,94,0)';$S;BIDI;
    'DQS9_A_T||TDQS9_A_T':'(0,201,0)';$S;BIDI;
    'DQS9_A_C||TDQS9_A_C':'(0,200,0)';$S;BIDI;
    'DQS8_A_T||TDQS8_A_T':'(0,190,0)';$S;BIDI;
    'DQS8_A_C||TDQS8_A_C':'(0,189,0)';$S;BIDI;
    'DQS7_B_C||TDQS7_B_C':'(0,271,0)';$S;BIDI;
    'DQS7_A_T||TDQS7_A_T':'(0,179,0)';$S;BIDI;
    'DQS6_B_T||TDQS6_B_T':'(0,261,0)';$S;BIDI;
    'DQS6_B_C||TDQS6_B_C':'(0,260,0)';$S;BIDI;
    'DQS6_A_C||TDQS6_A_C||DQS6_A_T||TDQS6_A_T':'(0,167,0)';$S;BIDI;
    'DQS5_B_T||TDQS5_B_T':'(0,250,0)';$S;BIDI;
    'DQS5_B_C||TDQS5_B_C':'(0,249,0)';$S;BIDI;
    'DQS5_A_T||TDQS5_A_T':'(0,157,0)';$S;BIDI;
    'DQS5_A_C||TDQS5_A_C||DQS5_A_T||TDQS5_A_T':'(0,156,0)';$S;BIDI;
    'DQS4_B_T':'(0,239,0)';$S;BIDI;
    'DQS4_B_C':'(0,238,0)';$S;BIDI;
    'DQS4_A_T':'(0,55,0)';$S;BIDI;
    'DQS4_A_C':'(0,56,0)';$S;BIDI;
    'DQS3_B_T':'(0,137,0)';$S;BIDI;
    'DQS3_B_C':'(0,138,0)';$S;BIDI;
    'DQS3_A_T':'(0,44,0)';$S;BIDI;
    'DQS3_A_C':'(0,45,0)';$S;BIDI;
    'DQS2_B_T':'(0,126,0)';$S;BIDI;
    'DQS2_B_C':'(0,127,0)';$S;BIDI;
    'DQS2_A_T':'(0,33,0)';$S;BIDI;
    'DQS2_A_C':'(0,34,0)';$S;BIDI;
    'DQS1_B_T':'(0,115,0)';$S;BIDI;
    'DQS1_B_C':'(0,116,0)';$S;BIDI;
    'DQS1_A_T':'(0,22,0)';$S;BIDI;
    'DQS1_A_C':'(0,23,0)';$S;BIDI;
    'DQS0_B_T':'(0,104,0)';$S;BIDI;
    'DQS0_B_C':'(0,105,0)';$S;BIDI;
    'DQS0_A_T':'(0,11,0)';$S;BIDI;
    'DQS0_A_C':'(0,12,0)';$S;BIDI;
    'DQS7_B_T||TDQS7_B_T':'(0,272,0)';$S;BIDI;
    'DQS8_B_C||TDQS8_B_C':'(0,282,0)';$S;BIDI;
    'DQS8_B_T||TDQS8_B_T':'(0,283,0)';$S;BIDI;
    'DQS6_A_T||TDQS6_A_T':'(0,168,0)';$S;BIDI;
    'DQS7_A_C||TDQS7_A_C':'(0,178,0)';$S;BIDI;
    'VSS0':'(0,0,6)';$S;
    'VSS1':'(0,0,8)';$S;
    'VSS2':'(0,0,10)';$S;
    'VSS3':'(0,0,13)';$S;
    'VSS4':'(0,0,15)';$S;
    'VSS5':'(0,0,17)';$S;
    'VSS6':'(0,0,19)';$S;
    'VSS7':'(0,0,21)';$S;
    'VSS8':'(0,0,24)';$S;
    'VSS9':'(0,0,26)';$S;
    'VSS10':'(0,0,28)';$S;
    'VSS11':'(0,0,30)';$S;
    'VSS12':'(0,0,32)';$S;
    'VSS13':'(0,0,35)';$S;
    'VSS14':'(0,0,37)';$S;
    'VSS15':'(0,0,39)';$S;
    'VSS16':'(0,0,41)';$S;
    'VSS17':'(0,0,43)';$S;
    'VSS18':'(0,0,46)';$S;
    'VSS19':'(0,0,48)';$S;
    'VSS20':'(0,0,50)';$S;
    'VSS21':'(0,0,52)';$S;
    'VSS22':'(0,0,54)';$S;
    'VSS23':'(0,0,57)';$S;
    'VSS24':'(0,0,59)';$S;
    'VSS25':'(0,0,61)';$S;
    'VSS26':'(0,0,63)';$S;
    'VSS27':'(0,0,65)';$S;
    'VSS28':'(0,0,67)';$S;
    'VSS29':'(0,0,69)';$S;
    'VSS30':'(0,0,71)';$S;
    'VSS31':'(0,0,73)';$S;
    'VSS32':'(0,0,75)';$S;
    'VSS33':'(0,0,77)';$S;
    'VSS34':'(0,0,79)';$S;
    'VSS35':'(0,0,81)';$S;
    'VSS36':'(0,0,83)';$S;
    'VSS37':'(0,0,85)';$S;
    'VSS38':'(0,0,88)';$S;
    'VSS39':'(0,0,90)';$S;
    'VSS40':'(0,0,92)';$S;
    'VSS41':'(0,0,95)';$S;
    'VSS42':'(0,0,97)';$S;
    'VSS43':'(0,0,99)';$S;
    'VSS44':'(0,0,101)';$S;
    'VSS45':'(0,0,103)';$S;
    'VSS46':'(0,0,106)';$S;
    'VSS47':'(0,0,108)';$S;
    'VSS48':'(0,0,110)';$S;
    'VSS49':'(0,0,112)';$S;
    'VSS50':'(0,0,114)';$S;
    'VSS51':'(0,0,117)';$S;
    'VSS52':'(0,0,119)';$S;
    'VSS53':'(0,0,121)';$S;
    'VSS54':'(0,0,123)';$S;
    'VSS55':'(0,0,125)';$S;
    'VSS56':'(0,0,128)';$S;
    'VSS57':'(0,0,130)';$S;
    'VSS59':'(0,0,134)';$S;
    'VSS63':'(0,0,143)';$S;
    'VSS64':'(0,0,151)';$S;
    'VSS65':'(0,0,153)';$S;
    'VSS66':'(0,0,155)';$S;
    'VSS67':'(0,0,158)';$S;
    'VSS68':'(0,0,160)';$S;
    'VSS69':'(0,0,162)';$S;
    'VSS70':'(0,0,164)';$S;
    'VSS71':'(0,0,166)';$S;
    'VSS72':'(0,0,169)';$S;
    'VSS73':'(0,0,171)';$S;
    'VSS74':'(0,0,173)';$S;
    'VSS75':'(0,0,175)';$S;
    'VSS76':'(0,0,177)';$S;
    'VSS77':'(0,0,180)';$S;
    'VSS78':'(0,0,182)';$S;
    'VSS79':'(0,0,184)';$S;
    'VSS80':'(0,0,186)';$S;
    'VSS81':'(0,0,188)';$S;
    'VSS82':'(0,0,191)';$S;
    'VSS83':'(0,0,193)';$S;
    'VSS84':'(0,0,195)';$S;
    'VSS85':'(0,0,197)';$S;
    'VSS86':'(0,0,199)';$S;
    'VSS87':'(0,0,202)';$S;
    'VSS88':'(0,0,204)';$S;
    'VSS89':'(0,0,206)';$S;
    'VSS90':'(0,0,208)';$S;
    'VSS91':'(0,0,210)';$S;
    'VSS92':'(0,0,212)';$S;
    'VSS93':'(0,0,214)';$S;
    'VSS94':'(0,0,216)';$S;
    'VSS95':'(0,0,219)';$S;
    'VSS96':'(0,0,222)';$S;
    'VSS97':'(0,0,224)';$S;
    'VSS98':'(0,0,226)';$S;
    'VSS99':'(0,0,228)';$S;
    'VSS101':'(0,0,233)';$S;
    'VSS103':'(0,0,237)';$S;
    'VSS105':'(0,0,242)';$S;
    'VSS106':'(0,0,244)';$S;
    'VSS107':'(0,0,246)';$S;
    'VSS108':'(0,0,248)';$S;
    'VSS109':'(0,0,251)';$S;
    'VSS110':'(0,0,253)';$S;
    'VSS111':'(0,0,255)';$S;
    'VSS112':'(0,0,257)';$S;
    'VSS113':'(0,0,259)';$S;
    'VSS114':'(0,0,262)';$S;
    'VSS115':'(0,0,264)';$S;
    'VSS116':'(0,0,266)';$S;
    'VSS117':'(0,0,268)';$S;
    'VSS118':'(0,0,270)';$S;
    'VSS119':'(0,0,273)';$S;
    'VSS120':'(0,0,275)';$S;
    'VSS121':'(0,0,277)';$S;
    'VSS122':'(0,0,279)';$S;
    'VSS123':'(0,0,281)';$S;
    'VSS124':'(0,0,284)';$S;
    'VSS125':'(0,0,286)';$S;
    'VSS126':'(0,0,288)';$S;
    'VIN_BULK0':'(0,0,1)';$S;
    'VIN_BULK1':'(0,0,145)';$S;
    'VIN_BULK2':'(0,0,146)';$S;
    'VSS100':'(0,0,230)';$S;
    'VSS102':'(0,0,235)';$S;
    'VSS104':'(0,0,240)';$S;
    'VSS58':'(0,0,132)';$S;
    'VSS60':'(0,0,136)';$S;
    'VSS61':'(0,0,139)';$S;
    'VSS62':'(0,0,141)';$S;
    'G1':'(0,0,G1)';$S;
    'G2':'(0,0,G2)';$S;
    'G3':'(0,0,G3)';$S;
end_primitive;
primitive 'SCONN288_ADR50017P130CC-SCONN2A';body 'SCONN288_ADR50017P130CC';
    'VIN_MGMT':'(3,0,0)';$S;
    'RFU0':'(2,0,0)';$S;OUT;
    'RFU1':'(144,0,0)';$S;OUT;
    'RFU2':'(149,0,0)';$S;OUT;
    'RFU3':'(150,0,0)';$S;OUT;
    'RFU4':'(220,0,0)';$S;OUT;
    'RFU5':'(231,0,0)';$S;OUT;
    'RFU6':'(232,0,0)';$S;OUT;
    'RESET_N':'(207,0,0)';$S;IN;
    'PWR_GOOD||FAIL_N':'(147,0,0)';$S;BIDI;
    'PAR_B':'(227,0,0)';$S;IN;
    'PAR_A':'(74,0,0)';$S;IN;
    'LBS||RSP_B_N':'(87,0,0)';$S;OUT;
    'LBD||RSP_A_N':'(86,0,0)';$S;OUT;
    'HSDA':'(5,0,0)';$S;BIDI;
    'HSCL':'(4,0,0)';$S;IN;
    'HSA':'(148,0,0)';$S;IN;
    'DQ0_B':'(100,0,0)';$S;BIDI;
    'DQ1_B':'(102,0,0)';$S;BIDI;
    'DQ2_B':'(245,0,0)';$S;BIDI;
    'DQ3_B':'(247,0,0)';$S;BIDI;
    'DQ4_B':'(107,0,0)';$S;BIDI;
    'DQ5_B':'(109,0,0)';$S;BIDI;
    'DQ6_B':'(252,0,0)';$S;BIDI;
    'DQ7_B':'(254,0,0)';$S;BIDI;
    'DQ8_B':'(111,0,0)';$S;BIDI;
    'DQ9_B':'(113,0,0)';$S;BIDI;
    'DQ10_B':'(256,0,0)';$S;BIDI;
    'DQ11_B':'(258,0,0)';$S;BIDI;
    'DQ12_B':'(118,0,0)';$S;BIDI;
    'DQ13_B':'(120,0,0)';$S;BIDI;
    'DQ14_B':'(263,0,0)';$S;BIDI;
    'DQ15_B':'(265,0,0)';$S;BIDI;
    'DQ16_B':'(122,0,0)';$S;BIDI;
    'DQ17_B':'(124,0,0)';$S;BIDI;
    'DQ18_B':'(267,0,0)';$S;BIDI;
    'DQ19_B':'(269,0,0)';$S;BIDI;
    'DQ20_B':'(129,0,0)';$S;BIDI;
    'DQ21_B':'(131,0,0)';$S;BIDI;
    'DQ22_B':'(274,0,0)';$S;BIDI;
    'DQ23_B':'(276,0,0)';$S;BIDI;
    'DQ24_B':'(133,0,0)';$S;BIDI;
    'DQ25_B':'(135,0,0)';$S;BIDI;
    'DQ26_B':'(278,0,0)';$S;BIDI;
    'DQ27_B':'(280,0,0)';$S;BIDI;
    'DQ28_B':'(140,0,0)';$S;BIDI;
    'DQ29_B':'(142,0,0)';$S;BIDI;
    'DQ30_B':'(285,0,0)';$S;BIDI;
    'DQ31_B':'(287,0,0)';$S;BIDI;
    'DQ0_A':'(7,0,0)';$S;BIDI;
    'DQ1_A':'(9,0,0)';$S;BIDI;
    'DQ2_A':'(152,0,0)';$S;BIDI;
    'DQ3_A':'(154,0,0)';$S;BIDI;
    'DQ4_A':'(14,0,0)';$S;BIDI;
    'DQ5_A':'(16,0,0)';$S;BIDI;
    'DQ6_A':'(159,0,0)';$S;BIDI;
    'DQ7_A':'(161,0,0)';$S;BIDI;
    'DQ8_A':'(18,0,0)';$S;BIDI;
    'DQ9_A':'(20,0,0)';$S;BIDI;
    'DQ10_A':'(163,0,0)';$S;BIDI;
    'DQ11_A':'(165,0,0)';$S;BIDI;
    'DQ12_A':'(25,0,0)';$S;BIDI;
    'DQ13_A':'(27,0,0)';$S;BIDI;
    'DQ14_A':'(170,0,0)';$S;BIDI;
    'DQ15_A':'(172,0,0)';$S;BIDI;
    'DQ16_A':'(29,0,0)';$S;BIDI;
    'DQ17_A':'(31,0,0)';$S;BIDI;
    'DQ18_A':'(174,0,0)';$S;BIDI;
    'DQ19_A':'(176,0,0)';$S;BIDI;
    'DQ20_A':'(36,0,0)';$S;BIDI;
    'DQ21_A':'(38,0,0)';$S;BIDI;
    'DQ22_A':'(181,0,0)';$S;BIDI;
    'DQ23_A':'(183,0,0)';$S;BIDI;
    'DQ24_A':'(40,0,0)';$S;BIDI;
    'DQ25_A':'(42,0,0)';$S;BIDI;
    'DQ26_A':'(185,0,0)';$S;BIDI;
    'DQ27_A':'(187,0,0)';$S;BIDI;
    'DQ28_A':'(47,0,0)';$S;BIDI;
    'DQ29_A':'(49,0,0)';$S;BIDI;
    'DQ30_A':'(192,0,0)';$S;BIDI;
    'CS1_B_N':'(229,0,0)';$S;IN;
    'CS1_A_N':'(209,0,0)';$S;IN;
    'CS0_B_N':'(84,0,0)';$S;IN;
    'CS0_A_N':'(64,0,0)';$S;IN;
    'CK_T':'(217,0,0)';$S;IN;
    'CK_C':'(218,0,0)';$S;IN;
    'CB0_B':'(96,0,0)';$S;BIDI;
    'CB1_B':'(98,0,0)';$S;BIDI;
    'CB2_B':'(241,0,0)';$S;BIDI;
    'CB3_B':'(243,0,0)';$S;BIDI;
    'CB4_B':'(89,0,0)';$S;BIDI;
    'CB5_B':'(91,0,0)';$S;BIDI;
    'CB6_B':'(234,0,0)';$S;BIDI;
    'CB0_A':'(51,0,0)';$S;BIDI;
    'CB2_A':'(196,0,0)';$S;BIDI;
    'CB3_A':'(198,0,0)';$S;BIDI;
    'CB5_A':'(60,0,0)';$S;BIDI;
    'CB6_A':'(203,0,0)';$S;BIDI;
    'CA6_B':'(82,0,0)';$S;IN;
    'CA6_A':'(72,0,0)';$S;IN;
    'CA5_B':'(225,0,0)';$S;IN;
    'CA5_A':'(215,0,0)';$S;IN;
    'CA4_B':'(80,0,0)';$S;IN;
    'CA4_A':'(70,0,0)';$S;IN;
    'CA3_B':'(223,0,0)';$S;IN;
    'CA3_A':'(213,0,0)';$S;IN;
    'CA2_B':'(78,0,0)';$S;IN;
    'CA2_A':'(68,0,0)';$S;IN;
    'CA1_B':'(221,0,0)';$S;IN;
    'CA1_A':'(211,0,0)';$S;IN;
    'CA0_B':'(76,0,0)';$S;IN;
    'CA0_A':'(66,0,0)';$S;IN;
    'ALERT_N':'(62,0,0)';$S;OUT;
    'CB7_B':'(236,0,0)';$S;BIDI;
    'CB1_A':'(53,0,0)';$S;BIDI;
    'CB4_A':'(58,0,0)';$S;BIDI;
    'CB7_A':'(205,0,0)';$S;BIDI;
    'DQ31_A':'(194,0,0)';$S;BIDI;
    'DQS9_B_T||TDQS9_B_T||DBI4_B_N':'(0,93,0)';$S;BIDI;
    'DQS9_B_C||TDQS9_B_C':'(0,94,0)';$S;BIDI;
    'DQS9_A_T||TDQS9_A_T':'(0,201,0)';$S;BIDI;
    'DQS9_A_C||TDQS9_A_C':'(0,200,0)';$S;BIDI;
    'DQS8_A_T||TDQS8_A_T':'(0,190,0)';$S;BIDI;
    'DQS8_A_C||TDQS8_A_C':'(0,189,0)';$S;BIDI;
    'DQS7_B_C||TDQS7_B_C':'(0,271,0)';$S;BIDI;
    'DQS7_A_T||TDQS7_A_T':'(0,179,0)';$S;BIDI;
    'DQS6_B_T||TDQS6_B_T':'(0,261,0)';$S;BIDI;
    'DQS6_B_C||TDQS6_B_C':'(0,260,0)';$S;BIDI;
    'DQS6_A_C||TDQS6_A_C||DQS6_A_T||TDQS6_A_T':'(0,167,0)';$S;BIDI;
    'DQS5_B_T||TDQS5_B_T':'(0,250,0)';$S;BIDI;
    'DQS5_B_C||TDQS5_B_C':'(0,249,0)';$S;BIDI;
    'DQS5_A_T||TDQS5_A_T':'(0,157,0)';$S;BIDI;
    'DQS5_A_C||TDQS5_A_C||DQS5_A_T||TDQS5_A_T':'(0,156,0)';$S;BIDI;
    'DQS4_B_T':'(0,239,0)';$S;BIDI;
    'DQS4_B_C':'(0,238,0)';$S;BIDI;
    'DQS4_A_T':'(0,55,0)';$S;BIDI;
    'DQS4_A_C':'(0,56,0)';$S;BIDI;
    'DQS3_B_T':'(0,137,0)';$S;BIDI;
    'DQS3_B_C':'(0,138,0)';$S;BIDI;
    'DQS3_A_T':'(0,44,0)';$S;BIDI;
    'DQS3_A_C':'(0,45,0)';$S;BIDI;
    'DQS2_B_T':'(0,126,0)';$S;BIDI;
    'DQS2_B_C':'(0,127,0)';$S;BIDI;
    'DQS2_A_T':'(0,33,0)';$S;BIDI;
    'DQS2_A_C':'(0,34,0)';$S;BIDI;
    'DQS1_B_T':'(0,115,0)';$S;BIDI;
    'DQS1_B_C':'(0,116,0)';$S;BIDI;
    'DQS1_A_T':'(0,22,0)';$S;BIDI;
    'DQS1_A_C':'(0,23,0)';$S;BIDI;
    'DQS0_B_T':'(0,104,0)';$S;BIDI;
    'DQS0_B_C':'(0,105,0)';$S;BIDI;
    'DQS0_A_T':'(0,11,0)';$S;BIDI;
    'DQS0_A_C':'(0,12,0)';$S;BIDI;
    'DQS7_B_T||TDQS7_B_T':'(0,272,0)';$S;BIDI;
    'DQS8_B_C||TDQS8_B_C':'(0,282,0)';$S;BIDI;
    'DQS8_B_T||TDQS8_B_T':'(0,283,0)';$S;BIDI;
    'DQS6_A_T||TDQS6_A_T':'(0,168,0)';$S;BIDI;
    'DQS7_A_C||TDQS7_A_C':'(0,178,0)';$S;BIDI;
    'VSS0':'(0,0,6)';$S;
    'VSS1':'(0,0,8)';$S;
    'VSS2':'(0,0,10)';$S;
    'VSS3':'(0,0,13)';$S;
    'VSS4':'(0,0,15)';$S;
    'VSS5':'(0,0,17)';$S;
    'VSS6':'(0,0,19)';$S;
    'VSS7':'(0,0,21)';$S;
    'VSS8':'(0,0,24)';$S;
    'VSS9':'(0,0,26)';$S;
    'VSS10':'(0,0,28)';$S;
    'VSS11':'(0,0,30)';$S;
    'VSS12':'(0,0,32)';$S;
    'VSS13':'(0,0,35)';$S;
    'VSS14':'(0,0,37)';$S;
    'VSS15':'(0,0,39)';$S;
    'VSS16':'(0,0,41)';$S;
    'VSS17':'(0,0,43)';$S;
    'VSS18':'(0,0,46)';$S;
    'VSS19':'(0,0,48)';$S;
    'VSS20':'(0,0,50)';$S;
    'VSS21':'(0,0,52)';$S;
    'VSS22':'(0,0,54)';$S;
    'VSS23':'(0,0,57)';$S;
    'VSS24':'(0,0,59)';$S;
    'VSS25':'(0,0,61)';$S;
    'VSS26':'(0,0,63)';$S;
    'VSS27':'(0,0,65)';$S;
    'VSS28':'(0,0,67)';$S;
    'VSS29':'(0,0,69)';$S;
    'VSS30':'(0,0,71)';$S;
    'VSS31':'(0,0,73)';$S;
    'VSS32':'(0,0,75)';$S;
    'VSS33':'(0,0,77)';$S;
    'VSS34':'(0,0,79)';$S;
    'VSS35':'(0,0,81)';$S;
    'VSS36':'(0,0,83)';$S;
    'VSS37':'(0,0,85)';$S;
    'VSS38':'(0,0,88)';$S;
    'VSS39':'(0,0,90)';$S;
    'VSS40':'(0,0,92)';$S;
    'VSS41':'(0,0,95)';$S;
    'VSS42':'(0,0,97)';$S;
    'VSS43':'(0,0,99)';$S;
    'VSS44':'(0,0,101)';$S;
    'VSS45':'(0,0,103)';$S;
    'VSS46':'(0,0,106)';$S;
    'VSS47':'(0,0,108)';$S;
    'VSS48':'(0,0,110)';$S;
    'VSS49':'(0,0,112)';$S;
    'VSS50':'(0,0,114)';$S;
    'VSS51':'(0,0,117)';$S;
    'VSS52':'(0,0,119)';$S;
    'VSS53':'(0,0,121)';$S;
    'VSS54':'(0,0,123)';$S;
    'VSS55':'(0,0,125)';$S;
    'VSS56':'(0,0,128)';$S;
    'VSS57':'(0,0,130)';$S;
    'VSS59':'(0,0,134)';$S;
    'VSS63':'(0,0,143)';$S;
    'VSS64':'(0,0,151)';$S;
    'VSS65':'(0,0,153)';$S;
    'VSS66':'(0,0,155)';$S;
    'VSS67':'(0,0,158)';$S;
    'VSS68':'(0,0,160)';$S;
    'VSS69':'(0,0,162)';$S;
    'VSS70':'(0,0,164)';$S;
    'VSS71':'(0,0,166)';$S;
    'VSS72':'(0,0,169)';$S;
    'VSS73':'(0,0,171)';$S;
    'VSS74':'(0,0,173)';$S;
    'VSS75':'(0,0,175)';$S;
    'VSS76':'(0,0,177)';$S;
    'VSS77':'(0,0,180)';$S;
    'VSS78':'(0,0,182)';$S;
    'VSS79':'(0,0,184)';$S;
    'VSS80':'(0,0,186)';$S;
    'VSS81':'(0,0,188)';$S;
    'VSS82':'(0,0,191)';$S;
    'VSS83':'(0,0,193)';$S;
    'VSS84':'(0,0,195)';$S;
    'VSS85':'(0,0,197)';$S;
    'VSS86':'(0,0,199)';$S;
    'VSS87':'(0,0,202)';$S;
    'VSS88':'(0,0,204)';$S;
    'VSS89':'(0,0,206)';$S;
    'VSS90':'(0,0,208)';$S;
    'VSS91':'(0,0,210)';$S;
    'VSS92':'(0,0,212)';$S;
    'VSS93':'(0,0,214)';$S;
    'VSS94':'(0,0,216)';$S;
    'VSS95':'(0,0,219)';$S;
    'VSS96':'(0,0,222)';$S;
    'VSS97':'(0,0,224)';$S;
    'VSS98':'(0,0,226)';$S;
    'VSS99':'(0,0,228)';$S;
    'VSS101':'(0,0,233)';$S;
    'VSS103':'(0,0,237)';$S;
    'VSS105':'(0,0,242)';$S;
    'VSS106':'(0,0,244)';$S;
    'VSS107':'(0,0,246)';$S;
    'VSS108':'(0,0,248)';$S;
    'VSS109':'(0,0,251)';$S;
    'VSS110':'(0,0,253)';$S;
    'VSS111':'(0,0,255)';$S;
    'VSS112':'(0,0,257)';$S;
    'VSS113':'(0,0,259)';$S;
    'VSS114':'(0,0,262)';$S;
    'VSS115':'(0,0,264)';$S;
    'VSS116':'(0,0,266)';$S;
    'VSS117':'(0,0,268)';$S;
    'VSS118':'(0,0,270)';$S;
    'VSS119':'(0,0,273)';$S;
    'VSS120':'(0,0,275)';$S;
    'VSS121':'(0,0,277)';$S;
    'VSS122':'(0,0,279)';$S;
    'VSS123':'(0,0,281)';$S;
    'VSS124':'(0,0,284)';$S;
    'VSS125':'(0,0,286)';$S;
    'VSS126':'(0,0,288)';$S;
    'VIN_BULK0':'(0,0,1)';$S;
    'VIN_BULK1':'(0,0,145)';$S;
    'VIN_BULK2':'(0,0,146)';$S;
    'VSS100':'(0,0,230)';$S;
    'VSS102':'(0,0,235)';$S;
    'VSS104':'(0,0,240)';$S;
    'VSS58':'(0,0,132)';$S;
    'VSS60':'(0,0,136)';$S;
    'VSS61':'(0,0,139)';$S;
    'VSS62':'(0,0,141)';$S;
    'G1':'(0,0,G1)';$S;
    'G2':'(0,0,G2)';$S;
    'G3':'(0,0,G3)';$S;
end_primitive;
primitive 'SCONN56_123276793-SCONN56_1-23A';body 'SCONN56_123276793';
    'P12V_B1':'(B1)';
    'P12V_B2':'(B2)';
    'P12V_B3':'(B3)';
    'P12V_B4':'(B4)';
    'P12V_B5':'(B5)';
    'P12V_B6':'(B6)';
    'GND_A1':'(A1)';
    'GND_A2':'(A2)';
    'GND_A3':'(A3)';
    'GND_A4':'(A4)';
    'GND_A5':'(A5)';
    'GND_A6':'(A6)';
    'MFG':'(B7)';BIDI;
    'RFU':'(B8)';BIDI;
    'DUALPORTEN#':'(B9)';BIDI;
    'P3V3_AUX':'(B11)';
    'PWRDIS':'(B12)';BIDI;
    'GND_B13':'(B13)';
    'GND_B16':'(B16)';
    'GND_B19':'(B19)';
    'GND_B22':'(B22)';
    'GND_B25':'(B25)';
    'GND_B28':'(B28)';
    'REFCLK_N0':'(B14)';BIDI;
    'REFCLK_P0':'(B15)';BIDI;
    'PET_N0':'(B17)';BIDI;
    'PET_P0':'(B18)';BIDI;
    'PET_N1':'(B20)';BIDI;
    'PET_P1':'(B21)';BIDI;
    'PET_N2':'(B23)';BIDI;
    'PET_P2':'(B24)';BIDI;
    'PET_N3':'(B26)';BIDI;
    'PET_P3':'(B27)';BIDI;
    'SMBCLK':'(A7)';BIDI;
    'SMBDAT':'(A8)';BIDI;
    'SMBRST#':'(A9)';BIDI;
    'LED#_ACTIVITY':'(A10)';BIDI;
    'PERST0#':'(B10)';BIDI;
    'PERST1#_CLKREQ#':'(A11)';BIDI;
    'PRSNT0#':'(A12)';BIDI;
    'GND_A13':'(A13)';
    'GND_A16':'(A16)';
    'GND_A19':'(A19)';
    'GND_A22':'(A22)';
    'GND_A25':'(A25)';
    'GND_A28':'(A28)';
    'REFCLK_N1':'(A14)';BIDI;
    'REFCLK_P1':'(A15)';BIDI;
    'PER_N0':'(A17)';BIDI;
    'PER_P0':'(A18)';BIDI;
    'PER_N1':'(A20)';BIDI;
    'PER_P1':'(A21)';BIDI;
    'PER_N2':'(A23)';BIDI;
    'PER_P2':'(A24)';BIDI;
    'PER_N3':'(A26)';BIDI;
    'PER_P3':'(A27)';BIDI;
    'G2':'(G2)';
    'G1':'(G1)';
end_primitive;
primitive 'SCONN60_ASP21410801-SCONN60_ASA';body 'SCONN60_ASP21410801';
    '1':'(1)';BIDI;
    '2':'(2)';BIDI;
    '3':'(3)';BIDI;
    '4':'(4)';BIDI;
    '5':'(5)';BIDI;
    '6':'(6)';BIDI;
    '7':'(7)';BIDI;
    '8':'(8)';BIDI;
    '9':'(9)';BIDI;
    '10':'(10)';BIDI;
    '11':'(11)';BIDI;
    '12':'(12)';BIDI;
    '13':'(13)';BIDI;
    '14':'(14)';BIDI;
    '15':'(15)';BIDI;
    '16':'(16)';BIDI;
    '17':'(17)';BIDI;
    '18':'(18)';BIDI;
    '19':'(19)';BIDI;
    '20':'(20)';BIDI;
    '21':'(21)';BIDI;
    '22':'(22)';BIDI;
    '23':'(23)';BIDI;
    '24':'(24)';BIDI;
    '25':'(25)';BIDI;
    '26':'(26)';BIDI;
    '27':'(27)';BIDI;
    '28':'(28)';BIDI;
    '30':'(30)';BIDI;
    '29':'(29)';BIDI;
    '31':'(31)';BIDI;
    '32':'(32)';BIDI;
    '33':'(33)';BIDI;
    '34':'(34)';BIDI;
    '35':'(35)';BIDI;
    '36':'(36)';BIDI;
    '37':'(37)';BIDI;
    '38':'(38)';BIDI;
    '39':'(39)';BIDI;
    '40':'(40)';BIDI;
    '41':'(41)';BIDI;
    '42':'(42)';BIDI;
    '43':'(43)';BIDI;
    '44':'(44)';BIDI;
    '45':'(45)';BIDI;
    '46':'(46)';BIDI;
    '47':'(47)';BIDI;
    '48':'(48)';BIDI;
    '49':'(49)';BIDI;
    '50':'(50)';BIDI;
    '51':'(51)';BIDI;
    '52':'(52)';BIDI;
    '53':'(53)';BIDI;
    '54':'(54)';BIDI;
    '55':'(55)';BIDI;
    '56':'(56)';BIDI;
    '57':'(57)';BIDI;
    '58':'(58)';BIDI;
    '59':'(59)';BIDI;
    '60':'(60)';BIDI;
    'G1':'(G1)';
    'G2':'(G2)';
    'G3':'(G3)';
    'G4':'(G4)';
end_primitive;
primitive 'SCONN75K_APCI0155P004A-SCONN75A';body 'SCONN75K_APCI0155P004A';
    '3.3V_1':'(2)';
    '3.3V_2':'(4)';
    'DAS_DSS#||LED1#':'(10)';BIDI;
    '3.3V_3':'(12)';
    '3.3V_4':'(14)';
    '3.3V_5':'(16)';
    '3.3V_6':'(18)';
    'DEVSLP':'(38)';IN;
    'PERST#':'(50)';IN;
    'CLKREQ#':'(52)';BIDI;
    'PEWAKE#':'(54)';BIDI;
    'NC18':'(58)';OUT;
    'SUSCLK':'(68)';IN;
    '3.3V_7':'(70)';
    '3.3V_8':'(72)';
    '3.3V_9':'(74)';
    'PERN0||SATA-B+':'(41)';BIDI;
    'PERP0||SATA-B-':'(43)';BIDI;
    'PETN0||SATA-A-':'(47)';BIDI;
    'PETP0||SATA-A+':'(49)';BIDI;
    'GND11':'(57)';
    'NC19':'(67)';OUT;
    'PEDET':'(69)';OUT;
    'GND12':'(71)';
    'GND13':'(73)';
    'GND14':'(75)';
    'G1':'(G1)';
    'G2':'(G2)';
    'NC1':'(6)';OUT;
    'NC2':'(8)';OUT;
    'NC3':'(20)';OUT;
    'NC10':'(34)';OUT;
    'NC17':'(56)';OUT;
    'NC16':'(48)';OUT;
    'NC15':'(46)';OUT;
    'NC14':'(44)';OUT;
    'NC13':'(42)';OUT;
    'NC12':'(40)';OUT;
    'NC11':'(36)';OUT;
    'NC9':'(32)';OUT;
    'NC8':'(30)';OUT;
    'NC7':'(28)';OUT;
    'NC6':'(26)';OUT;
    'NC5':'(24)';OUT;
    'NC4':'(22)';OUT;
    'GND1':'(1)';
    'GND2':'(3)';
    'GND3':'(9)';
    'GND4':'(15)';
    'GND5':'(21)';
    'GND6':'(27)';
    'GND7':'(33)';
    'GND8':'(39)';
    'GND9':'(45)';
    'GND10':'(51)';
    'PERN3':'(5)';BIDI;
    'PERP3':'(7)';BIDI;
    'PETN3':'(11)';BIDI;
    'PETP3':'(13)';BIDI;
    'PERN2':'(17)';BIDI;
    'PERP2':'(19)';BIDI;
    'PETN2':'(23)';BIDI;
    'PETP2':'(25)';BIDI;
    'PERN1':'(29)';BIDI;
    'PERP1':'(31)';BIDI;
    'PETN1':'(35)';BIDI;
    'PETP1':'(37)';BIDI;
    'REFCLKN':'(53)';IN;
    'REFCLKP':'(55)';IN;
end_primitive;
primitive 'SN74LVC2G07DCKR_SMLF-SN74LVC2GA';body 'SN74LVC2G07DCKR';
    '1A':'(1)';IN;
    '2A':'(3)';IN;
    '1Y':'(6)';OUT;
    '2Y':'(4)';OUT;
    'GND':'(2)';
    'VCC':'(5)';
end_primitive;
primitive 'SOCKET4677_AZIF0045P001C01CS-SA';body 'SOCKET4677_AZIF0045P001C01CS';
    'XTAL_CLK_DP':'(CY32,0,0,0,0,0,0,0,0,0,0,0,0,0,0,0,0,0,0,0,0,0,0,0,0,0,0,0,0~
,0,0,0,0,0,0,0,0,0,0,0,0,0)';$S;IN;
    'TXT_PLTEN':'(CT20,0,0,0,0,0,0,0,0,0,0,0,0,0,0,0,0,0,0,0,0,0,0,0,0,0,0,0,0,0~
,0,0,0,0,0,0,0,0,0,0,0,0)';$S;IN;
    'TXT_AGENT':'(BT26,0,0,0,0,0,0,0,0,0,0,0,0,0,0,0,0,0,0,0,0,0,0,0,0,0,0,0,0,0~
,0,0,0,0,0,0,0,0,0,0,0,0)';$S;IN;
    'TMS':'(BR25,0,0,0,0,0,0,0,0,0,0,0,0,0,0,0,0,0,0,0,0,0,0,0,0,0,0,0,0,0,0,0,0~
,0,0,0,0,0,0,0,0,0)';$S;IN;
    'TDO':'(BW25,0,0,0,0,0,0,0,0,0,0,0,0,0,0,0,0,0,0,0,0,0,0,0,0,0,0,0,0,0,0,0,0~
,0,0,0,0,0,0,0,0,0)';$S;OUT;
    'TDI':'(BV24,0,0,0,0,0,0,0,0,0,0,0,0,0,0,0,0,0,0,0,0,0,0,0,0,0,0,0,0,0,0,0,0~
,0,0,0,0,0,0,0,0,0)';$S;IN;
    'TCK':'(BT24,0,0,0,0,0,0,0,0,0,0,0,0,0,0,0,0,0,0,0,0,0,0,0,0,0,0,0,0,0,0,0,0~
,0,0,0,0,0,0,0,0,0)';$S;IN;
    'SOCKET_ID0':'(CW60,0,0,0,0,0,0,0,0,0,0,0,0,0,0,0,0,0,0,0,0,0,0,0,0,0,0,0,0,~
0,0,0,0,0,0,0,0,0,0,0,0,0)';$S;IN;
    'SOCKET_ID1':'(CY61,0,0,0,0,0,0,0,0,0,0,0,0,0,0,0,0,0,0,0,0,0,0,0,0,0,0,0,0,~
0,0,0,0,0,0,0,0,0,0,0,0,0)';$S;IN;
    'SOCKET_ID2':'(CT61,0,0,0,0,0,0,0,0,0,0,0,0,0,0,0,0,0,0,0,0,0,0,0,0,0,0,0,0,~
0,0,0,0,0,0,0,0,0,0,0,0,0)';$S;IN;
    'SAFE_MODE_BOOT':'(AU23,0,0,0,0,0,0,0,0,0,0,0,0,0,0,0,0,0,0,0,0,0,0,0,0,0,0,~
0,0,0,0,0,0,0,0,0,0,0,0,0,0,0)';$S;BIDI;
    'RSVD91':'(CE70,0,0,0,0,0,0,0,0,0,0,0,0,0,0,0,0,0,0,0,0,0,0,0,0,0,0,0,0,0,0,~
0,0,0,0,0,0,0,0,0,0,0)';$S;BIDI;
    'RSVD88':'(CD71,0,0,0,0,0,0,0,0,0,0,0,0,0,0,0,0,0,0,0,0,0,0,0,0,0,0,0,0,0,0,~
0,0,0,0,0,0,0,0,0,0,0)';$S;BIDI;
    'RSVD76':'(BY24,0,0,0,0,0,0,0,0,0,0,0,0,0,0,0,0,0,0,0,0,0,0,0,0,0,0,0,0,0,0,~
0,0,0,0,0,0,0,0,0,0,0)';$S;BIDI;
    'RSVD161':'(G5,0,0,0,0,0,0,0,0,0,0,0,0,0,0,0,0,0,0,0,0,0,0,0,0,0,0,0,0,0,0,0~
,0,0,0,0,0,0,0,0,0,0)';$S;BIDI;
    'RSVD108':'(CJ72,0,0,0,0,0,0,0,0,0,0,0,0,0,0,0,0,0,0,0,0,0,0,0,0,0,0,0,0,0,0~
,0,0,0,0,0,0,0,0,0,0,0)';$S;BIDI;
    'PROC_ID0':'(BG72,0,0,0,0,0,0,0,0,0,0,0,0,0,0,0,0,0,0,0,0,0,0,0,0,0,0,0,0,0,~
0,0,0,0,0,0,0,0,0,0,0,0)';$S;IN;
    'PROC_ID1':'(BH71,0,0,0,0,0,0,0,0,0,0,0,0,0,0,0,0,0,0,0,0,0,0,0,0,0,0,0,0,0,~
0,0,0,0,0,0,0,0,0,0,0,0)';$S;IN;
    'PROCDIS_N':'(DA52,0,0,0,0,0,0,0,0,0,0,0,0,0,0,0,0,0,0,0,0,0,0,0,0,0,0,0,0,0~
,0,0,0,0,0,0,0,0,0,0,0,0)';$S;IN;
    'PREQ_N':'(AV22,0,0,0,0,0,0,0,0,0,0,0,0,0,0,0,0,0,0,0,0,0,0,0,0,0,0,0,0,0,0,~
0,0,0,0,0,0,0,0,0,0,0)';$S;IN;
    'PRDY_N':'(BP26,0,0,0,0,0,0,0,0,0,0,0,0,0,0,0,0,0,0,0,0,0,0,0,0,0,0,0,0,0,0,~
0,0,0,0,0,0,0,0,0,0,0)';$S;OUT;
    'PKG_ID0':'(BL64,0,0,0,0,0,0,0,0,0,0,0,0,0,0,0,0,0,0,0,0,0,0,0,0,0,0,0,0,0,0~
,0,0,0,0,0,0,0,0,0,0,0)';$S;IN;
    'PKG_ID1':'(AY63,0,0,0,0,0,0,0,0,0,0,0,0,0,0,0,0,0,0,0,0,0,0,0,0,0,0,0,0,0,0~
,0,0,0,0,0,0,0,0,0,0,0)';$S;IN;
    'PKG_ID2':'(BN64,0,0,0,0,0,0,0,0,0,0,0,0,0,0,0,0,0,0,0,0,0,0,0,0,0,0,0,0,0,0~
,0,0,0,0,0,0,0,0,0,0,0)';$S;IN;
    'PECI':'(BH24,0,0,0,0,0,0,0,0,0,0,0,0,0,0,0,0,0,0,0,0,0,0,0,0,0,0,0,0,0,0,0,~
0,0,0,0,0,0,0,0,0,0)';$S;BIDI;
    'RSVD72':'(BR23,0,0,0,0,0,0,0,0,0,0,0,0,0,0,0,0,0,0,0,0,0,0,0,0,0,0,0,0,0,0,~
0,0,0,0,0,0,0,0,0,0,0)';$S;BIDI;
    'LEGACY_SKT':'(CY59,0,0,0,0,0,0,0,0,0,0,0,0,0,0,0,0,0,0,0,0,0,0,0,0,0,0,0,0,~
0,0,0,0,0,0,0,0,0,0,0,0,0)';$S;IN;
    'FRMAGENT':'(AU17,0,0,0,0,0,0,0,0,0,0,0,0,0,0,0,0,0,0,0,0,0,0,0,0,0,0,0,0,0,~
0,0,0,0,0,0,0,0,0,0,0,0)';$S;IN;
    'DMIMODE_OVERRIDE':'(AW17,0,0,0,0,0,0,0,0,0,0,0,0,0,0,0,0,0,0,0,0,0,0,0,0,0,~
0,0,0,0,0,0,0,0,0,0,0,0,0,0,0,0)';$S;IN;
    'DDR67_RESET_N':'(CY55,0,0,0,0,0,0,0,0,0,0,0,0,0,0,0,0,0,0,0,0,0,0,0,0,0,0,0~
,0,0,0,0,0,0,0,0,0,0,0,0,0,0)';$S;OUT;
    'DDR45_RESET_N':'(CY42,0,0,0,0,0,0,0,0,0,0,0,0,0,0,0,0,0,0,0,0,0,0,0,0,0,0,0~
,0,0,0,0,0,0,0,0,0,0,0,0,0,0)';$S;OUT;
    'DDR4567_SPDSDA':'(CT18,0,0,0,0,0,0,0,0,0,0,0,0,0,0,0,0,0,0,0,0,0,0,0,0,0,0,~
0,0,0,0,0,0,0,0,0,0,0,0,0,0,0)';$S;BIDI;
    'DDR4567_SPDSCL':'(CU17,0,0,0,0,0,0,0,0,0,0,0,0,0,0,0,0,0,0,0,0,0,0,0,0,0,0,~
0,0,0,0,0,0,0,0,0,0,0,0,0,0,0)';$S;OUT;
    'DDR23_RESET_N':'(AV51,0,0,0,0,0,0,0,0,0,0,0,0,0,0,0,0,0,0,0,0,0,0,0,0,0,0,0~
,0,0,0,0,0,0,0,0,0,0,0,0,0,0)';$S;OUT;
    'DDR01_RESET_N':'(AU50,0,0,0,0,0,0,0,0,0,0,0,0,0,0,0,0,0,0,0,0,0,0,0,0,0,0,0~
,0,0,0,0,0,0,0,0,0,0,0,0,0,0)';$S;OUT;
    'DDR0123_SPDSDA':'(BY22,0,0,0,0,0,0,0,0,0,0,0,0,0,0,0,0,0,0,0,0,0,0,0,0,0,0,~
0,0,0,0,0,0,0,0,0,0,0,0,0,0,0)';$S;BIDI;
    'DDR0123_SPDSCL':'(BT22,0,0,0,0,0,0,0,0,0,0,0,0,0,0,0,0,0,0,0,0,0,0,0,0,0,0,~
0,0,0,0,0,0,0,0,0,0,0,0,0,0,0)';$S;OUT;
    'BMCINIT':'(BN23,0,0,0,0,0,0,0,0,0,0,0,0,0,0,0,0,0,0,0,0,0,0,0,0,0,0,0,0,0,0~
,0,0,0,0,0,0,0,0,0,0,0)';$S;IN;
    'BIST_ENABLE':'(AT18,0,0,0,0,0,0,0,0,0,0,0,0,0,0,0,0,0,0,0,0,0,0,0,0,0,0,0,0~
,0,0,0,0,0,0,0,0,0,0,0,0,0)';$S;IN;
    'BCLK3_DP':'(DA27,0,0,0,0,0,0,0,0,0,0,0,0,0,0,0,0,0,0,0,0,0,0,0,0,0,0,0,0,0,~
0,0,0,0,0,0,0,0,0,0,0,0)';$S;IN;
    'BCLK3_DN':'(CW27,0,0,0,0,0,0,0,0,0,0,0,0,0,0,0,0,0,0,0,0,0,0,0,0,0,0,0,0,0,~
0,0,0,0,0,0,0,0,0,0,0,0)';$S;IN;
    'BCLK2_DP':'(AV28,0,0,0,0,0,0,0,0,0,0,0,0,0,0,0,0,0,0,0,0,0,0,0,0,0,0,0,0,0,~
0,0,0,0,0,0,0,0,0,0,0,0)';$S;IN;
    'BCLK2_DN':'(AU29,0,0,0,0,0,0,0,0,0,0,0,0,0,0,0,0,0,0,0,0,0,0,0,0,0,0,0,0,0,~
0,0,0,0,0,0,0,0,0,0,0,0)';$S;IN;
    'BCLK0_DP':'(AV30,0,0,0,0,0,0,0,0,0,0,0,0,0,0,0,0,0,0,0,0,0,0,0,0,0,0,0,0,0,~
0,0,0,0,0,0,0,0,0,0,0,0)';$S;IN;
    'BCLK1_DN':'(CY28,0,0,0,0,0,0,0,0,0,0,0,0,0,0,0,0,0,0,0,0,0,0,0,0,0,0,0,0,0,~
0,0,0,0,0,0,0,0,0,0,0,0)';$S;IN;
    'BCLK1_DP':'(CW29,0,0,0,0,0,0,0,0,0,0,0,0,0,0,0,0,0,0,0,0,0,0,0,0,0,0,0,0,0,~
0,0,0,0,0,0,0,0,0,0,0,0)';$S;IN;
    'BCLK0_DN':'(AT30,0,0,0,0,0,0,0,0,0,0,0,0,0,0,0,0,0,0,0,0,0,0,0,0,0,0,0,0,0,~
0,0,0,0,0,0,0,0,0,0,0,0)';$S;IN;
    'RSVD120':'(CL72,0,0,0,0,0,0,0,0,0,0,0,0,0,0,0,0,0,0,0,0,0,0,0,0,0,0,0,0,0,0~
,0,0,0,0,0,0,0,0,0,0,0)';$S;BIDI;
    'RSVD157':'(D4,0,0,0,0,0,0,0,0,0,0,0,0,0,0,0,0,0,0,0,0,0,0,0,0,0,0,0,0,0,0,0~
,0,0,0,0,0,0,0,0,0,0)';$S;BIDI;
    'XTAL_CLK_DN':'(CW31,0,0,0,0,0,0,0,0,0,0,0,0,0,0,0,0,0,0,0,0,0,0,0,0,0,0,0,0~
,0,0,0,0,0,0,0,0,0,0,0,0,0)';$S;IN;
    'CATERR_N':'(0,BP24,0,0,0,0,0,0,0,0,0,0,0,0,0,0,0,0,0,0,0,0,0,0,0,0,0,0,0,0,~
0,0,0,0,0,0,0,0,0,0,0,0)';$S;BIDI;
    'CXPSMBUSSCL':'(0,CA25,0,0,0,0,0,0,0,0,0,0,0,0,0,0,0,0,0,0,0,0,0,0,0,0,0,0,0~
,0,0,0,0,0,0,0,0,0,0,0,0,0)';$S;OUT;
    'CXPSMBUSSDA':'(0,BY26,0,0,0,0,0,0,0,0,0,0,0,0,0,0,0,0,0,0,0,0,0,0,0,0,0,0,0~
,0,0,0,0,0,0,0,0,0,0,0,0,0)';$S;BIDI;
    'CXPSMBUS_ALERT_N':'(0,BV26,0,0,0,0,0,0,0,0,0,0,0,0,0,0,0,0,0,0,0,0,0,0,0,0,~
0,0,0,0,0,0,0,0,0,0,0,0,0,0,0,0)';$S;IN;
    'DDR01_DRAM_PWR_OK':'(0,A43,0,0,0,0,0,0,0,0,0,0,0,0,0,0,0,0,0,0,0,0,0,0,0,0,~
0,0,0,0,0,0,0,0,0,0,0,0,0,0,0,0)';$S;IN;
    'DDR23_DRAM_PWR_OK':'(0,F47,0,0,0,0,0,0,0,0,0,0,0,0,0,0,0,0,0,0,0,0,0,0,0,0,~
0,0,0,0,0,0,0,0,0,0,0,0,0,0,0,0)';$S;IN;
    'DDR45_DRAM_PWR_OK':'(0,CY44,0,0,0,0,0,0,0,0,0,0,0,0,0,0,0,0,0,0,0,0,0,0,0,0~
,0,0,0,0,0,0,0,0,0,0,0,0,0,0,0,0)';$S;IN;
    'DDR67_DRAM_PWR_OK':'(0,CW45,0,0,0,0,0,0,0,0,0,0,0,0,0,0,0,0,0,0,0,0,0,0,0,0~
,0,0,0,0,0,0,0,0,0,0,0,0,0,0,0,0)';$S;IN;
    'RSVD96':'(0,CH22,0,0,0,0,0,0,0,0,0,0,0,0,0,0,0,0,0,0,0,0,0,0,0,0,0,0,0,0,0,~
0,0,0,0,0,0,0,0,0,0,0)';$S;BIDI;
    'ERROR_N2':'(0,BD22,0,0,0,0,0,0,0,0,0,0,0,0,0,0,0,0,0,0,0,0,0,0,0,0,0,0,0,0,~
0,0,0,0,0,0,0,0,0,0,0,0)';$S;OUT;
    'ERROR_N1':'(0,AY22,0,0,0,0,0,0,0,0,0,0,0,0,0,0,0,0,0,0,0,0,0,0,0,0,0,0,0,0,~
0,0,0,0,0,0,0,0,0,0,0,0)';$S;OUT;
    'ERROR_N0':'(0,BF22,0,0,0,0,0,0,0,0,0,0,0,0,0,0,0,0,0,0,0,0,0,0,0,0,0,0,0,0,~
0,0,0,0,0,0,0,0,0,0,0,0)';$S;OUT;
    'FBRK_N':'(0,AV57,0,0,0,0,0,0,0,0,0,0,0,0,0,0,0,0,0,0,0,0,0,0,0,0,0,0,0,0,0,~
0,0,0,0,0,0,0,0,0,0,0)';$S;IN;
    'MEMHOT_IN_N':'(0,AU21,0,0,0,0,0,0,0,0,0,0,0,0,0,0,0,0,0,0,0,0,0,0,0,0,0,0,0~
,0,0,0,0,0,0,0,0,0,0,0,0,0)';$S;IN;
    'MEMHOT_OUT_N':'(0,CF26,0,0,0,0,0,0,0,0,0,0,0,0,0,0,0,0,0,0,0,0,0,0,0,0,0,0,~
0,0,0,0,0,0,0,0,0,0,0,0,0,0)';$S;OUT;
    'MEMTRIP_N':'(0,AV24,0,0,0,0,0,0,0,0,0,0,0,0,0,0,0,0,0,0,0,0,0,0,0,0,0,0,0,0~
,0,0,0,0,0,0,0,0,0,0,0,0)';$S;OUT;
    'NMI':'(0,AV18,0,0,0,0,0,0,0,0,0,0,0,0,0,0,0,0,0,0,0,0,0,0,0,0,0,0,0,0,0,0,0~
,0,0,0,0,0,0,0,0,0)';$S;IN;
    'PIROM_AD2':'(0,CP71,0,0,0,0,0,0,0,0,0,0,0,0,0,0,0,0,0,0,0,0,0,0,0,0,0,0,0,0~
,0,0,0,0,0,0,0,0,0,0,0,0)';$S;IN;
    'PIROM_AD1':'(0,CT71,0,0,0,0,0,0,0,0,0,0,0,0,0,0,0,0,0,0,0,0,0,0,0,0,0,0,0,0~
,0,0,0,0,0,0,0,0,0,0,0,0)';$S;IN;
    'PIROM_AD0':'(0,CR70,0,0,0,0,0,0,0,0,0,0,0,0,0,0,0,0,0,0,0,0,0,0,0,0,0,0,0,0~
,0,0,0,0,0,0,0,0,0,0,0,0)';$S;IN;
    'PIROM_SCL':'(0,CU70,0,0,0,0,0,0,0,0,0,0,0,0,0,0,0,0,0,0,0,0,0,0,0,0,0,0,0,0~
,0,0,0,0,0,0,0,0,0,0,0,0)';$S;IN;
    'PIROM_SDA':'(0,CM71,0,0,0,0,0,0,0,0,0,0,0,0,0,0,0,0,0,0,0,0,0,0,0,0,0,0,0,0~
,0,0,0,0,0,0,0,0,0,0,0,0)';$S;BIDI;
    'PIROM_SM_WP':'(0,CR72,0,0,0,0,0,0,0,0,0,0,0,0,0,0,0,0,0,0,0,0,0,0,0,0,0,0,0~
,0,0,0,0,0,0,0,0,0,0,0,0,0)';$S;IN;
    'PMDOWN6':'(0,CC25,0,0,0,0,0,0,0,0,0,0,0,0,0,0,0,0,0,0,0,0,0,0,0,0,0,0,0,0,0~
,0,0,0,0,0,0,0,0,0,0,0)';$S;BIDI;
    'PMDOWN5':'(0,CE23,0,0,0,0,0,0,0,0,0,0,0,0,0,0,0,0,0,0,0,0,0,0,0,0,0,0,0,0,0~
,0,0,0,0,0,0,0,0,0,0,0)';$S;BIDI;
    'PMDOWN4':'(0,CV18,0,0,0,0,0,0,0,0,0,0,0,0,0,0,0,0,0,0,0,0,0,0,0,0,0,0,0,0,0~
,0,0,0,0,0,0,0,0,0,0,0)';$S;BIDI;
    'PMDOWN3':'(0,CD24,0,0,0,0,0,0,0,0,0,0,0,0,0,0,0,0,0,0,0,0,0,0,0,0,0,0,0,0,0~
,0,0,0,0,0,0,0,0,0,0,0)';$S;BIDI;
    'PMDOWN2':'(0,CM26,0,0,0,0,0,0,0,0,0,0,0,0,0,0,0,0,0,0,0,0,0,0,0,0,0,0,0,0,0~
,0,0,0,0,0,0,0,0,0,0,0)';$S;BIDI;
    'PMDOWN1':'(0,CP26,0,0,0,0,0,0,0,0,0,0,0,0,0,0,0,0,0,0,0,0,0,0,0,0,0,0,0,0,0~
,0,0,0,0,0,0,0,0,0,0,0)';$S;BIDI;
    'PMDOWN0':'(0,CW39,0,0,0,0,0,0,0,0,0,0,0,0,0,0,0,0,0,0,0,0,0,0,0,0,0,0,0,0,0~
,0,0,0,0,0,0,0,0,0,0,0)';$S;IN;
    'PMDOWN_PCH':'(0,CY40,0,0,0,0,0,0,0,0,0,0,0,0,0,0,0,0,0,0,0,0,0,0,0,0,0,0,0,~
0,0,0,0,0,0,0,0,0,0,0,0,0)';$S;BIDI;
    'PMFAST_WAKE_N':'(0,CP20,0,0,0,0,0,0,0,0,0,0,0,0,0,0,0,0,0,0,0,0,0,0,0,0,0,0~
,0,0,0,0,0,0,0,0,0,0,0,0,0,0)';$S;BIDI;
    'PMSYNC6':'(0,CF24,0,0,0,0,0,0,0,0,0,0,0,0,0,0,0,0,0,0,0,0,0,0,0,0,0,0,0,0,0~
,0,0,0,0,0,0,0,0,0,0,0)';$S;BIDI;
    'PMSYNC5':'(0,CH24,0,0,0,0,0,0,0,0,0,0,0,0,0,0,0,0,0,0,0,0,0,0,0,0,0,0,0,0,0~
,0,0,0,0,0,0,0,0,0,0,0)';$S;BIDI;
    'PMSYNC4':'(0,CR19,0,0,0,0,0,0,0,0,0,0,0,0,0,0,0,0,0,0,0,0,0,0,0,0,0,0,0,0,0~
,0,0,0,0,0,0,0,0,0,0,0)';$S;BIDI;
    'PMSYNC3':'(0,CE25,0,0,0,0,0,0,0,0,0,0,0,0,0,0,0,0,0,0,0,0,0,0,0,0,0,0,0,0,0~
,0,0,0,0,0,0,0,0,0,0,0)';$S;BIDI;
    'PMSYNC2':'(0,CH26,0,0,0,0,0,0,0,0,0,0,0,0,0,0,0,0,0,0,0,0,0,0,0,0,0,0,0,0,0~
,0,0,0,0,0,0,0,0,0,0,0)';$S;BIDI;
    'PMSYNC1':'(0,CL25,0,0,0,0,0,0,0,0,0,0,0,0,0,0,0,0,0,0,0,0,0,0,0,0,0,0,0,0,0~
,0,0,0,0,0,0,0,0,0,0,0)';$S;BIDI;
    'PMSYNC0':'(0,CN25,0,0,0,0,0,0,0,0,0,0,0,0,0,0,0,0,0,0,0,0,0,0,0,0,0,0,0,0,0~
,0,0,0,0,0,0,0,0,0,0,0)';$S;BIDI;
    'PMSYNC_PCH':'(0,DA39,0,0,0,0,0,0,0,0,0,0,0,0,0,0,0,0,0,0,0,0,0,0,0,0,0,0,0,~
0,0,0,0,0,0,0,0,0,0,0,0,0)';$S;BIDI;
    'PROCHOT_N':'(0,AU19,0,0,0,0,0,0,0,0,0,0,0,0,0,0,0,0,0,0,0,0,0,0,0,0,0,0,0,0~
,0,0,0,0,0,0,0,0,0,0,0,0)';$S;IN;
    'PWRGOOD':'(0,AV20,0,0,0,0,0,0,0,0,0,0,0,0,0,0,0,0,0,0,0,0,0,0,0,0,0,0,0,0,0~
,0,0,0,0,0,0,0,0,0,0,0)';$S;IN;
    'RESET_N':'(0,BH61,0,0,0,0,0,0,0,0,0,0,0,0,0,0,0,0,0,0,0,0,0,0,0,0,0,0,0,0,0~
,0,0,0,0,0,0,0,0,0,0,0)';$S;IN;
    'RSVD113':'(0,CL21,0,0,0,0,0,0,0,0,0,0,0,0,0,0,0,0,0,0,0,0,0,0,0,0,0,0,0,0,0~
,0,0,0,0,0,0,0,0,0,0,0)';$S;BIDI;
    'RSVD116':'(0,CL64,0,0,0,0,0,0,0,0,0,0,0,0,0,0,0,0,0,0,0,0,0,0,0,0,0,0,0,0,0~
,0,0,0,0,0,0,0,0,0,0,0)';$S;BIDI;
    'RSVD121':'(0,CM63,0,0,0,0,0,0,0,0,0,0,0,0,0,0,0,0,0,0,0,0,0,0,0,0,0,0,0,0,0~
,0,0,0,0,0,0,0,0,0,0,0)';$S;BIDI;
    'RSVD126':'(0,CN62,0,0,0,0,0,0,0,0,0,0,0,0,0,0,0,0,0,0,0,0,0,0,0,0,0,0,0,0,0~
,0,0,0,0,0,0,0,0,0,0,0)';$S;BIDI;
    'RSVD132':'(0,CR23,0,0,0,0,0,0,0,0,0,0,0,0,0,0,0,0,0,0,0,0,0,0,0,0,0,0,0,0,0~
,0,0,0,0,0,0,0,0,0,0,0)';$S;BIDI;
    'RSVD141':'(0,CV24,0,0,0,0,0,0,0,0,0,0,0,0,0,0,0,0,0,0,0,0,0,0,0,0,0,0,0,0,0~
,0,0,0,0,0,0,0,0,0,0,0)';$S;BIDI;
    'RSVD145':'(0,CW23,0,0,0,0,0,0,0,0,0,0,0,0,0,0,0,0,0,0,0,0,0,0,0,0,0,0,0,0,0~
,0,0,0,0,0,0,0,0,0,0,0)';$S;BIDI;
    'RSVD146':'(0,CW25,0,0,0,0,0,0,0,0,0,0,0,0,0,0,0,0,0,0,0,0,0,0,0,0,0,0,0,0,0~
,0,0,0,0,0,0,0,0,0,0,0)';$S;BIDI;
    'RSVD150':'(0,CW68,0,0,0,0,0,0,0,0,0,0,0,0,0,0,0,0,0,0,0,0,0,0,0,0,0,0,0,0,0~
,0,0,0,0,0,0,0,0,0,0,0)';$S;BIDI;
    'RSVD15':'(0,AV26,0,0,0,0,0,0,0,0,0,0,0,0,0,0,0,0,0,0,0,0,0,0,0,0,0,0,0,0,0,~
0,0,0,0,0,0,0,0,0,0,0)';$S;BIDI;
    'RSVD27':'(0,AY26,0,0,0,0,0,0,0,0,0,0,0,0,0,0,0,0,0,0,0,0,0,0,0,0,0,0,0,0,0,~
0,0,0,0,0,0,0,0,0,0,0)';$S;BIDI;
    'RSVD29':'(0,AY65,0,0,0,0,0,0,0,0,0,0,0,0,0,0,0,0,0,0,0,0,0,0,0,0,0,0,0,0,0,~
0,0,0,0,0,0,0,0,0,0,0)';$S;BIDI;
    'RSVD4':'(0,AT24,0,0,0,0,0,0,0,0,0,0,0,0,0,0,0,0,0,0,0,0,0,0,0,0,0,0,0,0,0,0~
,0,0,0,0,0,0,0,0,0,0)';$S;BIDI;
    'RSVD59':'(0,BJ70,0,0,0,0,0,0,0,0,0,0,0,0,0,0,0,0,0,0,0,0,0,0,0,0,0,0,0,0,0,~
0,0,0,0,0,0,0,0,0,0,0)';$S;BIDI;
    'RSVD6':'(0,AU25,0,0,0,0,0,0,0,0,0,0,0,0,0,0,0,0,0,0,0,0,0,0,0,0,0,0,0,0,0,0~
,0,0,0,0,0,0,0,0,0,0)';$S;BIDI;
    'RSVD69':'(0,BP67,0,0,0,0,0,0,0,0,0,0,0,0,0,0,0,0,0,0,0,0,0,0,0,0,0,0,0,0,0,~
0,0,0,0,0,0,0,0,0,0,0)';$S;BIDI;
    'RSVD70':'(0,BP69,0,0,0,0,0,0,0,0,0,0,0,0,0,0,0,0,0,0,0,0,0,0,0,0,0,0,0,0,0,~
0,0,0,0,0,0,0,0,0,0,0)';$S;BIDI;
    'RSVD104':'(0,CJ62,0,0,0,0,0,0,0,0,0,0,0,0,0,0,0,0,0,0,0,0,0,0,0,0,0,0,0,0,0~
,0,0,0,0,0,0,0,0,0,0,0)';$S;BIDI;
    'SKTOCC_N':'(0,CG66,0,0,0,0,0,0,0,0,0,0,0,0,0,0,0,0,0,0,0,0,0,0,0,0,0,0,0,0,~
0,0,0,0,0,0,0,0,0,0,0,0)';$S;OUT;
    'SVIDALERT0_N':'(0,BK26,0,0,0,0,0,0,0,0,0,0,0,0,0,0,0,0,0,0,0,0,0,0,0,0,0,0,~
0,0,0,0,0,0,0,0,0,0,0,0,0,0)';$S;IN;
    'SVIDALERT1_N':'(0,BJ25,0,0,0,0,0,0,0,0,0,0,0,0,0,0,0,0,0,0,0,0,0,0,0,0,0,0,~
0,0,0,0,0,0,0,0,0,0,0,0,0,0)';$S;IN;
    'SVIDCLK0':'(0,BH26,0,0,0,0,0,0,0,0,0,0,0,0,0,0,0,0,0,0,0,0,0,0,0,0,0,0,0,0,~
0,0,0,0,0,0,0,0,0,0,0,0)';$S;OUT;
    'SVIDCLK1':'(0,BF26,0,0,0,0,0,0,0,0,0,0,0,0,0,0,0,0,0,0,0,0,0,0,0,0,0,0,0,0,~
0,0,0,0,0,0,0,0,0,0,0,0)';$S;OUT;
    'SVIDDATA0':'(0,BD26,0,0,0,0,0,0,0,0,0,0,0,0,0,0,0,0,0,0,0,0,0,0,0,0,0,0,0,0~
,0,0,0,0,0,0,0,0,0,0,0,0)';$S;BIDI;
    'SVIDDATA1':'(0,BL25,0,0,0,0,0,0,0,0,0,0,0,0,0,0,0,0,0,0,0,0,0,0,0,0,0,0,0,0~
,0,0,0,0,0,0,0,0,0,0,0,0)';$S;BIDI;
    'TAP_ODT_EN':'(0,AY20,0,0,0,0,0,0,0,0,0,0,0,0,0,0,0,0,0,0,0,0,0,0,0,0,0,0,0,~
0,0,0,0,0,0,0,0,0,0,0,0,0)';$S;IN;
    'RSVD19':'(0,AV59,0,0,0,0,0,0,0,0,0,0,0,0,0,0,0,0,0,0,0,0,0,0,0,0,0,0,0,0,0,~
0,0,0,0,0,0,0,0,0,0,0)';$S;BIDI;
    'THERMTRIP_N':'(0,BL62,0,0,0,0,0,0,0,0,0,0,0,0,0,0,0,0,0,0,0,0,0,0,0,0,0,0,0~
,0,0,0,0,0,0,0,0,0,0,0,0,0)';$S;OUT;
    'PLT_AUX_PWRGOOD':'(0,0,CV20,0,0,0,0,0,0,0,0,0,0,0,0,0,0,0,0,0,0,0,0,0,0,0,0~
,0,0,0,0,0,0,0,0,0,0,0,0,0,0,0)';$S;IN;
    'RSVD109':'(0,0,CK22,0,0,0,0,0,0,0,0,0,0,0,0,0,0,0,0,0,0,0,0,0,0,0,0,0,0,0,0~
,0,0,0,0,0,0,0,0,0,0,0)';$S;BIDI;
    'RSVD110':'(0,0,CK24,0,0,0,0,0,0,0,0,0,0,0,0,0,0,0,0,0,0,0,0,0,0,0,0,0,0,0,0~
,0,0,0,0,0,0,0,0,0,0,0)';$S;BIDI;
    'RSVD114':'(0,0,CL23,0,0,0,0,0,0,0,0,0,0,0,0,0,0,0,0,0,0,0,0,0,0,0,0,0,0,0,0~
,0,0,0,0,0,0,0,0,0,0,0)';$S;BIDI;
    'RSVD11':'(0,0,AU62,0,0,0,0,0,0,0,0,0,0,0,0,0,0,0,0,0,0,0,0,0,0,0,0,0,0,0,0,~
0,0,0,0,0,0,0,0,0,0,0)';$S;BIDI;
    'RSVD117':'(0,0,CL66,0,0,0,0,0,0,0,0,0,0,0,0,0,0,0,0,0,0,0,0,0,0,0,0,0,0,0,0~
,0,0,0,0,0,0,0,0,0,0,0)';$S;BIDI;
    'RSVD123':'(0,0,CN21,0,0,0,0,0,0,0,0,0,0,0,0,0,0,0,0,0,0,0,0,0,0,0,0,0,0,0,0~
,0,0,0,0,0,0,0,0,0,0,0)';$S;BIDI;
    'RSVD124':'(0,0,CN23,0,0,0,0,0,0,0,0,0,0,0,0,0,0,0,0,0,0,0,0,0,0,0,0,0,0,0,0~
,0,0,0,0,0,0,0,0,0,0,0)';$S;BIDI;
    'RSVD12':'(0,0,AU64,0,0,0,0,0,0,0,0,0,0,0,0,0,0,0,0,0,0,0,0,0,0,0,0,0,0,0,0,~
0,0,0,0,0,0,0,0,0,0,0)';$S;BIDI;
    'RSVD127':'(0,0,CP22,0,0,0,0,0,0,0,0,0,0,0,0,0,0,0,0,0,0,0,0,0,0,0,0,0,0,0,0~
,0,0,0,0,0,0,0,0,0,0,0)';$S;BIDI;
    'RSVD128':'(0,0,CP24,0,0,0,0,0,0,0,0,0,0,0,0,0,0,0,0,0,0,0,0,0,0,0,0,0,0,0,0~
,0,0,0,0,0,0,0,0,0,0,0)';$S;BIDI;
    'RSVD131':'(0,0,CR21,0,0,0,0,0,0,0,0,0,0,0,0,0,0,0,0,0,0,0,0,0,0,0,0,0,0,0,0~
,0,0,0,0,0,0,0,0,0,0,0)';$S;BIDI;
    'RSVD136':'(0,0,CT22,0,0,0,0,0,0,0,0,0,0,0,0,0,0,0,0,0,0,0,0,0,0,0,0,0,0,0,0~
,0,0,0,0,0,0,0,0,0,0,0)';$S;BIDI;
    'RSVD137':'(0,0,CT24,0,0,0,0,0,0,0,0,0,0,0,0,0,0,0,0,0,0,0,0,0,0,0,0,0,0,0,0~
,0,0,0,0,0,0,0,0,0,0,0)';$S;BIDI;
    'RSVD140':'(0,0,CV22,0,0,0,0,0,0,0,0,0,0,0,0,0,0,0,0,0,0,0,0,0,0,0,0,0,0,0,0~
,0,0,0,0,0,0,0,0,0,0,0)';$S;BIDI;
    'RSVD142':'(0,0,CV69,0,0,0,0,0,0,0,0,0,0,0,0,0,0,0,0,0,0,0,0,0,0,0,0,0,0,0,0~
,0,0,0,0,0,0,0,0,0,0,0)';$S;BIDI;
    'RSVD143':'(0,0,CV71,0,0,0,0,0,0,0,0,0,0,0,0,0,0,0,0,0,0,0,0,0,0,0,0,0,0,0,0~
,0,0,0,0,0,0,0,0,0,0,0)';$S;BIDI;
    'RSVD144':'(0,0,CW21,0,0,0,0,0,0,0,0,0,0,0,0,0,0,0,0,0,0,0,0,0,0,0,0,0,0,0,0~
,0,0,0,0,0,0,0,0,0,0,0)';$S;BIDI;
    'CD_INIT_ERROR':'(0,0,CY20,0,0,0,0,0,0,0,0,0,0,0,0,0,0,0,0,0,0,0,0,0,0,0,0,0~
,0,0,0,0,0,0,0,0,0,0,0,0,0,0)';$S;OUT;
    'TEST_5':'(0,0,CY22,0,0,0,0,0,0,0,0,0,0,0,0,0,0,0,0,0,0,0,0,0,0,0,0,0,0,0,0,~
0,0,0,0,0,0,0,0,0,0,0)';$S;BIDI;
    'RSVD155':'(0,0,CY69,0,0,0,0,0,0,0,0,0,0,0,0,0,0,0,0,0,0,0,0,0,0,0,0,0,0,0,0~
,0,0,0,0,0,0,0,0,0,0,0)';$S;BIDI;
    'RSVD156':'(0,0,CY71,0,0,0,0,0,0,0,0,0,0,0,0,0,0,0,0,0,0,0,0,0,0,0,0,0,0,0,0~
,0,0,0,0,0,0,0,0,0,0,0)';$S;BIDI;
    'RSVD20':'(0,0,AV63,0,0,0,0,0,0,0,0,0,0,0,0,0,0,0,0,0,0,0,0,0,0,0,0,0,0,0,0,~
0,0,0,0,0,0,0,0,0,0,0)';$S;BIDI;
    'RSVD23':'(0,0,AW19,0,0,0,0,0,0,0,0,0,0,0,0,0,0,0,0,0,0,0,0,0,0,0,0,0,0,0,0,~
0,0,0,0,0,0,0,0,0,0,0)';$S;BIDI;
    'RSVD24':'(0,0,AW64,0,0,0,0,0,0,0,0,0,0,0,0,0,0,0,0,0,0,0,0,0,0,0,0,0,0,0,0,~
0,0,0,0,0,0,0,0,0,0,0)';$S;BIDI;
    'RSVD28':'(0,0,AY61,0,0,0,0,0,0,0,0,0,0,0,0,0,0,0,0,0,0,0,0,0,0,0,0,0,0,0,0,~
0,0,0,0,0,0,0,0,0,0,0)';$S;BIDI;
    'RSVD30':'(0,0,AY67,0,0,0,0,0,0,0,0,0,0,0,0,0,0,0,0,0,0,0,0,0,0,0,0,0,0,0,0,~
0,0,0,0,0,0,0,0,0,0,0)';$S;BIDI;
    'RSVD32':'(0,0,BA62,0,0,0,0,0,0,0,0,0,0,0,0,0,0,0,0,0,0,0,0,0,0,0,0,0,0,0,0,~
0,0,0,0,0,0,0,0,0,0,0)';$S;BIDI;
    'RSVD33':'(0,0,BA66,0,0,0,0,0,0,0,0,0,0,0,0,0,0,0,0,0,0,0,0,0,0,0,0,0,0,0,0,~
0,0,0,0,0,0,0,0,0,0,0)';$S;BIDI;
    'RSVD34':'(0,0,BA68,0,0,0,0,0,0,0,0,0,0,0,0,0,0,0,0,0,0,0,0,0,0,0,0,0,0,0,0,~
0,0,0,0,0,0,0,0,0,0,0)';$S;BIDI;
    'RSVD35':'(0,0,BB61,0,0,0,0,0,0,0,0,0,0,0,0,0,0,0,0,0,0,0,0,0,0,0,0,0,0,0,0,~
0,0,0,0,0,0,0,0,0,0,0)';$S;BIDI;
    'RSVD36':'(0,0,BB67,0,0,0,0,0,0,0,0,0,0,0,0,0,0,0,0,0,0,0,0,0,0,0,0,0,0,0,0,~
0,0,0,0,0,0,0,0,0,0,0)';$S;BIDI;
    'RSVD38':'(0,0,BC25,0,0,0,0,0,0,0,0,0,0,0,0,0,0,0,0,0,0,0,0,0,0,0,0,0,0,0,0,~
0,0,0,0,0,0,0,0,0,0,0)';$S;BIDI;
    'RSVD39':'(0,0,BC64,0,0,0,0,0,0,0,0,0,0,0,0,0,0,0,0,0,0,0,0,0,0,0,0,0,0,0,0,~
0,0,0,0,0,0,0,0,0,0,0)';$S;BIDI;
    'RSVD40':'(0,0,BD61,0,0,0,0,0,0,0,0,0,0,0,0,0,0,0,0,0,0,0,0,0,0,0,0,0,0,0,0,~
0,0,0,0,0,0,0,0,0,0,0)';$S;BIDI;
    'RSVD41':'(0,0,BD63,0,0,0,0,0,0,0,0,0,0,0,0,0,0,0,0,0,0,0,0,0,0,0,0,0,0,0,0,~
0,0,0,0,0,0,0,0,0,0,0)';$S;BIDI;
    'RSVD42':'(0,0,BD65,0,0,0,0,0,0,0,0,0,0,0,0,0,0,0,0,0,0,0,0,0,0,0,0,0,0,0,0,~
0,0,0,0,0,0,0,0,0,0,0)';$S;BIDI;
    'RSVD47':'(0,0,BE25,0,0,0,0,0,0,0,0,0,0,0,0,0,0,0,0,0,0,0,0,0,0,0,0,0,0,0,0,~
0,0,0,0,0,0,0,0,0,0,0)';$S;BIDI;
    'RSVD48':'(0,0,BE62,0,0,0,0,0,0,0,0,0,0,0,0,0,0,0,0,0,0,0,0,0,0,0,0,0,0,0,0,~
0,0,0,0,0,0,0,0,0,0,0)';$S;BIDI;
    'RSVD50':'(0,0,BF65,0,0,0,0,0,0,0,0,0,0,0,0,0,0,0,0,0,0,0,0,0,0,0,0,0,0,0,0,~
0,0,0,0,0,0,0,0,0,0,0)';$S;BIDI;
    'RSVD52':'(0,0,BG62,0,0,0,0,0,0,0,0,0,0,0,0,0,0,0,0,0,0,0,0,0,0,0,0,0,0,0,0,~
0,0,0,0,0,0,0,0,0,0,0)';$S;BIDI;
    'RSVD53':'(0,0,BG64,0,0,0,0,0,0,0,0,0,0,0,0,0,0,0,0,0,0,0,0,0,0,0,0,0,0,0,0,~
0,0,0,0,0,0,0,0,0,0,0)';$S;BIDI;
    'RSVD55':'(0,0,BH63,0,0,0,0,0,0,0,0,0,0,0,0,0,0,0,0,0,0,0,0,0,0,0,0,0,0,0,0,~
0,0,0,0,0,0,0,0,0,0,0)';$S;BIDI;
    'RSVD56':'(0,0,BH65,0,0,0,0,0,0,0,0,0,0,0,0,0,0,0,0,0,0,0,0,0,0,0,0,0,0,0,0,~
0,0,0,0,0,0,0,0,0,0,0)';$S;BIDI;
    'RSVD58':'(0,0,BJ64,0,0,0,0,0,0,0,0,0,0,0,0,0,0,0,0,0,0,0,0,0,0,0,0,0,0,0,0,~
0,0,0,0,0,0,0,0,0,0,0)';$S;BIDI;
    'RSVD61':'(0,0,BK63,0,0,0,0,0,0,0,0,0,0,0,0,0,0,0,0,0,0,0,0,0,0,0,0,0,0,0,0,~
0,0,0,0,0,0,0,0,0,0,0)';$S;BIDI;
    'RSVD64':'(0,0,BM63,0,0,0,0,0,0,0,0,0,0,0,0,0,0,0,0,0,0,0,0,0,0,0,0,0,0,0,0,~
0,0,0,0,0,0,0,0,0,0,0)';$S;BIDI;
    'RSVD86':'(0,0,CD65,0,0,0,0,0,0,0,0,0,0,0,0,0,0,0,0,0,0,0,0,0,0,0,0,0,0,0,0,~
0,0,0,0,0,0,0,0,0,0,0)';$S;BIDI;
    'TEST_6':'(0,0,CF61,0,0,0,0,0,0,0,0,0,0,0,0,0,0,0,0,0,0,0,0,0,0,0,0,0,0,0,0,~
0,0,0,0,0,0,0,0,0,0,0)';$S;BIDI;
    'RSVD93':'(0,0,CF63,0,0,0,0,0,0,0,0,0,0,0,0,0,0,0,0,0,0,0,0,0,0,0,0,0,0,0,0,~
0,0,0,0,0,0,0,0,0,0,0)';$S;BIDI;
    'RSVD94':'(0,0,CF65,0,0,0,0,0,0,0,0,0,0,0,0,0,0,0,0,0,0,0,0,0,0,0,0,0,0,0,0,~
0,0,0,0,0,0,0,0,0,0,0)';$S;BIDI;
    'RSVD98':'(0,0,CH63,0,0,0,0,0,0,0,0,0,0,0,0,0,0,0,0,0,0,0,0,0,0,0,0,0,0,0,0,~
0,0,0,0,0,0,0,0,0,0,0)';$S;BIDI;
    'RSVD100':'(0,0,CH71,0,0,0,0,0,0,0,0,0,0,0,0,0,0,0,0,0,0,0,0,0,0,0,0,0,0,0,0~
,0,0,0,0,0,0,0,0,0,0,0)';$S;BIDI;
    'RSVD101':'(0,0,CJ21,0,0,0,0,0,0,0,0,0,0,0,0,0,0,0,0,0,0,0,0,0,0,0,0,0,0,0,0~
,0,0,0,0,0,0,0,0,0,0,0)';$S;BIDI;
    'RSVD102':'(0,0,CJ23,0,0,0,0,0,0,0,0,0,0,0,0,0,0,0,0,0,0,0,0,0,0,0,0,0,0,0,0~
,0,0,0,0,0,0,0,0,0,0,0)';$S;BIDI;
    'RSVD103':'(0,0,CJ25,0,0,0,0,0,0,0,0,0,0,0,0,0,0,0,0,0,0,0,0,0,0,0,0,0,0,0,0~
,0,0,0,0,0,0,0,0,0,0,0)';$S;BIDI;
    'RSVD105':'(0,0,CJ66,0,0,0,0,0,0,0,0,0,0,0,0,0,0,0,0,0,0,0,0,0,0,0,0,0,0,0,0~
,0,0,0,0,0,0,0,0,0,0,0)';$S;BIDI;
    'RSVD25':'(0,0,AW70,0,0,0,0,0,0,0,0,0,0,0,0,0,0,0,0,0,0,0,0,0,0,0,0,0,0,0,0,~
0,0,0,0,0,0,0,0,0,0,0)';$S;BIDI;
    'TEST_8':'(0,0,AY69,0,0,0,0,0,0,0,0,0,0,0,0,0,0,0,0,0,0,0,0,0,0,0,0,0,0,0,0,~
0,0,0,0,0,0,0,0,0,0,0)';$S;BIDI;
    'TEST_7':'(0,0,AV69,0,0,0,0,0,0,0,0,0,0,0,0,0,0,0,0,0,0,0,0,0,0,0,0,0,0,0,0,~
0,0,0,0,0,0,0,0,0,0,0)';$S;BIDI;
    'PARTITION_ID1':'(0,0,AV71,0,0,0,0,0,0,0,0,0,0,0,0,0,0,0,0,0,0,0,0,0,0,0,0,0~
,0,0,0,0,0,0,0,0,0,0,0,0,0,0)';$S;IN;
    'PARTITION_ID0':'(0,0,BA70,0,0,0,0,0,0,0,0,0,0,0,0,0,0,0,0,0,0,0,0,0,0,0,0,0~
,0,0,0,0,0,0,0,0,0,0,0,0,0,0)';$S;IN;
    'SMB_CLK':'(0,0,CE64,0,0,0,0,0,0,0,0,0,0,0,0,0,0,0,0,0,0,0,0,0,0,0,0,0,0,0,0~
,0,0,0,0,0,0,0,0,0,0,0)';$S;OUT;
    'SMB_DATA':'(0,0,CD63,0,0,0,0,0,0,0,0,0,0,0,0,0,0,0,0,0,0,0,0,0,0,0,0,0,0,0,~
0,0,0,0,0,0,0,0,0,0,0,0)';$S;BIDI;
    'TEST_1':'(0,0,CJ64,0,0,0,0,0,0,0,0,0,0,0,0,0,0,0,0,0,0,0,0,0,0,0,0,0,0,0,0,~
0,0,0,0,0,0,0,0,0,0,0)';$S;BIDI;
    'TEST_2':'(0,0,CK65,0,0,0,0,0,0,0,0,0,0,0,0,0,0,0,0,0,0,0,0,0,0,0,0,0,0,0,0,~
0,0,0,0,0,0,0,0,0,0,0)';$S;BIDI;
    'TEST_3':'(0,0,CH65,0,0,0,0,0,0,0,0,0,0,0,0,0,0,0,0,0,0,0,0,0,0,0,0,0,0,0,0,~
0,0,0,0,0,0,0,0,0,0,0)';$S;BIDI;
    'RSVD37':'(0,0,0,BC23,0,0,0,0,0,0,0,0,0,0,0,0,0,0,0,0,0,0,0,0,0,0,0,0,0,0,0,~
0,0,0,0,0,0,0,0,0,0,0)';$S;BIDI;
    'RSVD46':'(0,0,0,BE23,0,0,0,0,0,0,0,0,0,0,0,0,0,0,0,0,0,0,0,0,0,0,0,0,0,0,0,~
0,0,0,0,0,0,0,0,0,0,0)';$S;BIDI;
    'RSVD49':'(0,0,0,BF24,0,0,0,0,0,0,0,0,0,0,0,0,0,0,0,0,0,0,0,0,0,0,0,0,0,0,0,~
0,0,0,0,0,0,0,0,0,0,0)';$S;BIDI;
    'MBP0_N':'(0,0,0,BL23,0,0,0,0,0,0,0,0,0,0,0,0,0,0,0,0,0,0,0,0,0,0,0,0,0,0,0,~
0,0,0,0,0,0,0,0,0,0,0)';$S;BIDI;
    'MBP1_N':'(0,0,0,BN25,0,0,0,0,0,0,0,0,0,0,0,0,0,0,0,0,0,0,0,0,0,0,0,0,0,0,0,~
0,0,0,0,0,0,0,0,0,0,0)';$S;BIDI;
    'MBP2_N':'(0,0,0,BJ23,0,0,0,0,0,0,0,0,0,0,0,0,0,0,0,0,0,0,0,0,0,0,0,0,0,0,0,~
0,0,0,0,0,0,0,0,0,0,0)';$S;BIDI;
    'MBP3_N':'(0,0,0,BK24,0,0,0,0,0,0,0,0,0,0,0,0,0,0,0,0,0,0,0,0,0,0,0,0,0,0,0,~
0,0,0,0,0,0,0,0,0,0,0)';$S;BIDI;
    'PMAX_TRIGGER_IO':'(0,0,0,BD24,0,0,0,0,0,0,0,0,0,0,0,0,0,0,0,0,0,0,0,0,0,0,0~
,0,0,0,0,0,0,0,0,0,0,0,0,0,0,0)';$S;BIDI;
    'RMCA_N':'(0,0,0,BH22,0,0,0,0,0,0,0,0,0,0,0,0,0,0,0,0,0,0,0,0,0,0,0,0,0,0,0,~
0,0,0,0,0,0,0,0,0,0,0)';$S;BIDI;
    'RSVD10':'(0,0,0,AU58,0,0,0,0,0,0,0,0,0,0,0,0,0,0,0,0,0,0,0,0,0,0,0,0,0,0,0,~
0,0,0,0,0,0,0,0,0,0,0)';$S;BIDI;
    'RSVD90':'(0,0,0,CE62,0,0,0,0,0,0,0,0,0,0,0,0,0,0,0,0,0,0,0,0,0,0,0,0,0,0,0,~
0,0,0,0,0,0,0,0,0,0,0)';$S;BIDI;
    'RSVD139':'(0,0,0,CU62,0,0,0,0,0,0,0,0,0,0,0,0,0,0,0,0,0,0,0,0,0,0,0,0,0,0,0~
,0,0,0,0,0,0,0,0,0,0,0)';$S;BIDI;
    'RSVD125':'(0,0,0,CN60,0,0,0,0,0,0,0,0,0,0,0,0,0,0,0,0,0,0,0,0,0,0,0,0,0,0,0~
,0,0,0,0,0,0,0,0,0,0,0)';$S;BIDI;
    'RSVD129':'(0,0,0,CP61,0,0,0,0,0,0,0,0,0,0,0,0,0,0,0,0,0,0,0,0,0,0,0,0,0,0,0~
,0,0,0,0,0,0,0,0,0,0,0)';$S;BIDI;
    'RSVD134':'(0,0,0,CR60,0,0,0,0,0,0,0,0,0,0,0,0,0,0,0,0,0,0,0,0,0,0,0,0,0,0,0~
,0,0,0,0,0,0,0,0,0,0,0)';$S;BIDI;
    'RSVD151':'(0,0,0,CY24,0,0,0,0,0,0,0,0,0,0,0,0,0,0,0,0,0,0,0,0,0,0,0,0,0,0,0~
,0,0,0,0,0,0,0,0,0,0,0)';$S;BIDI;
    'RSVD152':'(0,0,0,CY38,0,0,0,0,0,0,0,0,0,0,0,0,0,0,0,0,0,0,0,0,0,0,0,0,0,0,0~
,0,0,0,0,0,0,0,0,0,0,0)';$S;BIDI;
    'RSVD153':'(0,0,0,CY49,0,0,0,0,0,0,0,0,0,0,0,0,0,0,0,0,0,0,0,0,0,0,0,0,0,0,0~
,0,0,0,0,0,0,0,0,0,0,0)';$S;BIDI;
    'RSVD158':'(0,0,0,DA45,0,0,0,0,0,0,0,0,0,0,0,0,0,0,0,0,0,0,0,0,0,0,0,0,0,0,0~
,0,0,0,0,0,0,0,0,0,0,0)';$S;BIDI;
    'RSVD162':'(0,0,0,H12,0,0,0,0,0,0,0,0,0,0,0,0,0,0,0,0,0,0,0,0,0,0,0,0,0,0,0,~
0,0,0,0,0,0,0,0,0,0,0)';$S;BIDI;
    'RSVD16':'(0,0,0,AV32,0,0,0,0,0,0,0,0,0,0,0,0,0,0,0,0,0,0,0,0,0,0,0,0,0,0,0,~
0,0,0,0,0,0,0,0,0,0,0)';$S;BIDI;
    'RSVD17':'(0,0,0,AV38,0,0,0,0,0,0,0,0,0,0,0,0,0,0,0,0,0,0,0,0,0,0,0,0,0,0,0,~
0,0,0,0,0,0,0,0,0,0,0)';$S;BIDI;
    'RSVD18':'(0,0,0,AV40,0,0,0,0,0,0,0,0,0,0,0,0,0,0,0,0,0,0,0,0,0,0,0,0,0,0,0,~
0,0,0,0,0,0,0,0,0,0,0)';$S;BIDI;
    'RSVD7':'(0,0,0,AU33,0,0,0,0,0,0,0,0,0,0,0,0,0,0,0,0,0,0,0,0,0,0,0,0,0,0,0,0~
,0,0,0,0,0,0,0,0,0,0)';$S;BIDI;
    'RSVD9':'(0,0,0,AU56,0,0,0,0,0,0,0,0,0,0,0,0,0,0,0,0,0,0,0,0,0,0,0,0,0,0,0,0~
,0,0,0,0,0,0,0,0,0,0)';$S;BIDI;
    'RSVD81':'(0,0,0,CC64,0,0,0,0,0,0,0,0,0,0,0,0,0,0,0,0,0,0,0,0,0,0,0,0,0,0,0,~
0,0,0,0,0,0,0,0,0,0,0)';$S;BIDI;
    'VCCD_HV_SENSE':'(0,0,0,BU11,0,0,0,0,0,0,0,0,0,0,0,0,0,0,0,0,0,0,0,0,0,0,0,0~
,0,0,0,0,0,0,0,0,0,0,0,0,0,0)';$S;
    'VCCFA_EHV_FIVRA_SENSE':'(0,0,0,AY85,0,0,0,0,0,0,0,0,0,0,0,0,0,0,0,0,0,0,0,0~
,0,0,0,0,0,0,0,0,0,0,0,0,0,0,0,0,0,0)';$S;
    'VCCFA_EHV_SENSE':'(0,0,0,AU11,0,0,0,0,0,0,0,0,0,0,0,0,0,0,0,0,0,0,0,0,0,0,0~
,0,0,0,0,0,0,0,0,0,0,0,0,0,0,0)';$S;
    'VCCINFAON_SENSE':'(0,0,0,CA11,0,0,0,0,0,0,0,0,0,0,0,0,0,0,0,0,0,0,0,0,0,0,0~
,0,0,0,0,0,0,0,0,0,0,0,0,0,0,0)';$S;
    'VCCIN_SENSE':'(0,0,0,BD87,0,0,0,0,0,0,0,0,0,0,0,0,0,0,0,0,0,0,0,0,0,0,0,0,0~
,0,0,0,0,0,0,0,0,0,0,0,0,0)';$S;
    'VSS_VCCD_HV_SENSE':'(0,0,0,BN11,0,0,0,0,0,0,0,0,0,0,0,0,0,0,0,0,0,0,0,0,0,0~
,0,0,0,0,0,0,0,0,0,0,0,0,0,0,0,0)';$S;
    'VSS_VCCFA_EHV_FIVRA_SENSE':'(0,0,0,AT85,0,0,0,0,0,0,0,0,0,0,0,0,0,0,0,0,0,0~
,0,0,0,0,0,0,0,0,0,0,0,0,0,0,0,0,0,0,0,0)';$S;
    'VSS_VCCFA_EHV_SENSE':'(0,0,0,BA11,0,0,0,0,0,0,0,0,0,0,0,0,0,0,0,0,0,0,0,0,0~
,0,0,0,0,0,0,0,0,0,0,0,0,0,0,0,0,0)';$S;
    'VSS_VCCINFAON_SENSE':'(0,0,0,CE11,0,0,0,0,0,0,0,0,0,0,0,0,0,0,0,0,0,0,0,0,0~
,0,0,0,0,0,0,0,0,0,0,0,0,0,0,0,0,0)';$S;
    'VSS_VCCIN_SENSE':'(0,0,0,BC90,0,0,0,0,0,0,0,0,0,0,0,0,0,0,0,0,0,0,0,0,0,0,0~
,0,0,0,0,0,0,0,0,0,0,0,0,0,0,0)';$S;
    'RSVD0':'(0,0,0,0,AC78,0,0,0,0,0,0,0,0,0,0,0,0,0,0,0,0,0,0,0,0,0,0,0,0,0,0,0~
,0,0,0,0,0,0,0,0,0,0)';$S;BIDI;
    'RSVD1':'(0,0,0,0,AD77,0,0,0,0,0,0,0,0,0,0,0,0,0,0,0,0,0,0,0,0,0,0,0,0,0,0,0~
,0,0,0,0,0,0,0,0,0,0)';$S;BIDI;
    'RSVD106':'(0,0,0,0,CJ68,0,0,0,0,0,0,0,0,0,0,0,0,0,0,0,0,0,0,0,0,0,0,0,0,0,0~
,0,0,0,0,0,0,0,0,0,0,0)';$S;BIDI;
    'RSVD107':'(0,0,0,0,CJ70,0,0,0,0,0,0,0,0,0,0,0,0,0,0,0,0,0,0,0,0,0,0,0,0,0,0~
,0,0,0,0,0,0,0,0,0,0,0)';$S;BIDI;
    'RSVD112':'(0,0,0,0,CK67,0,0,0,0,0,0,0,0,0,0,0,0,0,0,0,0,0,0,0,0,0,0,0,0,0,0~
,0,0,0,0,0,0,0,0,0,0,0)';$S;BIDI;
    'RSVD133':'(0,0,0,0,CR25,0,0,0,0,0,0,0,0,0,0,0,0,0,0,0,0,0,0,0,0,0,0,0,0,0,0~
,0,0,0,0,0,0,0,0,0,0,0)';$S;BIDI;
    'RSVD138':'(0,0,0,0,CT26,0,0,0,0,0,0,0,0,0,0,0,0,0,0,0,0,0,0,0,0,0,0,0,0,0,0~
,0,0,0,0,0,0,0,0,0,0,0)';$S;BIDI;
    'RSVD147':'(0,0,0,0,CW41,0,0,0,0,0,0,0,0,0,0,0,0,0,0,0,0,0,0,0,0,0,0,0,0,0,0~
,0,0,0,0,0,0,0,0,0,0,0)';$S;BIDI;
    'RSVD149':'(0,0,0,0,CW58,0,0,0,0,0,0,0,0,0,0,0,0,0,0,0,0,0,0,0,0,0,0,0,0,0,0~
,0,0,0,0,0,0,0,0,0,0,0)';$S;BIDI;
    'RSVD154':'(0,0,0,0,CY57,0,0,0,0,0,0,0,0,0,0,0,0,0,0,0,0,0,0,0,0,0,0,0,0,0,0~
,0,0,0,0,0,0,0,0,0,0,0)';$S;BIDI;
    'RSVD160':'(0,0,0,0,EG17,0,0,0,0,0,0,0,0,0,0,0,0,0,0,0,0,0,0,0,0,0,0,0,0,0,0~
,0,0,0,0,0,0,0,0,0,0,0)';$S;BIDI;
    'RSVD164':'(0,0,0,0,U17,0,0,0,0,0,0,0,0,0,0,0,0,0,0,0,0,0,0,0,0,0,0,0,0,0,0,~
0,0,0,0,0,0,0,0,0,0,0)';$S;BIDI;
    'RSVD165':'(0,0,0,0,W17,0,0,0,0,0,0,0,0,0,0,0,0,0,0,0,0,0,0,0,0,0,0,0,0,0,0,~
0,0,0,0,0,0,0,0,0,0,0)';$S;BIDI;
    'RSVD21':'(0,0,0,0,AV65,0,0,0,0,0,0,0,0,0,0,0,0,0,0,0,0,0,0,0,0,0,0,0,0,0,0,~
0,0,0,0,0,0,0,0,0,0,0)';$S;BIDI;
    'RSVD26':'(0,0,0,0,AY24,0,0,0,0,0,0,0,0,0,0,0,0,0,0,0,0,0,0,0,0,0,0,0,0,0,0,~
0,0,0,0,0,0,0,0,0,0,0)';$S;BIDI;
    'RSVD31':'(0,0,0,0,BA25,0,0,0,0,0,0,0,0,0,0,0,0,0,0,0,0,0,0,0,0,0,0,0,0,0,0,~
0,0,0,0,0,0,0,0,0,0,0)';$S;BIDI;
    'RSVD43':'(0,0,0,0,BD71,0,0,0,0,0,0,0,0,0,0,0,0,0,0,0,0,0,0,0,0,0,0,0,0,0,0,~
0,0,0,0,0,0,0,0,0,0,0)';$S;BIDI;
    'RSVD45':'(0,0,0,0,BE21,0,0,0,0,0,0,0,0,0,0,0,0,0,0,0,0,0,0,0,0,0,0,0,0,0,0,~
0,0,0,0,0,0,0,0,0,0,0)';$S;BIDI;
    'RSVD51':'(0,0,0,0,BF71,0,0,0,0,0,0,0,0,0,0,0,0,0,0,0,0,0,0,0,0,0,0,0,0,0,0,~
0,0,0,0,0,0,0,0,0,0,0)';$S;BIDI;
    'RSVD54':'(0,0,0,0,BG78,0,0,0,0,0,0,0,0,0,0,0,0,0,0,0,0,0,0,0,0,0,0,0,0,0,0,~
0,0,0,0,0,0,0,0,0,0,0)';$S;BIDI;
    'RSVD57':'(0,0,0,0,BJ21,0,0,0,0,0,0,0,0,0,0,0,0,0,0,0,0,0,0,0,0,0,0,0,0,0,0,~
0,0,0,0,0,0,0,0,0,0,0)';$S;BIDI;
    'RSVD60':'(0,0,0,0,BK22,0,0,0,0,0,0,0,0,0,0,0,0,0,0,0,0,0,0,0,0,0,0,0,0,0,0,~
0,0,0,0,0,0,0,0,0,0,0)';$S;BIDI;
    'RSVD63':'(0,0,0,0,BL60,0,0,0,0,0,0,0,0,0,0,0,0,0,0,0,0,0,0,0,0,0,0,0,0,0,0,~
0,0,0,0,0,0,0,0,0,0,0)';$S;BIDI;
    'RSVD65':'(0,0,0,0,BM65,0,0,0,0,0,0,0,0,0,0,0,0,0,0,0,0,0,0,0,0,0,0,0,0,0,0,~
0,0,0,0,0,0,0,0,0,0,0)';$S;BIDI;
    'RSVD67':'(0,0,0,0,BP22,0,0,0,0,0,0,0,0,0,0,0,0,0,0,0,0,0,0,0,0,0,0,0,0,0,0,~
0,0,0,0,0,0,0,0,0,0,0)';$S;BIDI;
    'RSVD68':'(0,0,0,0,BP65,0,0,0,0,0,0,0,0,0,0,0,0,0,0,0,0,0,0,0,0,0,0,0,0,0,0,~
0,0,0,0,0,0,0,0,0,0,0)';$S;BIDI;
    'RSVD71':'(0,0,0,0,BR21,0,0,0,0,0,0,0,0,0,0,0,0,0,0,0,0,0,0,0,0,0,0,0,0,0,0,~
0,0,0,0,0,0,0,0,0,0,0)';$S;BIDI;
    'RSVD82':'(0,0,0,0,CC66,0,0,0,0,0,0,0,0,0,0,0,0,0,0,0,0,0,0,0,0,0,0,0,0,0,0,~
0,0,0,0,0,0,0,0,0,0,0)';$S;BIDI;
    'RSVD83':'(0,0,0,0,CD22,0,0,0,0,0,0,0,0,0,0,0,0,0,0,0,0,0,0,0,0,0,0,0,0,0,0,~
0,0,0,0,0,0,0,0,0,0,0)';$S;BIDI;
    'RSVD84':'(0,0,0,0,CD26,0,0,0,0,0,0,0,0,0,0,0,0,0,0,0,0,0,0,0,0,0,0,0,0,0,0,~
0,0,0,0,0,0,0,0,0,0,0)';$S;BIDI;
    'RSVD85':'(0,0,0,0,CD30,0,0,0,0,0,0,0,0,0,0,0,0,0,0,0,0,0,0,0,0,0,0,0,0,0,0,~
0,0,0,0,0,0,0,0,0,0,0)';$S;BIDI;
    'RSVD92':'(0,0,0,0,CF22,0,0,0,0,0,0,0,0,0,0,0,0,0,0,0,0,0,0,0,0,0,0,0,0,0,0,~
0,0,0,0,0,0,0,0,0,0,0)';$S;BIDI;
    'RSVD99':'(0,0,0,0,CH69,0,0,0,0,0,0,0,0,0,0,0,0,0,0,0,0,0,0,0,0,0,0,0,0,0,0,~
0,0,0,0,0,0,0,0,0,0,0)';$S;BIDI;
    'RSVD119':'(0,0,0,0,0,CL70,0,0,0,0,0,0,0,0,0,0,0,0,0,0,0,0,0,0,0,0,0,0,0,0,0~
,0,0,0,0,0,0,0,0,0,0,0)';$S;BIDI;
    'RSVD115':'(0,0,0,0,0,CL60,0,0,0,0,0,0,0,0,0,0,0,0,0,0,0,0,0,0,0,0,0,0,0,0,0~
,0,0,0,0,0,0,0,0,0,0,0)';$S;BIDI;
    'RSVD148':'(0,0,0,0,0,CW43,0,0,0,0,0,0,0,0,0,0,0,0,0,0,0,0,0,0,0,0,0,0,0,0,0~
,0,0,0,0,0,0,0,0,0,0,0)';$S;BIDI;
    'RSVD159':'(0,0,0,0,0,DA70,0,0,0,0,0,0,0,0,0,0,0,0,0,0,0,0,0,0,0,0,0,0,0,0,0~
,0,0,0,0,0,0,0,0,0,0,0)';$S;BIDI;
    'RSVD44':'(0,0,0,0,0,BD77,0,0,0,0,0,0,0,0,0,0,0,0,0,0,0,0,0,0,0,0,0,0,0,0,0,~
0,0,0,0,0,0,0,0,0,0,0)';$S;BIDI;
    'RSVD97':'(0,0,0,0,0,CH61,0,0,0,0,0,0,0,0,0,0,0,0,0,0,0,0,0,0,0,0,0,0,0,0,0,~
0,0,0,0,0,0,0,0,0,0,0)';$S;BIDI;
    'RSVD8':'(0,0,0,0,0,AU52,0,0,0,0,0,0,0,0,0,0,0,0,0,0,0,0,0,0,0,0,0,0,0,0,0,0~
,0,0,0,0,0,0,0,0,0,0)';$S;BIDI;
    'RSVD87':'(0,0,0,0,0,CD69,0,0,0,0,0,0,0,0,0,0,0,0,0,0,0,0,0,0,0,0,0,0,0,0,0,~
0,0,0,0,0,0,0,0,0,0,0)';$S;BIDI;
    'RSVD111':'(0,0,0,0,0,CK61,0,0,0,0,0,0,0,0,0,0,0,0,0,0,0,0,0,0,0,0,0,0,0,0,0~
,0,0,0,0,0,0,0,0,0,0,0)';$S;BIDI;
    'RSVD95':'(0,0,0,0,0,CG60,0,0,0,0,0,0,0,0,0,0,0,0,0,0,0,0,0,0,0,0,0,0,0,0,0,~
0,0,0,0,0,0,0,0,0,0,0)';$S;BIDI;
    'RSVD163':'(0,0,0,0,0,J13,0,0,0,0,0,0,0,0,0,0,0,0,0,0,0,0,0,0,0,0,0,0,0,0,0,~
0,0,0,0,0,0,0,0,0,0,0)';$S;BIDI;
    'PTI_DIE0015':'(0,0,0,0,0,0,BP30,0,0,0,0,0,0,0,0,0,0,0,0,0,0,0,0,0,0,0,0,0,0~
,0,0,0,0,0,0,0,0,0,0,0,0,0)';$S;OUT;
    'PTI_DIE0014':'(0,0,0,0,0,0,BN29,0,0,0,0,0,0,0,0,0,0,0,0,0,0,0,0,0,0,0,0,0,0~
,0,0,0,0,0,0,0,0,0,0,0,0,0)';$S;OUT;
    'PTI_DIE0013':'(0,0,0,0,0,0,BP28,0,0,0,0,0,0,0,0,0,0,0,0,0,0,0,0,0,0,0,0,0,0~
,0,0,0,0,0,0,0,0,0,0,0,0,0)';$S;OUT;
    'PTI_DIE0012':'(0,0,0,0,0,0,BN27,0,0,0,0,0,0,0,0,0,0,0,0,0,0,0,0,0,0,0,0,0,0~
,0,0,0,0,0,0,0,0,0,0,0,0,0)';$S;OUT;
    'PTI_DIE0011':'(0,0,0,0,0,0,BT30,0,0,0,0,0,0,0,0,0,0,0,0,0,0,0,0,0,0,0,0,0,0~
,0,0,0,0,0,0,0,0,0,0,0,0,0)';$S;OUT;
    'PTI_DIE0010':'(0,0,0,0,0,0,BU29,0,0,0,0,0,0,0,0,0,0,0,0,0,0,0,0,0,0,0,0,0,0~
,0,0,0,0,0,0,0,0,0,0,0,0,0)';$S;OUT;
    'PTI_DIE009':'(0,0,0,0,0,0,BT28,0,0,0,0,0,0,0,0,0,0,0,0,0,0,0,0,0,0,0,0,0,0,~
0,0,0,0,0,0,0,0,0,0,0,0,0)';$S;OUT;
    'PTI_DIE008':'(0,0,0,0,0,0,BU27,0,0,0,0,0,0,0,0,0,0,0,0,0,0,0,0,0,0,0,0,0,0,~
0,0,0,0,0,0,0,0,0,0,0,0,0)';$S;OUT;
    'PTI_DIE007':'(0,0,0,0,0,0,BV28,0,0,0,0,0,0,0,0,0,0,0,0,0,0,0,0,0,0,0,0,0,0,~
0,0,0,0,0,0,0,0,0,0,0,0,0)';$S;OUT;
    'PTI_DIE006':'(0,0,0,0,0,0,CA27,0,0,0,0,0,0,0,0,0,0,0,0,0,0,0,0,0,0,0,0,0,0,~
0,0,0,0,0,0,0,0,0,0,0,0,0)';$S;OUT;
    'PTI_DIE005':'(0,0,0,0,0,0,BV30,0,0,0,0,0,0,0,0,0,0,0,0,0,0,0,0,0,0,0,0,0,0,~
0,0,0,0,0,0,0,0,0,0,0,0,0)';$S;OUT;
    'PTI_DIE004':'(0,0,0,0,0,0,CA29,0,0,0,0,0,0,0,0,0,0,0,0,0,0,0,0,0,0,0,0,0,0,~
0,0,0,0,0,0,0,0,0,0,0,0,0)';$S;OUT;
    'PTI_DIE003':'(0,0,0,0,0,0,BY30,0,0,0,0,0,0,0,0,0,0,0,0,0,0,0,0,0,0,0,0,0,0,~
0,0,0,0,0,0,0,0,0,0,0,0,0)';$S;OUT;
    'PTI_DIE002':'(0,0,0,0,0,0,CC27,0,0,0,0,0,0,0,0,0,0,0,0,0,0,0,0,0,0,0,0,0,0,~
0,0,0,0,0,0,0,0,0,0,0,0,0)';$S;OUT;
    'PTI_DIE001':'(0,0,0,0,0,0,CD28,0,0,0,0,0,0,0,0,0,0,0,0,0,0,0,0,0,0,0,0,0,0,~
0,0,0,0,0,0,0,0,0,0,0,0,0)';$S;OUT;
    'PTI_DIE000':'(0,0,0,0,0,0,CC29,0,0,0,0,0,0,0,0,0,0,0,0,0,0,0,0,0,0,0,0,0,0,~
0,0,0,0,0,0,0,0,0,0,0,0,0)';$S;OUT;
    'PTI_DIE00_STB_0':'(0,0,0,0,0,0,CB30,0,0,0,0,0,0,0,0,0,0,0,0,0,0,0,0,0,0,0,0~
,0,0,0,0,0,0,0,0,0,0,0,0,0,0,0)';$S;OUT;
    'PTI_DIE00_STB_1':'(0,0,0,0,0,0,BY28,0,0,0,0,0,0,0,0,0,0,0,0,0,0,0,0,0,0,0,0~
,0,0,0,0,0,0,0,0,0,0,0,0,0,0,0)';$S;OUT;
    'PTI_DIE0115':'(0,0,0,0,0,0,BN66,0,0,0,0,0,0,0,0,0,0,0,0,0,0,0,0,0,0,0,0,0,0~
,0,0,0,0,0,0,0,0,0,0,0,0,0)';$S;OUT;
    'PTI_DIE0114':'(0,0,0,0,0,0,BM67,0,0,0,0,0,0,0,0,0,0,0,0,0,0,0,0,0,0,0,0,0,0~
,0,0,0,0,0,0,0,0,0,0,0,0,0)';$S;OUT;
    'PTI_DIE0113':'(0,0,0,0,0,0,BL66,0,0,0,0,0,0,0,0,0,0,0,0,0,0,0,0,0,0,0,0,0,0~
,0,0,0,0,0,0,0,0,0,0,0,0,0)';$S;OUT;
    'PTI_DIE0112':'(0,0,0,0,0,0,BJ66,0,0,0,0,0,0,0,0,0,0,0,0,0,0,0,0,0,0,0,0,0,0~
,0,0,0,0,0,0,0,0,0,0,0,0,0)';$S;OUT;
    'PTI_DIE0111':'(0,0,0,0,0,0,BG66,0,0,0,0,0,0,0,0,0,0,0,0,0,0,0,0,0,0,0,0,0,0~
,0,0,0,0,0,0,0,0,0,0,0,0,0)';$S;OUT;
    'PTI_DIE0110':'(0,0,0,0,0,0,BN68,0,0,0,0,0,0,0,0,0,0,0,0,0,0,0,0,0,0,0,0,0,0~
,0,0,0,0,0,0,0,0,0,0,0,0,0)';$S;OUT;
    'PTI_DIE019':'(0,0,0,0,0,0,BM69,0,0,0,0,0,0,0,0,0,0,0,0,0,0,0,0,0,0,0,0,0,0,~
0,0,0,0,0,0,0,0,0,0,0,0,0)';$S;OUT;
    'PTI_DIE018':'(0,0,0,0,0,0,BK69,0,0,0,0,0,0,0,0,0,0,0,0,0,0,0,0,0,0,0,0,0,0,~
0,0,0,0,0,0,0,0,0,0,0,0,0)';$S;OUT;
    'PTI_DIE017':'(0,0,0,0,0,0,BD67,0,0,0,0,0,0,0,0,0,0,0,0,0,0,0,0,0,0,0,0,0,0,~
0,0,0,0,0,0,0,0,0,0,0,0,0)';$S;OUT;
    'PTI_DIE016':'(0,0,0,0,0,0,BG68,0,0,0,0,0,0,0,0,0,0,0,0,0,0,0,0,0,0,0,0,0,0,~
0,0,0,0,0,0,0,0,0,0,0,0,0)';$S;OUT;
    'PTI_DIE015':'(0,0,0,0,0,0,BC68,0,0,0,0,0,0,0,0,0,0,0,0,0,0,0,0,0,0,0,0,0,0,~
0,0,0,0,0,0,0,0,0,0,0,0,0)';$S;OUT;
    'PTI_DIE014':'(0,0,0,0,0,0,BH69,0,0,0,0,0,0,0,0,0,0,0,0,0,0,0,0,0,0,0,0,0,0,~
0,0,0,0,0,0,0,0,0,0,0,0,0)';$S;OUT;
    'PTI_DIE013':'(0,0,0,0,0,0,BF69,0,0,0,0,0,0,0,0,0,0,0,0,0,0,0,0,0,0,0,0,0,0,~
0,0,0,0,0,0,0,0,0,0,0,0,0)';$S;OUT;
    'PTI_DIE012':'(0,0,0,0,0,0,BD69,0,0,0,0,0,0,0,0,0,0,0,0,0,0,0,0,0,0,0,0,0,0,~
0,0,0,0,0,0,0,0,0,0,0,0,0)';$S;OUT;
    'PTI_DIE011':'(0,0,0,0,0,0,BE70,0,0,0,0,0,0,0,0,0,0,0,0,0,0,0,0,0,0,0,0,0,0,~
0,0,0,0,0,0,0,0,0,0,0,0,0)';$S;OUT;
    'PTI_DIE010':'(0,0,0,0,0,0,BC70,0,0,0,0,0,0,0,0,0,0,0,0,0,0,0,0,0,0,0,0,0,0,~
0,0,0,0,0,0,0,0,0,0,0,0,0)';$S;OUT;
    'PTI_DIE01_STB_0':'(0,0,0,0,0,0,BF67,0,0,0,0,0,0,0,0,0,0,0,0,0,0,0,0,0,0,0,0~
,0,0,0,0,0,0,0,0,0,0,0,0,0,0,0)';$S;OUT;
    'PTI_DIE01_STB_1':'(0,0,0,0,0,0,BK67,0,0,0,0,0,0,0,0,0,0,0,0,0,0,0,0,0,0,0,0~
,0,0,0,0,0,0,0,0,0,0,0,0,0,0,0)';$S;OUT;
    'RSVD118':'(0,0,0,0,0,0,CL68,0,0,0,0,0,0,0,0,0,0,0,0,0,0,0,0,0,0,0,0,0,0,0,0~
,0,0,0,0,0,0,0,0,0,0,0)';$S;BIDI;
    'RSVD122':'(0,0,0,0,0,0,CM69,0,0,0,0,0,0,0,0,0,0,0,0,0,0,0,0,0,0,0,0,0,0,0,0~
,0,0,0,0,0,0,0,0,0,0,0)';$S;BIDI;
    'RSVD130':'(0,0,0,0,0,0,CP69,0,0,0,0,0,0,0,0,0,0,0,0,0,0,0,0,0,0,0,0,0,0,0,0~
,0,0,0,0,0,0,0,0,0,0,0)';$S;BIDI;
    'RSVD135':'(0,0,0,0,0,0,CR68,0,0,0,0,0,0,0,0,0,0,0,0,0,0,0,0,0,0,0,0,0,0,0,0~
,0,0,0,0,0,0,0,0,0,0,0)';$S;BIDI;
    'RSVD13':'(0,0,0,0,0,0,AU66,0,0,0,0,0,0,0,0,0,0,0,0,0,0,0,0,0,0,0,0,0,0,0,0,~
0,0,0,0,0,0,0,0,0,0,0)';$S;BIDI;
    'RSVD14':'(0,0,0,0,0,0,AU68,0,0,0,0,0,0,0,0,0,0,0,0,0,0,0,0,0,0,0,0,0,0,0,0,~
0,0,0,0,0,0,0,0,0,0,0)';$S;BIDI;
    'RSVD2':'(0,0,0,0,0,0,AN17,0,0,0,0,0,0,0,0,0,0,0,0,0,0,0,0,0,0,0,0,0,0,0,0,0~
,0,0,0,0,0,0,0,0,0,0)';$S;BIDI;
    'RSVD22':'(0,0,0,0,0,0,AV67,0,0,0,0,0,0,0,0,0,0,0,0,0,0,0,0,0,0,0,0,0,0,0,0,~
0,0,0,0,0,0,0,0,0,0,0)';$S;BIDI;
    'RSVD3':'(0,0,0,0,0,0,AR17,0,0,0,0,0,0,0,0,0,0,0,0,0,0,0,0,0,0,0,0,0,0,0,0,0~
,0,0,0,0,0,0,0,0,0,0)';$S;BIDI;
    'RSVD5':'(0,0,0,0,0,0,AT67,0,0,0,0,0,0,0,0,0,0,0,0,0,0,0,0,0,0,0,0,0,0,0,0,0~
,0,0,0,0,0,0,0,0,0,0)';$S;BIDI;
    'RSVD62':'(0,0,0,0,0,0,BL21,0,0,0,0,0,0,0,0,0,0,0,0,0,0,0,0,0,0,0,0,0,0,0,0,~
0,0,0,0,0,0,0,0,0,0,0)';$S;BIDI;
    'RSVD66':'(0,0,0,0,0,0,BN21,0,0,0,0,0,0,0,0,0,0,0,0,0,0,0,0,0,0,0,0,0,0,0,0,~
0,0,0,0,0,0,0,0,0,0,0)';$S;BIDI;
    'RSVD73':'(0,0,0,0,0,0,BV22,0,0,0,0,0,0,0,0,0,0,0,0,0,0,0,0,0,0,0,0,0,0,0,0,~
0,0,0,0,0,0,0,0,0,0,0)';$S;BIDI;
    'RSVD74':'(0,0,0,0,0,0,BW21,0,0,0,0,0,0,0,0,0,0,0,0,0,0,0,0,0,0,0,0,0,0,0,0,~
0,0,0,0,0,0,0,0,0,0,0)';$S;BIDI;
    'RSVD75':'(0,0,0,0,0,0,BW23,0,0,0,0,0,0,0,0,0,0,0,0,0,0,0,0,0,0,0,0,0,0,0,0,~
0,0,0,0,0,0,0,0,0,0,0)';$S;BIDI;
    'RSVD77':'(0,0,0,0,0,0,CA21,0,0,0,0,0,0,0,0,0,0,0,0,0,0,0,0,0,0,0,0,0,0,0,0,~
0,0,0,0,0,0,0,0,0,0,0)';$S;BIDI;
    'RSVD78':'(0,0,0,0,0,0,CA23,0,0,0,0,0,0,0,0,0,0,0,0,0,0,0,0,0,0,0,0,0,0,0,0,~
0,0,0,0,0,0,0,0,0,0,0)';$S;BIDI;
    'RSVD79':'(0,0,0,0,0,0,CC21,0,0,0,0,0,0,0,0,0,0,0,0,0,0,0,0,0,0,0,0,0,0,0,0,~
0,0,0,0,0,0,0,0,0,0,0)';$S;BIDI;
    'RSVD80':'(0,0,0,0,0,0,CC23,0,0,0,0,0,0,0,0,0,0,0,0,0,0,0,0,0,0,0,0,0,0,0,0,~
0,0,0,0,0,0,0,0,0,0,0)';$S;BIDI;
    'RSVD89':'(0,0,0,0,0,0,CE21,0,0,0,0,0,0,0,0,0,0,0,0,0,0,0,0,0,0,0,0,0,0,0,0,~
0,0,0,0,0,0,0,0,0,0,0)';$S;BIDI;
    'UPI0_AC_COUPLING':'(0,0,0,0,0,0,BA23,0,0,0,0,0,0,0,0,0,0,0,0,0,0,0,0,0,0,0,~
0,0,0,0,0,0,0,0,0,0,0,0,0,0,0,0)';$S;IN;
    'UPI1_AC_COUPLING':'(0,0,0,0,0,0,CW19,0,0,0,0,0,0,0,0,0,0,0,0,0,0,0,0,0,0,0,~
0,0,0,0,0,0,0,0,0,0,0,0,0,0,0,0)';$S;IN;
    'UPI2_AC_COUPLING':'(0,0,0,0,0,0,BB65,0,0,0,0,0,0,0,0,0,0,0,0,0,0,0,0,0,0,0,~
0,0,0,0,0,0,0,0,0,0,0,0,0,0,0,0)';$S;IN;
    'UPI3_AC_COUPLING':'(0,0,0,0,0,0,CK71,0,0,0,0,0,0,0,0,0,0,0,0,0,0,0,0,0,0,0,~
0,0,0,0,0,0,0,0,0,0,0,0,0,0,0,0)';$S;IN;
    'DDR0_ALERT_N':'(0,0,0,0,0,0,0,AT49,0,0,0,0,0,0,0,0,0,0,0,0,0,0,0,0,0,0,0,0,~
0,0,0,0,0,0,0,0,0,0,0,0,0,0)';$S;IN;
    'DDR0_A_RSP1':'(0,0,0,0,0,0,0,AU43,0,0,0,0,0,0,0,0,0,0,0,0,0,0,0,0,0,0,0,0,0~
,0,0,0,0,0,0,0,0,0,0,0,0,0)';$S;IN;
    'DDR0_A_RSP0':'(0,0,0,0,0,0,0,AT42,0,0,0,0,0,0,0,0,0,0,0,0,0,0,0,0,0,0,0,0,0~
,0,0,0,0,0,0,0,0,0,0,0,0,0)';$S;IN;
    'DDR0_B_RSP1':'(0,0,0,0,0,0,0,AV42,0,0,0,0,0,0,0,0,0,0,0,0,0,0,0,0,0,0,0,0,0~
,0,0,0,0,0,0,0,0,0,0,0,0,0)';$S;IN;
    'DDR0_B_RSP0':'(0,0,0,0,0,0,0,AV44,0,0,0,0,0,0,0,0,0,0,0,0,0,0,0,0,0,0,0,0,0~
,0,0,0,0,0,0,0,0,0,0,0,0,0)';$S;IN;
    'DDR0_CLK_DN1':'(0,0,0,0,0,0,0,G45,0,0,0,0,0,0,0,0,0,0,0,0,0,0,0,0,0,0,0,0,0~
,0,0,0,0,0,0,0,0,0,0,0,0,0)';$S;OUT;
    'DDR0_CLK_DN0':'(0,0,0,0,0,0,0,B44,0,0,0,0,0,0,0,0,0,0,0,0,0,0,0,0,0,0,0,0,0~
,0,0,0,0,0,0,0,0,0,0,0,0,0)';$S;OUT;
    'DDR0_CLK_DP1':'(0,0,0,0,0,0,0,E45,0,0,0,0,0,0,0,0,0,0,0,0,0,0,0,0,0,0,0,0,0~
,0,0,0,0,0,0,0,0,0,0,0,0,0)';$S;OUT;
    'DDR0_CLK_DP0':'(0,0,0,0,0,0,0,C43,0,0,0,0,0,0,0,0,0,0,0,0,0,0,0,0,0,0,0,0,0~
,0,0,0,0,0,0,0,0,0,0,0,0,0)';$S;OUT;
    'DDR0_SA_CA6':'(0,0,0,0,0,0,0,C48,0,0,0,0,0,0,0,0,0,0,0,0,0,0,0,0,0,0,0,0,0,~
0,0,0,0,0,0,0,0,0,0,0,0,0)';$S;OUT;
    'DDR0_SA_CA5':'(0,0,0,0,0,0,0,E50,0,0,0,0,0,0,0,0,0,0,0,0,0,0,0,0,0,0,0,0,0,~
0,0,0,0,0,0,0,0,0,0,0,0,0)';$S;OUT;
    'DDR0_SA_CA4':'(0,0,0,0,0,0,0,C50,0,0,0,0,0,0,0,0,0,0,0,0,0,0,0,0,0,0,0,0,0,~
0,0,0,0,0,0,0,0,0,0,0,0,0)';$S;OUT;
    'DDR0_SA_CA3':'(0,0,0,0,0,0,0,F51,0,0,0,0,0,0,0,0,0,0,0,0,0,0,0,0,0,0,0,0,0,~
0,0,0,0,0,0,0,0,0,0,0,0,0)';$S;OUT;
    'DDR0_SA_CA2':'(0,0,0,0,0,0,0,B51,0,0,0,0,0,0,0,0,0,0,0,0,0,0,0,0,0,0,0,0,0,~
0,0,0,0,0,0,0,0,0,0,0,0,0)';$S;OUT;
    'DDR0_SA_CA1':'(0,0,0,0,0,0,0,G52,0,0,0,0,0,0,0,0,0,0,0,0,0,0,0,0,0,0,0,0,0,~
0,0,0,0,0,0,0,0,0,0,0,0,0)';$S;OUT;
    'DDR0_SA_CA0':'(0,0,0,0,0,0,0,A52,0,0,0,0,0,0,0,0,0,0,0,0,0,0,0,0,0,0,0,0,0,~
0,0,0,0,0,0,0,0,0,0,0,0,0)';$S;OUT;
    'DDR0_SA_CS_N3':'(0,0,0,0,0,0,0,F53,0,0,0,0,0,0,0,0,0,0,0,0,0,0,0,0,0,0,0,0,~
0,0,0,0,0,0,0,0,0,0,0,0,0,0)';$S;OUT;
    'DDR0_SA_CS_N2':'(0,0,0,0,0,0,0,E54,0,0,0,0,0,0,0,0,0,0,0,0,0,0,0,0,0,0,0,0,~
0,0,0,0,0,0,0,0,0,0,0,0,0,0)';$S;OUT;
    'DDR0_SA_CS_N1':'(0,0,0,0,0,0,0,B53,0,0,0,0,0,0,0,0,0,0,0,0,0,0,0,0,0,0,0,0,~
0,0,0,0,0,0,0,0,0,0,0,0,0,0)';$S;OUT;
    'DDR0_SA_CS_N0':'(0,0,0,0,0,0,0,C54,0,0,0,0,0,0,0,0,0,0,0,0,0,0,0,0,0,0,0,0,~
0,0,0,0,0,0,0,0,0,0,0,0,0,0)';$S;OUT;
    'DDR0_SA_DQ31':'(0,0,0,0,0,0,0,E62,0,0,0,0,0,0,0,0,0,0,0,0,0,0,0,0,0,0,0,0,0~
,0,0,0,0,0,0,0,0,0,0,0,0,0)';$S;BIDI;
    'DDR0_SA_DQ30':'(0,0,0,0,0,0,0,F63,0,0,0,0,0,0,0,0,0,0,0,0,0,0,0,0,0,0,0,0,0~
,0,0,0,0,0,0,0,0,0,0,0,0,0)';$S;BIDI;
    'DDR0_SA_DQ29':'(0,0,0,0,0,0,0,C62,0,0,0,0,0,0,0,0,0,0,0,0,0,0,0,0,0,0,0,0,0~
,0,0,0,0,0,0,0,0,0,0,0,0,0)';$S;BIDI;
    'DDR0_SA_DQ28':'(0,0,0,0,0,0,0,B63,0,0,0,0,0,0,0,0,0,0,0,0,0,0,0,0,0,0,0,0,0~
,0,0,0,0,0,0,0,0,0,0,0,0,0)';$S;BIDI;
    'DDR0_SA_DQ27':'(0,0,0,0,0,0,0,F65,0,0,0,0,0,0,0,0,0,0,0,0,0,0,0,0,0,0,0,0,0~
,0,0,0,0,0,0,0,0,0,0,0,0,0)';$S;BIDI;
    'DDR0_SA_DQ26':'(0,0,0,0,0,0,0,E66,0,0,0,0,0,0,0,0,0,0,0,0,0,0,0,0,0,0,0,0,0~
,0,0,0,0,0,0,0,0,0,0,0,0,0)';$S;BIDI;
    'DDR0_SA_DQ25':'(0,0,0,0,0,0,0,B65,0,0,0,0,0,0,0,0,0,0,0,0,0,0,0,0,0,0,0,0,0~
,0,0,0,0,0,0,0,0,0,0,0,0,0)';$S;BIDI;
    'DDR0_SA_DQ24':'(0,0,0,0,0,0,0,C66,0,0,0,0,0,0,0,0,0,0,0,0,0,0,0,0,0,0,0,0,0~
,0,0,0,0,0,0,0,0,0,0,0,0,0)';$S;BIDI;
    'DDR0_SA_DQ23':'(0,0,0,0,0,0,0,E68,0,0,0,0,0,0,0,0,0,0,0,0,0,0,0,0,0,0,0,0,0~
,0,0,0,0,0,0,0,0,0,0,0,0,0)';$S;BIDI;
    'DDR0_SA_DQ22':'(0,0,0,0,0,0,0,F69,0,0,0,0,0,0,0,0,0,0,0,0,0,0,0,0,0,0,0,0,0~
,0,0,0,0,0,0,0,0,0,0,0,0,0)';$S;BIDI;
    'DDR0_SA_DQ21':'(0,0,0,0,0,0,0,C68,0,0,0,0,0,0,0,0,0,0,0,0,0,0,0,0,0,0,0,0,0~
,0,0,0,0,0,0,0,0,0,0,0,0,0)';$S;BIDI;
    'DDR0_SA_DQ20':'(0,0,0,0,0,0,0,B69,0,0,0,0,0,0,0,0,0,0,0,0,0,0,0,0,0,0,0,0,0~
,0,0,0,0,0,0,0,0,0,0,0,0,0)';$S;BIDI;
    'DDR0_SA_DQ19':'(0,0,0,0,0,0,0,F71,0,0,0,0,0,0,0,0,0,0,0,0,0,0,0,0,0,0,0,0,0~
,0,0,0,0,0,0,0,0,0,0,0,0,0)';$S;BIDI;
    'DDR0_SA_DQ18':'(0,0,0,0,0,0,0,D73,0,0,0,0,0,0,0,0,0,0,0,0,0,0,0,0,0,0,0,0,0~
,0,0,0,0,0,0,0,0,0,0,0,0,0)';$S;BIDI;
    'DDR0_SA_DQ17':'(0,0,0,0,0,0,0,E72,0,0,0,0,0,0,0,0,0,0,0,0,0,0,0,0,0,0,0,0,0~
,0,0,0,0,0,0,0,0,0,0,0,0,0)';$S;BIDI;
    'DDR0_SA_DQ16':'(0,0,0,0,0,0,0,B73,0,0,0,0,0,0,0,0,0,0,0,0,0,0,0,0,0,0,0,0,0~
,0,0,0,0,0,0,0,0,0,0,0,0,0)';$S;BIDI;
    'DDR0_SA_DQ15':'(0,0,0,0,0,0,0,M65,0,0,0,0,0,0,0,0,0,0,0,0,0,0,0,0,0,0,0,0,0~
,0,0,0,0,0,0,0,0,0,0,0,0,0)';$S;BIDI;
    'DDR0_SA_DQ14':'(0,0,0,0,0,0,0,N66,0,0,0,0,0,0,0,0,0,0,0,0,0,0,0,0,0,0,0,0,0~
,0,0,0,0,0,0,0,0,0,0,0,0,0)';$S;BIDI;
    'DDR0_SA_DQ13':'(0,0,0,0,0,0,0,K65,0,0,0,0,0,0,0,0,0,0,0,0,0,0,0,0,0,0,0,0,0~
,0,0,0,0,0,0,0,0,0,0,0,0,0)';$S;BIDI;
    'DDR0_SA_DQ12':'(0,0,0,0,0,0,0,J66,0,0,0,0,0,0,0,0,0,0,0,0,0,0,0,0,0,0,0,0,0~
,0,0,0,0,0,0,0,0,0,0,0,0,0)';$S;BIDI;
    'DDR0_SA_DQ11':'(0,0,0,0,0,0,0,N68,0,0,0,0,0,0,0,0,0,0,0,0,0,0,0,0,0,0,0,0,0~
,0,0,0,0,0,0,0,0,0,0,0,0,0)';$S;BIDI;
    'DDR0_SA_DQ10':'(0,0,0,0,0,0,0,M69,0,0,0,0,0,0,0,0,0,0,0,0,0,0,0,0,0,0,0,0,0~
,0,0,0,0,0,0,0,0,0,0,0,0,0)';$S;BIDI;
    'DDR0_SA_DQ9':'(0,0,0,0,0,0,0,J68,0,0,0,0,0,0,0,0,0,0,0,0,0,0,0,0,0,0,0,0,0,~
0,0,0,0,0,0,0,0,0,0,0,0,0)';$S;BIDI;
    'DDR0_SA_DQ8':'(0,0,0,0,0,0,0,K69,0,0,0,0,0,0,0,0,0,0,0,0,0,0,0,0,0,0,0,0,0,~
0,0,0,0,0,0,0,0,0,0,0,0,0)';$S;BIDI;
    'DDR0_SA_DQ7':'(0,0,0,0,0,0,0,F75,0,0,0,0,0,0,0,0,0,0,0,0,0,0,0,0,0,0,0,0,0,~
0,0,0,0,0,0,0,0,0,0,0,0,0)';$S;BIDI;
    'DDR0_SA_DQ6':'(0,0,0,0,0,0,0,G76,0,0,0,0,0,0,0,0,0,0,0,0,0,0,0,0,0,0,0,0,0,~
0,0,0,0,0,0,0,0,0,0,0,0,0)';$S;BIDI;
    'DDR0_SA_DQ5':'(0,0,0,0,0,0,0,D75,0,0,0,0,0,0,0,0,0,0,0,0,0,0,0,0,0,0,0,0,0,~
0,0,0,0,0,0,0,0,0,0,0,0,0)';$S;BIDI;
    'DDR0_SA_DQ4':'(0,0,0,0,0,0,0,C76,0,0,0,0,0,0,0,0,0,0,0,0,0,0,0,0,0,0,0,0,0,~
0,0,0,0,0,0,0,0,0,0,0,0,0)';$S;BIDI;
    'DDR0_SA_DQ3':'(0,0,0,0,0,0,0,G78,0,0,0,0,0,0,0,0,0,0,0,0,0,0,0,0,0,0,0,0,0,~
0,0,0,0,0,0,0,0,0,0,0,0,0)';$S;BIDI;
    'DDR0_SA_DQ2':'(0,0,0,0,0,0,0,M77,0,0,0,0,0,0,0,0,0,0,0,0,0,0,0,0,0,0,0,0,0,~
0,0,0,0,0,0,0,0,0,0,0,0,0)';$S;BIDI;
    'DDR0_SA_DQ1':'(0,0,0,0,0,0,0,B79,0,0,0,0,0,0,0,0,0,0,0,0,0,0,0,0,0,0,0,0,0,~
0,0,0,0,0,0,0,0,0,0,0,0,0)';$S;BIDI;
    'DDR0_SA_DQ0':'(0,0,0,0,0,0,0,B81,0,0,0,0,0,0,0,0,0,0,0,0,0,0,0,0,0,0,0,0,0,~
0,0,0,0,0,0,0,0,0,0,0,0,0)';$S;BIDI;
    'DDR0_SA_DQS_DN9':'(0,0,0,0,0,0,0,G58,0,0,0,0,0,0,0,0,0,0,0,0,0,0,0,0,0,0,0,~
0,0,0,0,0,0,0,0,0,0,0,0,0,0,0)';$S;BIDI;
    'DDR0_SA_DQS_DN8':'(0,0,0,0,0,0,0,G64,0,0,0,0,0,0,0,0,0,0,0,0,0,0,0,0,0,0,0,~
0,0,0,0,0,0,0,0,0,0,0,0,0,0,0)';$S;BIDI;
    'DDR0_SA_DQS_DN7':'(0,0,0,0,0,0,0,G70,0,0,0,0,0,0,0,0,0,0,0,0,0,0,0,0,0,0,0,~
0,0,0,0,0,0,0,0,0,0,0,0,0,0,0)';$S;BIDI;
    'DDR0_SA_DQS_DN6':'(0,0,0,0,0,0,0,P67,0,0,0,0,0,0,0,0,0,0,0,0,0,0,0,0,0,0,0,~
0,0,0,0,0,0,0,0,0,0,0,0,0,0,0)';$S;BIDI;
    'DDR0_SA_DQS_DN5':'(0,0,0,0,0,0,0,H77,0,0,0,0,0,0,0,0,0,0,0,0,0,0,0,0,0,0,0,~
0,0,0,0,0,0,0,0,0,0,0,0,0,0,0)';$S;BIDI;
    'DDR0_SA_DQS_DN4':'(0,0,0,0,0,0,0,A58,0,0,0,0,0,0,0,0,0,0,0,0,0,0,0,0,0,0,0,~
0,0,0,0,0,0,0,0,0,0,0,0,0,0,0)';$S;BIDI;
    'DDR0_SA_DQS_DN3':'(0,0,0,0,0,0,0,A64,0,0,0,0,0,0,0,0,0,0,0,0,0,0,0,0,0,0,0,~
0,0,0,0,0,0,0,0,0,0,0,0,0,0,0)';$S;BIDI;
    'DDR0_SA_DQS_DN2':'(0,0,0,0,0,0,0,B71,0,0,0,0,0,0,0,0,0,0,0,0,0,0,0,0,0,0,0,~
0,0,0,0,0,0,0,0,0,0,0,0,0,0,0)';$S;BIDI;
    'DDR0_SA_DQS_DN1':'(0,0,0,0,0,0,0,H67,0,0,0,0,0,0,0,0,0,0,0,0,0,0,0,0,0,0,0,~
0,0,0,0,0,0,0,0,0,0,0,0,0,0,0)';$S;BIDI;
    'DDR0_SA_DQS_DN0':'(0,0,0,0,0,0,0,B77,0,0,0,0,0,0,0,0,0,0,0,0,0,0,0,0,0,0,0,~
0,0,0,0,0,0,0,0,0,0,0,0,0,0,0)';$S;BIDI;
    'DDR0_SA_DQS_DP9':'(0,0,0,0,0,0,0,E58,0,0,0,0,0,0,0,0,0,0,0,0,0,0,0,0,0,0,0,~
0,0,0,0,0,0,0,0,0,0,0,0,0,0,0)';$S;BIDI;
    'DDR0_SA_DQS_DP8':'(0,0,0,0,0,0,0,E64,0,0,0,0,0,0,0,0,0,0,0,0,0,0,0,0,0,0,0,~
0,0,0,0,0,0,0,0,0,0,0,0,0,0,0)';$S;BIDI;
    'DDR0_SA_DQS_DP7':'(0,0,0,0,0,0,0,E70,0,0,0,0,0,0,0,0,0,0,0,0,0,0,0,0,0,0,0,~
0,0,0,0,0,0,0,0,0,0,0,0,0,0,0)';$S;BIDI;
    'DDR0_SA_DQS_DP6':'(0,0,0,0,0,0,0,M67,0,0,0,0,0,0,0,0,0,0,0,0,0,0,0,0,0,0,0,~
0,0,0,0,0,0,0,0,0,0,0,0,0,0,0)';$S;BIDI;
    'DDR0_SA_DQS_DP5':'(0,0,0,0,0,0,0,F77,0,0,0,0,0,0,0,0,0,0,0,0,0,0,0,0,0,0,0,~
0,0,0,0,0,0,0,0,0,0,0,0,0,0,0)';$S;BIDI;
    'DDR0_SA_DQS_DP4':'(0,0,0,0,0,0,0,C58,0,0,0,0,0,0,0,0,0,0,0,0,0,0,0,0,0,0,0,~
0,0,0,0,0,0,0,0,0,0,0,0,0,0,0)';$S;BIDI;
    'DDR0_SA_DQS_DP3':'(0,0,0,0,0,0,0,C64,0,0,0,0,0,0,0,0,0,0,0,0,0,0,0,0,0,0,0,~
0,0,0,0,0,0,0,0,0,0,0,0,0,0,0)';$S;BIDI;
    'DDR0_SA_DQS_DP2':'(0,0,0,0,0,0,0,C70,0,0,0,0,0,0,0,0,0,0,0,0,0,0,0,0,0,0,0,~
0,0,0,0,0,0,0,0,0,0,0,0,0,0,0)';$S;BIDI;
    'DDR0_SA_DQS_DP1':'(0,0,0,0,0,0,0,K67,0,0,0,0,0,0,0,0,0,0,0,0,0,0,0,0,0,0,0,~
0,0,0,0,0,0,0,0,0,0,0,0,0,0,0)';$S;BIDI;
    'DDR0_SA_DQS_DP0':'(0,0,0,0,0,0,0,D77,0,0,0,0,0,0,0,0,0,0,0,0,0,0,0,0,0,0,0,~
0,0,0,0,0,0,0,0,0,0,0,0,0,0,0)';$S;BIDI;
    'DDR0_SA_ECC7':'(0,0,0,0,0,0,0,E56,0,0,0,0,0,0,0,0,0,0,0,0,0,0,0,0,0,0,0,0,0~
,0,0,0,0,0,0,0,0,0,0,0,0,0)';$S;BIDI;
    'DDR0_SA_ECC6':'(0,0,0,0,0,0,0,F57,0,0,0,0,0,0,0,0,0,0,0,0,0,0,0,0,0,0,0,0,0~
,0,0,0,0,0,0,0,0,0,0,0,0,0)';$S;BIDI;
    'DDR0_SA_ECC5':'(0,0,0,0,0,0,0,C56,0,0,0,0,0,0,0,0,0,0,0,0,0,0,0,0,0,0,0,0,0~
,0,0,0,0,0,0,0,0,0,0,0,0,0)';$S;BIDI;
    'DDR0_SA_ECC4':'(0,0,0,0,0,0,0,B57,0,0,0,0,0,0,0,0,0,0,0,0,0,0,0,0,0,0,0,0,0~
,0,0,0,0,0,0,0,0,0,0,0,0,0)';$S;BIDI;
    'DDR0_SA_ECC3':'(0,0,0,0,0,0,0,F59,0,0,0,0,0,0,0,0,0,0,0,0,0,0,0,0,0,0,0,0,0~
,0,0,0,0,0,0,0,0,0,0,0,0,0)';$S;BIDI;
    'DDR0_SA_ECC2':'(0,0,0,0,0,0,0,E60,0,0,0,0,0,0,0,0,0,0,0,0,0,0,0,0,0,0,0,0,0~
,0,0,0,0,0,0,0,0,0,0,0,0,0)';$S;BIDI;
    'DDR0_SA_ECC1':'(0,0,0,0,0,0,0,B59,0,0,0,0,0,0,0,0,0,0,0,0,0,0,0,0,0,0,0,0,0~
,0,0,0,0,0,0,0,0,0,0,0,0,0)';$S;BIDI;
    'DDR0_SA_ECC0':'(0,0,0,0,0,0,0,C60,0,0,0,0,0,0,0,0,0,0,0,0,0,0,0,0,0,0,0,0,0~
,0,0,0,0,0,0,0,0,0,0,0,0,0)';$S;BIDI;
    'DDR0_SA_PAR':'(0,0,0,0,0,0,0,E48,0,0,0,0,0,0,0,0,0,0,0,0,0,0,0,0,0,0,0,0,0,~
0,0,0,0,0,0,0,0,0,0,0,0,0)';$S;OUT;
    'DDR0_SB_CA6':'(0,0,0,0,0,0,0,A39,0,0,0,0,0,0,0,0,0,0,0,0,0,0,0,0,0,0,0,0,0,~
0,0,0,0,0,0,0,0,0,0,0,0,0)';$S;OUT;
    'DDR0_SB_CA5':'(0,0,0,0,0,0,0,F40,0,0,0,0,0,0,0,0,0,0,0,0,0,0,0,0,0,0,0,0,0,~
0,0,0,0,0,0,0,0,0,0,0,0,0)';$S;OUT;
    'DDR0_SB_CA4':'(0,0,0,0,0,0,0,B40,0,0,0,0,0,0,0,0,0,0,0,0,0,0,0,0,0,0,0,0,0,~
0,0,0,0,0,0,0,0,0,0,0,0,0)';$S;OUT;
    'DDR0_SB_CA3':'(0,0,0,0,0,0,0,E41,0,0,0,0,0,0,0,0,0,0,0,0,0,0,0,0,0,0,0,0,0,~
0,0,0,0,0,0,0,0,0,0,0,0,0)';$S;OUT;
    'DDR0_SB_CA2':'(0,0,0,0,0,0,0,C41,0,0,0,0,0,0,0,0,0,0,0,0,0,0,0,0,0,0,0,0,0,~
0,0,0,0,0,0,0,0,0,0,0,0,0)';$S;OUT;
    'DDR0_SB_CA1':'(0,0,0,0,0,0,0,F44,0,0,0,0,0,0,0,0,0,0,0,0,0,0,0,0,0,0,0,0,0,~
0,0,0,0,0,0,0,0,0,0,0,0,0)';$S;OUT;
    'DDR0_SB_CA0':'(0,0,0,0,0,0,0,E43,0,0,0,0,0,0,0,0,0,0,0,0,0,0,0,0,0,0,0,0,0,~
0,0,0,0,0,0,0,0,0,0,0,0,0)';$S;OUT;
    'DDR0_SB_CS_N3':'(0,0,0,0,0,0,0,E37,0,0,0,0,0,0,0,0,0,0,0,0,0,0,0,0,0,0,0,0,~
0,0,0,0,0,0,0,0,0,0,0,0,0,0)';$S;OUT;
    'DDR0_SB_CS_N2':'(0,0,0,0,0,0,0,F38,0,0,0,0,0,0,0,0,0,0,0,0,0,0,0,0,0,0,0,0,~
0,0,0,0,0,0,0,0,0,0,0,0,0,0)';$S;OUT;
    'DDR0_SB_CS_N1':'(0,0,0,0,0,0,0,C37,0,0,0,0,0,0,0,0,0,0,0,0,0,0,0,0,0,0,0,0,~
0,0,0,0,0,0,0,0,0,0,0,0,0,0)';$S;OUT;
    'DDR0_SB_CS_N0':'(0,0,0,0,0,0,0,B38,0,0,0,0,0,0,0,0,0,0,0,0,0,0,0,0,0,0,0,0,~
0,0,0,0,0,0,0,0,0,0,0,0,0,0)';$S;OUT;
    'DDR0_SB_DQ31':'(0,0,0,0,0,0,0,E7,0,0,0,0,0,0,0,0,0,0,0,0,0,0,0,0,0,0,0,0,0,~
0,0,0,0,0,0,0,0,0,0,0,0,0)';$S;BIDI;
    'DDR0_SB_DQ30':'(0,0,0,0,0,0,0,F8,0,0,0,0,0,0,0,0,0,0,0,0,0,0,0,0,0,0,0,0,0,~
0,0,0,0,0,0,0,0,0,0,0,0,0)';$S;BIDI;
    'DDR0_SB_DQ29':'(0,0,0,0,0,0,0,C7,0,0,0,0,0,0,0,0,0,0,0,0,0,0,0,0,0,0,0,0,0,~
0,0,0,0,0,0,0,0,0,0,0,0,0)';$S;BIDI;
    'DDR0_SB_DQ28':'(0,0,0,0,0,0,0,B8,0,0,0,0,0,0,0,0,0,0,0,0,0,0,0,0,0,0,0,0,0,~
0,0,0,0,0,0,0,0,0,0,0,0,0)';$S;BIDI;
    'DDR0_SB_DQ27':'(0,0,0,0,0,0,0,F10,0,0,0,0,0,0,0,0,0,0,0,0,0,0,0,0,0,0,0,0,0~
,0,0,0,0,0,0,0,0,0,0,0,0,0)';$S;BIDI;
    'DDR0_SB_DQ26':'(0,0,0,0,0,0,0,E11,0,0,0,0,0,0,0,0,0,0,0,0,0,0,0,0,0,0,0,0,0~
,0,0,0,0,0,0,0,0,0,0,0,0,0)';$S;BIDI;
    'DDR0_SB_DQ25':'(0,0,0,0,0,0,0,B10,0,0,0,0,0,0,0,0,0,0,0,0,0,0,0,0,0,0,0,0,0~
,0,0,0,0,0,0,0,0,0,0,0,0,0)';$S;BIDI;
    'DDR0_SB_DQ24':'(0,0,0,0,0,0,0,C11,0,0,0,0,0,0,0,0,0,0,0,0,0,0,0,0,0,0,0,0,0~
,0,0,0,0,0,0,0,0,0,0,0,0,0)';$S;BIDI;
    'DDR0_SB_DQ23':'(0,0,0,0,0,0,0,E19,0,0,0,0,0,0,0,0,0,0,0,0,0,0,0,0,0,0,0,0,0~
,0,0,0,0,0,0,0,0,0,0,0,0,0)';$S;BIDI;
    'DDR0_SB_DQ22':'(0,0,0,0,0,0,0,F20,0,0,0,0,0,0,0,0,0,0,0,0,0,0,0,0,0,0,0,0,0~
,0,0,0,0,0,0,0,0,0,0,0,0,0)';$S;BIDI;
    'DDR0_SB_DQ21':'(0,0,0,0,0,0,0,C19,0,0,0,0,0,0,0,0,0,0,0,0,0,0,0,0,0,0,0,0,0~
,0,0,0,0,0,0,0,0,0,0,0,0,0)';$S;BIDI;
    'DDR0_SB_DQ20':'(0,0,0,0,0,0,0,B20,0,0,0,0,0,0,0,0,0,0,0,0,0,0,0,0,0,0,0,0,0~
,0,0,0,0,0,0,0,0,0,0,0,0,0)';$S;BIDI;
    'DDR0_SB_DQ19':'(0,0,0,0,0,0,0,F22,0,0,0,0,0,0,0,0,0,0,0,0,0,0,0,0,0,0,0,0,0~
,0,0,0,0,0,0,0,0,0,0,0,0,0)';$S;BIDI;
    'DDR0_SB_DQ18':'(0,0,0,0,0,0,0,E23,0,0,0,0,0,0,0,0,0,0,0,0,0,0,0,0,0,0,0,0,0~
,0,0,0,0,0,0,0,0,0,0,0,0,0)';$S;BIDI;
    'DDR0_SB_DQ17':'(0,0,0,0,0,0,0,B22,0,0,0,0,0,0,0,0,0,0,0,0,0,0,0,0,0,0,0,0,0~
,0,0,0,0,0,0,0,0,0,0,0,0,0)';$S;BIDI;
    'DDR0_SB_DQ16':'(0,0,0,0,0,0,0,C23,0,0,0,0,0,0,0,0,0,0,0,0,0,0,0,0,0,0,0,0,0~
,0,0,0,0,0,0,0,0,0,0,0,0,0)';$S;BIDI;
    'DDR0_SB_DQ15':'(0,0,0,0,0,0,0,E25,0,0,0,0,0,0,0,0,0,0,0,0,0,0,0,0,0,0,0,0,0~
,0,0,0,0,0,0,0,0,0,0,0,0,0)';$S;BIDI;
    'DDR0_SB_DQ14':'(0,0,0,0,0,0,0,F26,0,0,0,0,0,0,0,0,0,0,0,0,0,0,0,0,0,0,0,0,0~
,0,0,0,0,0,0,0,0,0,0,0,0,0)';$S;BIDI;
    'DDR0_SB_DQ13':'(0,0,0,0,0,0,0,C25,0,0,0,0,0,0,0,0,0,0,0,0,0,0,0,0,0,0,0,0,0~
,0,0,0,0,0,0,0,0,0,0,0,0,0)';$S;BIDI;
    'DDR0_SB_DQ12':'(0,0,0,0,0,0,0,B26,0,0,0,0,0,0,0,0,0,0,0,0,0,0,0,0,0,0,0,0,0~
,0,0,0,0,0,0,0,0,0,0,0,0,0)';$S;BIDI;
    'DDR0_SB_DQ11':'(0,0,0,0,0,0,0,F28,0,0,0,0,0,0,0,0,0,0,0,0,0,0,0,0,0,0,0,0,0~
,0,0,0,0,0,0,0,0,0,0,0,0,0)';$S;BIDI;
    'DDR0_SB_DQ10':'(0,0,0,0,0,0,0,E29,0,0,0,0,0,0,0,0,0,0,0,0,0,0,0,0,0,0,0,0,0~
,0,0,0,0,0,0,0,0,0,0,0,0,0)';$S;BIDI;
    'DDR0_SB_DQ9':'(0,0,0,0,0,0,0,B28,0,0,0,0,0,0,0,0,0,0,0,0,0,0,0,0,0,0,0,0,0,~
0,0,0,0,0,0,0,0,0,0,0,0,0)';$S;BIDI;
    'DDR0_SB_DQ8':'(0,0,0,0,0,0,0,C29,0,0,0,0,0,0,0,0,0,0,0,0,0,0,0,0,0,0,0,0,0,~
0,0,0,0,0,0,0,0,0,0,0,0,0)';$S;BIDI;
    'DDR0_SB_DQ7':'(0,0,0,0,0,0,0,M28,0,0,0,0,0,0,0,0,0,0,0,0,0,0,0,0,0,0,0,0,0,~
0,0,0,0,0,0,0,0,0,0,0,0,0)';$S;BIDI;
    'DDR0_SB_DQ6':'(0,0,0,0,0,0,0,N29,0,0,0,0,0,0,0,0,0,0,0,0,0,0,0,0,0,0,0,0,0,~
0,0,0,0,0,0,0,0,0,0,0,0,0)';$S;BIDI;
    'DDR0_SB_DQ5':'(0,0,0,0,0,0,0,K28,0,0,0,0,0,0,0,0,0,0,0,0,0,0,0,0,0,0,0,0,0,~
0,0,0,0,0,0,0,0,0,0,0,0,0)';$S;BIDI;
    'DDR0_SB_DQ4':'(0,0,0,0,0,0,0,J29,0,0,0,0,0,0,0,0,0,0,0,0,0,0,0,0,0,0,0,0,0,~
0,0,0,0,0,0,0,0,0,0,0,0,0)';$S;BIDI;
    'DDR0_SB_DQ3':'(0,0,0,0,0,0,0,N31,0,0,0,0,0,0,0,0,0,0,0,0,0,0,0,0,0,0,0,0,0,~
0,0,0,0,0,0,0,0,0,0,0,0,0)';$S;BIDI;
    'DDR0_SB_DQ2':'(0,0,0,0,0,0,0,M32,0,0,0,0,0,0,0,0,0,0,0,0,0,0,0,0,0,0,0,0,0,~
0,0,0,0,0,0,0,0,0,0,0,0,0)';$S;BIDI;
    'DDR0_SB_DQ1':'(0,0,0,0,0,0,0,J31,0,0,0,0,0,0,0,0,0,0,0,0,0,0,0,0,0,0,0,0,0,~
0,0,0,0,0,0,0,0,0,0,0,0,0)';$S;BIDI;
    'DDR0_SB_DQ0':'(0,0,0,0,0,0,0,K32,0,0,0,0,0,0,0,0,0,0,0,0,0,0,0,0,0,0,0,0,0,~
0,0,0,0,0,0,0,0,0,0,0,0,0)';$S;BIDI;
    'DDR0_SB_DQS_DN9':'(0,0,0,0,0,0,0,A33,0,0,0,0,0,0,0,0,0,0,0,0,0,0,0,0,0,0,0,~
0,0,0,0,0,0,0,0,0,0,0,0,0,0,0)';$S;BIDI;
    'DDR0_SB_DQS_DN8':'(0,0,0,0,0,0,0,G9,0,0,0,0,0,0,0,0,0,0,0,0,0,0,0,0,0,0,0,0~
,0,0,0,0,0,0,0,0,0,0,0,0,0,0)';$S;BIDI;
    'DDR0_SB_DQS_DN7':'(0,0,0,0,0,0,0,G21,0,0,0,0,0,0,0,0,0,0,0,0,0,0,0,0,0,0,0,~
0,0,0,0,0,0,0,0,0,0,0,0,0,0,0)';$S;BIDI;
    'DDR0_SB_DQS_DN6':'(0,0,0,0,0,0,0,G27,0,0,0,0,0,0,0,0,0,0,0,0,0,0,0,0,0,0,0,~
0,0,0,0,0,0,0,0,0,0,0,0,0,0,0)';$S;BIDI;
    'DDR0_SB_DQS_DN5':'(0,0,0,0,0,0,0,M30,0,0,0,0,0,0,0,0,0,0,0,0,0,0,0,0,0,0,0,~
0,0,0,0,0,0,0,0,0,0,0,0,0,0,0)';$S;BIDI;
    'DDR0_SB_DQS_DN4':'(0,0,0,0,0,0,0,G33,0,0,0,0,0,0,0,0,0,0,0,0,0,0,0,0,0,0,0,~
0,0,0,0,0,0,0,0,0,0,0,0,0,0,0)';$S;BIDI;
    'DDR0_SB_DQS_DN3':'(0,0,0,0,0,0,0,A9,0,0,0,0,0,0,0,0,0,0,0,0,0,0,0,0,0,0,0,0~
,0,0,0,0,0,0,0,0,0,0,0,0,0,0)';$S;BIDI;
    'DDR0_SB_DQS_DN2':'(0,0,0,0,0,0,0,A21,0,0,0,0,0,0,0,0,0,0,0,0,0,0,0,0,0,0,0,~
0,0,0,0,0,0,0,0,0,0,0,0,0,0,0)';$S;BIDI;
    'DDR0_SB_DQS_DN1':'(0,0,0,0,0,0,0,A27,0,0,0,0,0,0,0,0,0,0,0,0,0,0,0,0,0,0,0,~
0,0,0,0,0,0,0,0,0,0,0,0,0,0,0)';$S;BIDI;
    'DDR0_SB_DQS_DN0':'(0,0,0,0,0,0,0,H30,0,0,0,0,0,0,0,0,0,0,0,0,0,0,0,0,0,0,0,~
0,0,0,0,0,0,0,0,0,0,0,0,0,0,0)';$S;BIDI;
    'DDR0_SB_DQS_DP9':'(0,0,0,0,0,0,0,C33,0,0,0,0,0,0,0,0,0,0,0,0,0,0,0,0,0,0,0,~
0,0,0,0,0,0,0,0,0,0,0,0,0,0,0)';$S;BIDI;
    'DDR0_SB_DQS_DP8':'(0,0,0,0,0,0,0,E9,0,0,0,0,0,0,0,0,0,0,0,0,0,0,0,0,0,0,0,0~
,0,0,0,0,0,0,0,0,0,0,0,0,0,0)';$S;BIDI;
    'DDR0_SB_DQS_DP7':'(0,0,0,0,0,0,0,E21,0,0,0,0,0,0,0,0,0,0,0,0,0,0,0,0,0,0,0,~
0,0,0,0,0,0,0,0,0,0,0,0,0,0,0)';$S;BIDI;
    'DDR0_SB_DQS_DP6':'(0,0,0,0,0,0,0,E27,0,0,0,0,0,0,0,0,0,0,0,0,0,0,0,0,0,0,0,~
0,0,0,0,0,0,0,0,0,0,0,0,0,0,0)';$S;BIDI;
    'DDR0_SB_DQS_DP5':'(0,0,0,0,0,0,0,P30,0,0,0,0,0,0,0,0,0,0,0,0,0,0,0,0,0,0,0,~
0,0,0,0,0,0,0,0,0,0,0,0,0,0,0)';$S;BIDI;
    'DDR0_SB_DQS_DP4':'(0,0,0,0,0,0,0,E33,0,0,0,0,0,0,0,0,0,0,0,0,0,0,0,0,0,0,0,~
0,0,0,0,0,0,0,0,0,0,0,0,0,0,0)';$S;BIDI;
    'DDR0_SB_DQS_DP3':'(0,0,0,0,0,0,0,C9,0,0,0,0,0,0,0,0,0,0,0,0,0,0,0,0,0,0,0,0~
,0,0,0,0,0,0,0,0,0,0,0,0,0,0)';$S;BIDI;
    'DDR0_SB_DQS_DP2':'(0,0,0,0,0,0,0,C21,0,0,0,0,0,0,0,0,0,0,0,0,0,0,0,0,0,0,0,~
0,0,0,0,0,0,0,0,0,0,0,0,0,0,0)';$S;BIDI;
    'DDR0_SB_DQS_DP1':'(0,0,0,0,0,0,0,C27,0,0,0,0,0,0,0,0,0,0,0,0,0,0,0,0,0,0,0,~
0,0,0,0,0,0,0,0,0,0,0,0,0,0,0)';$S;BIDI;
    'DDR0_SB_DQS_DP0':'(0,0,0,0,0,0,0,K30,0,0,0,0,0,0,0,0,0,0,0,0,0,0,0,0,0,0,0,~
0,0,0,0,0,0,0,0,0,0,0,0,0,0,0)';$S;BIDI;
    'DDR0_SB_ECC7':'(0,0,0,0,0,0,0,F34,0,0,0,0,0,0,0,0,0,0,0,0,0,0,0,0,0,0,0,0,0~
,0,0,0,0,0,0,0,0,0,0,0,0,0)';$S;BIDI;
    'DDR0_SB_ECC6':'(0,0,0,0,0,0,0,E35,0,0,0,0,0,0,0,0,0,0,0,0,0,0,0,0,0,0,0,0,0~
,0,0,0,0,0,0,0,0,0,0,0,0,0)';$S;BIDI;
    'DDR0_SB_ECC5':'(0,0,0,0,0,0,0,B34,0,0,0,0,0,0,0,0,0,0,0,0,0,0,0,0,0,0,0,0,0~
,0,0,0,0,0,0,0,0,0,0,0,0,0)';$S;BIDI;
    'DDR0_SB_ECC4':'(0,0,0,0,0,0,0,C35,0,0,0,0,0,0,0,0,0,0,0,0,0,0,0,0,0,0,0,0,0~
,0,0,0,0,0,0,0,0,0,0,0,0,0)';$S;BIDI;
    'DDR0_SB_ECC3':'(0,0,0,0,0,0,0,E31,0,0,0,0,0,0,0,0,0,0,0,0,0,0,0,0,0,0,0,0,0~
,0,0,0,0,0,0,0,0,0,0,0,0,0)';$S;BIDI;
    'DDR0_SB_ECC2':'(0,0,0,0,0,0,0,F32,0,0,0,0,0,0,0,0,0,0,0,0,0,0,0,0,0,0,0,0,0~
,0,0,0,0,0,0,0,0,0,0,0,0,0)';$S;BIDI;
    'DDR0_SB_ECC1':'(0,0,0,0,0,0,0,C31,0,0,0,0,0,0,0,0,0,0,0,0,0,0,0,0,0,0,0,0,0~
,0,0,0,0,0,0,0,0,0,0,0,0,0)';$S;BIDI;
    'DDR0_SB_ECC0':'(0,0,0,0,0,0,0,B32,0,0,0,0,0,0,0,0,0,0,0,0,0,0,0,0,0,0,0,0,0~
,0,0,0,0,0,0,0,0,0,0,0,0,0)';$S;BIDI;
    'DDR0_SB_PAR':'(0,0,0,0,0,0,0,G39,0,0,0,0,0,0,0,0,0,0,0,0,0,0,0,0,0,0,0,0,0,~
0,0,0,0,0,0,0,0,0,0,0,0,0)';$S;OUT;
    'DDR1_ALERT_N':'(0,0,0,0,0,0,0,0,AV49,0,0,0,0,0,0,0,0,0,0,0,0,0,0,0,0,0,0,0,~
0,0,0,0,0,0,0,0,0,0,0,0,0,0)';$S;IN;
    'DDR1_A_RSP1':'(0,0,0,0,0,0,0,0,AK47,0,0,0,0,0,0,0,0,0,0,0,0,0,0,0,0,0,0,0,0~
,0,0,0,0,0,0,0,0,0,0,0,0,0)';$S;IN;
    'DDR1_A_RSP0':'(0,0,0,0,0,0,0,0,AL48,0,0,0,0,0,0,0,0,0,0,0,0,0,0,0,0,0,0,0,0~
,0,0,0,0,0,0,0,0,0,0,0,0,0)';$S;IN;
    'DDR1_B_RSP1':'(0,0,0,0,0,0,0,0,AP47,0,0,0,0,0,0,0,0,0,0,0,0,0,0,0,0,0,0,0,0~
,0,0,0,0,0,0,0,0,0,0,0,0,0)';$S;IN;
    'DDR1_B_RSP0':'(0,0,0,0,0,0,0,0,AN48,0,0,0,0,0,0,0,0,0,0,0,0,0,0,0,0,0,0,0,0~
,0,0,0,0,0,0,0,0,0,0,0,0,0)';$S;IN;
    'DDR1_CLK_DN1':'(0,0,0,0,0,0,0,0,W45,0,0,0,0,0,0,0,0,0,0,0,0,0,0,0,0,0,0,0,0~
,0,0,0,0,0,0,0,0,0,0,0,0,0)';$S;OUT;
    'DDR1_CLK_DN0':'(0,0,0,0,0,0,0,0,R45,0,0,0,0,0,0,0,0,0,0,0,0,0,0,0,0,0,0,0,0~
,0,0,0,0,0,0,0,0,0,0,0,0,0)';$S;OUT;
    'DDR1_CLK_DP1':'(0,0,0,0,0,0,0,0,AA45,0,0,0,0,0,0,0,0,0,0,0,0,0,0,0,0,0,0,0,~
0,0,0,0,0,0,0,0,0,0,0,0,0,0)';$S;OUT;
    'DDR1_CLK_DP0':'(0,0,0,0,0,0,0,0,U45,0,0,0,0,0,0,0,0,0,0,0,0,0,0,0,0,0,0,0,0~
,0,0,0,0,0,0,0,0,0,0,0,0,0)';$S;OUT;
    'DDR1_SA_CA6':'(0,0,0,0,0,0,0,0,Y44,0,0,0,0,0,0,0,0,0,0,0,0,0,0,0,0,0,0,0,0,~
0,0,0,0,0,0,0,0,0,0,0,0,0)';$S;OUT;
    'DDR1_SA_CA5':'(0,0,0,0,0,0,0,0,M47,0,0,0,0,0,0,0,0,0,0,0,0,0,0,0,0,0,0,0,0,~
0,0,0,0,0,0,0,0,0,0,0,0,0)';$S;OUT;
    'DDR1_SA_CA4':'(0,0,0,0,0,0,0,0,K47,0,0,0,0,0,0,0,0,0,0,0,0,0,0,0,0,0,0,0,0,~
0,0,0,0,0,0,0,0,0,0,0,0,0)';$S;OUT;
    'DDR1_SA_CA3':'(0,0,0,0,0,0,0,0,N48,0,0,0,0,0,0,0,0,0,0,0,0,0,0,0,0,0,0,0,0,~
0,0,0,0,0,0,0,0,0,0,0,0,0)';$S;OUT;
    'DDR1_SA_CA2':'(0,0,0,0,0,0,0,0,J48,0,0,0,0,0,0,0,0,0,0,0,0,0,0,0,0,0,0,0,0,~
0,0,0,0,0,0,0,0,0,0,0,0,0)';$S;OUT;
    'DDR1_SA_CA1':'(0,0,0,0,0,0,0,0,P49,0,0,0,0,0,0,0,0,0,0,0,0,0,0,0,0,0,0,0,0,~
0,0,0,0,0,0,0,0,0,0,0,0,0)';$S;OUT;
    'DDR1_SA_CA0':'(0,0,0,0,0,0,0,0,H49,0,0,0,0,0,0,0,0,0,0,0,0,0,0,0,0,0,0,0,0,~
0,0,0,0,0,0,0,0,0,0,0,0,0)';$S;OUT;
    'DDR1_SA_CS_N3':'(0,0,0,0,0,0,0,0,N50,0,0,0,0,0,0,0,0,0,0,0,0,0,0,0,0,0,0,0,~
0,0,0,0,0,0,0,0,0,0,0,0,0,0)';$S;OUT;
    'DDR1_SA_CS_N2':'(0,0,0,0,0,0,0,0,M51,0,0,0,0,0,0,0,0,0,0,0,0,0,0,0,0,0,0,0,~
0,0,0,0,0,0,0,0,0,0,0,0,0,0)';$S;OUT;
    'DDR1_SA_CS_N1':'(0,0,0,0,0,0,0,0,J50,0,0,0,0,0,0,0,0,0,0,0,0,0,0,0,0,0,0,0,~
0,0,0,0,0,0,0,0,0,0,0,0,0,0)';$S;OUT;
    'DDR1_SA_CS_N0':'(0,0,0,0,0,0,0,0,K51,0,0,0,0,0,0,0,0,0,0,0,0,0,0,0,0,0,0,0,~
0,0,0,0,0,0,0,0,0,0,0,0,0,0)';$S;OUT;
    'DDR1_SA_DQ31':'(0,0,0,0,0,0,0,0,W56,0,0,0,0,0,0,0,0,0,0,0,0,0,0,0,0,0,0,0,0~
,0,0,0,0,0,0,0,0,0,0,0,0,0)';$S;BIDI;
    'DDR1_SA_DQ30':'(0,0,0,0,0,0,0,0,Y57,0,0,0,0,0,0,0,0,0,0,0,0,0,0,0,0,0,0,0,0~
,0,0,0,0,0,0,0,0,0,0,0,0,0)';$S;BIDI;
    'DDR1_SA_DQ29':'(0,0,0,0,0,0,0,0,U56,0,0,0,0,0,0,0,0,0,0,0,0,0,0,0,0,0,0,0,0~
,0,0,0,0,0,0,0,0,0,0,0,0,0)';$S;BIDI;
    'DDR1_SA_DQ28':'(0,0,0,0,0,0,0,0,T57,0,0,0,0,0,0,0,0,0,0,0,0,0,0,0,0,0,0,0,0~
,0,0,0,0,0,0,0,0,0,0,0,0,0)';$S;BIDI;
    'DDR1_SA_DQ27':'(0,0,0,0,0,0,0,0,Y59,0,0,0,0,0,0,0,0,0,0,0,0,0,0,0,0,0,0,0,0~
,0,0,0,0,0,0,0,0,0,0,0,0,0)';$S;BIDI;
    'DDR1_SA_DQ26':'(0,0,0,0,0,0,0,0,W60,0,0,0,0,0,0,0,0,0,0,0,0,0,0,0,0,0,0,0,0~
,0,0,0,0,0,0,0,0,0,0,0,0,0)';$S;BIDI;
    'DDR1_SA_DQ25':'(0,0,0,0,0,0,0,0,T59,0,0,0,0,0,0,0,0,0,0,0,0,0,0,0,0,0,0,0,0~
,0,0,0,0,0,0,0,0,0,0,0,0,0)';$S;BIDI;
    'DDR1_SA_DQ24':'(0,0,0,0,0,0,0,0,U60,0,0,0,0,0,0,0,0,0,0,0,0,0,0,0,0,0,0,0,0~
,0,0,0,0,0,0,0,0,0,0,0,0,0)';$S;BIDI;
    'DDR1_SA_DQ23':'(0,0,0,0,0,0,0,0,M59,0,0,0,0,0,0,0,0,0,0,0,0,0,0,0,0,0,0,0,0~
,0,0,0,0,0,0,0,0,0,0,0,0,0)';$S;BIDI;
    'DDR1_SA_DQ22':'(0,0,0,0,0,0,0,0,N60,0,0,0,0,0,0,0,0,0,0,0,0,0,0,0,0,0,0,0,0~
,0,0,0,0,0,0,0,0,0,0,0,0,0)';$S;BIDI;
    'DDR1_SA_DQ21':'(0,0,0,0,0,0,0,0,K59,0,0,0,0,0,0,0,0,0,0,0,0,0,0,0,0,0,0,0,0~
,0,0,0,0,0,0,0,0,0,0,0,0,0)';$S;BIDI;
    'DDR1_SA_DQ20':'(0,0,0,0,0,0,0,0,J60,0,0,0,0,0,0,0,0,0,0,0,0,0,0,0,0,0,0,0,0~
,0,0,0,0,0,0,0,0,0,0,0,0,0)';$S;BIDI;
    'DDR1_SA_DQ19':'(0,0,0,0,0,0,0,0,N62,0,0,0,0,0,0,0,0,0,0,0,0,0,0,0,0,0,0,0,0~
,0,0,0,0,0,0,0,0,0,0,0,0,0)';$S;BIDI;
    'DDR1_SA_DQ18':'(0,0,0,0,0,0,0,0,M63,0,0,0,0,0,0,0,0,0,0,0,0,0,0,0,0,0,0,0,0~
,0,0,0,0,0,0,0,0,0,0,0,0,0)';$S;BIDI;
    'DDR1_SA_DQ17':'(0,0,0,0,0,0,0,0,J62,0,0,0,0,0,0,0,0,0,0,0,0,0,0,0,0,0,0,0,0~
,0,0,0,0,0,0,0,0,0,0,0,0,0)';$S;BIDI;
    'DDR1_SA_DQ16':'(0,0,0,0,0,0,0,0,K63,0,0,0,0,0,0,0,0,0,0,0,0,0,0,0,0,0,0,0,0~
,0,0,0,0,0,0,0,0,0,0,0,0,0)';$S;BIDI;
    'DDR1_SA_DQ15':'(0,0,0,0,0,0,0,0,W68,0,0,0,0,0,0,0,0,0,0,0,0,0,0,0,0,0,0,0,0~
,0,0,0,0,0,0,0,0,0,0,0,0,0)';$S;BIDI;
    'DDR1_SA_DQ14':'(0,0,0,0,0,0,0,0,Y69,0,0,0,0,0,0,0,0,0,0,0,0,0,0,0,0,0,0,0,0~
,0,0,0,0,0,0,0,0,0,0,0,0,0)';$S;BIDI;
    'DDR1_SA_DQ13':'(0,0,0,0,0,0,0,0,U68,0,0,0,0,0,0,0,0,0,0,0,0,0,0,0,0,0,0,0,0~
,0,0,0,0,0,0,0,0,0,0,0,0,0)';$S;BIDI;
    'DDR1_SA_DQ12':'(0,0,0,0,0,0,0,0,T69,0,0,0,0,0,0,0,0,0,0,0,0,0,0,0,0,0,0,0,0~
,0,0,0,0,0,0,0,0,0,0,0,0,0)';$S;BIDI;
    'DDR1_SA_DQ11':'(0,0,0,0,0,0,0,0,Y71,0,0,0,0,0,0,0,0,0,0,0,0,0,0,0,0,0,0,0,0~
,0,0,0,0,0,0,0,0,0,0,0,0,0)';$S;BIDI;
    'DDR1_SA_DQ10':'(0,0,0,0,0,0,0,0,W72,0,0,0,0,0,0,0,0,0,0,0,0,0,0,0,0,0,0,0,0~
,0,0,0,0,0,0,0,0,0,0,0,0,0)';$S;BIDI;
    'DDR1_SA_DQ9':'(0,0,0,0,0,0,0,0,T71,0,0,0,0,0,0,0,0,0,0,0,0,0,0,0,0,0,0,0,0,~
0,0,0,0,0,0,0,0,0,0,0,0,0)';$S;BIDI;
    'DDR1_SA_DQ8':'(0,0,0,0,0,0,0,0,U72,0,0,0,0,0,0,0,0,0,0,0,0,0,0,0,0,0,0,0,0,~
0,0,0,0,0,0,0,0,0,0,0,0,0)';$S;BIDI;
    'DDR1_SA_DQ7':'(0,0,0,0,0,0,0,0,M71,0,0,0,0,0,0,0,0,0,0,0,0,0,0,0,0,0,0,0,0,~
0,0,0,0,0,0,0,0,0,0,0,0,0)';$S;BIDI;
    'DDR1_SA_DQ6':'(0,0,0,0,0,0,0,0,N72,0,0,0,0,0,0,0,0,0,0,0,0,0,0,0,0,0,0,0,0,~
0,0,0,0,0,0,0,0,0,0,0,0,0)';$S;BIDI;
    'DDR1_SA_DQ5':'(0,0,0,0,0,0,0,0,K71,0,0,0,0,0,0,0,0,0,0,0,0,0,0,0,0,0,0,0,0,~
0,0,0,0,0,0,0,0,0,0,0,0,0)';$S;BIDI;
    'DDR1_SA_DQ4':'(0,0,0,0,0,0,0,0,J72,0,0,0,0,0,0,0,0,0,0,0,0,0,0,0,0,0,0,0,0,~
0,0,0,0,0,0,0,0,0,0,0,0,0)';$S;BIDI;
    'DDR1_SA_DQ3':'(0,0,0,0,0,0,0,0,N74,0,0,0,0,0,0,0,0,0,0,0,0,0,0,0,0,0,0,0,0,~
0,0,0,0,0,0,0,0,0,0,0,0,0)';$S;BIDI;
    'DDR1_SA_DQ2':'(0,0,0,0,0,0,0,0,M75,0,0,0,0,0,0,0,0,0,0,0,0,0,0,0,0,0,0,0,0,~
0,0,0,0,0,0,0,0,0,0,0,0,0)';$S;BIDI;
    'DDR1_SA_DQ1':'(0,0,0,0,0,0,0,0,J74,0,0,0,0,0,0,0,0,0,0,0,0,0,0,0,0,0,0,0,0,~
0,0,0,0,0,0,0,0,0,0,0,0,0)';$S;BIDI;
    'DDR1_SA_DQ0':'(0,0,0,0,0,0,0,0,K75,0,0,0,0,0,0,0,0,0,0,0,0,0,0,0,0,0,0,0,0,~
0,0,0,0,0,0,0,0,0,0,0,0,0)';$S;BIDI;
    'DDR1_SA_DQS_DN9':'(0,0,0,0,0,0,0,0,M55,0,0,0,0,0,0,0,0,0,0,0,0,0,0,0,0,0,0,~
0,0,0,0,0,0,0,0,0,0,0,0,0,0,0)';$S;BIDI;
    'DDR1_SA_DQS_DN8':'(0,0,0,0,0,0,0,0,AA58,0,0,0,0,0,0,0,0,0,0,0,0,0,0,0,0,0,0~
,0,0,0,0,0,0,0,0,0,0,0,0,0,0,0)';$S;BIDI;
    'DDR1_SA_DQS_DN7':'(0,0,0,0,0,0,0,0,M61,0,0,0,0,0,0,0,0,0,0,0,0,0,0,0,0,0,0,~
0,0,0,0,0,0,0,0,0,0,0,0,0,0,0)';$S;BIDI;
    'DDR1_SA_DQS_DN6':'(0,0,0,0,0,0,0,0,AA70,0,0,0,0,0,0,0,0,0,0,0,0,0,0,0,0,0,0~
,0,0,0,0,0,0,0,0,0,0,0,0,0,0,0)';$S;BIDI;
    'DDR1_SA_DQS_DN5':'(0,0,0,0,0,0,0,0,M73,0,0,0,0,0,0,0,0,0,0,0,0,0,0,0,0,0,0,~
0,0,0,0,0,0,0,0,0,0,0,0,0,0,0)';$S;BIDI;
    'DDR1_SA_DQS_DN4':'(0,0,0,0,0,0,0,0,H55,0,0,0,0,0,0,0,0,0,0,0,0,0,0,0,0,0,0,~
0,0,0,0,0,0,0,0,0,0,0,0,0,0,0)';$S;BIDI;
    'DDR1_SA_DQS_DN3':'(0,0,0,0,0,0,0,0,R58,0,0,0,0,0,0,0,0,0,0,0,0,0,0,0,0,0,0,~
0,0,0,0,0,0,0,0,0,0,0,0,0,0,0)';$S;BIDI;
    'DDR1_SA_DQS_DN2':'(0,0,0,0,0,0,0,0,H61,0,0,0,0,0,0,0,0,0,0,0,0,0,0,0,0,0,0,~
0,0,0,0,0,0,0,0,0,0,0,0,0,0,0)';$S;BIDI;
    'DDR1_SA_DQS_DN1':'(0,0,0,0,0,0,0,0,R70,0,0,0,0,0,0,0,0,0,0,0,0,0,0,0,0,0,0,~
0,0,0,0,0,0,0,0,0,0,0,0,0,0,0)';$S;BIDI;
    'DDR1_SA_DQS_DN0':'(0,0,0,0,0,0,0,0,H73,0,0,0,0,0,0,0,0,0,0,0,0,0,0,0,0,0,0,~
0,0,0,0,0,0,0,0,0,0,0,0,0,0,0)';$S;BIDI;
    'DDR1_SA_DQS_DP9':'(0,0,0,0,0,0,0,0,P55,0,0,0,0,0,0,0,0,0,0,0,0,0,0,0,0,0,0,~
0,0,0,0,0,0,0,0,0,0,0,0,0,0,0)';$S;BIDI;
    'DDR1_SA_DQS_DP8':'(0,0,0,0,0,0,0,0,W58,0,0,0,0,0,0,0,0,0,0,0,0,0,0,0,0,0,0,~
0,0,0,0,0,0,0,0,0,0,0,0,0,0,0)';$S;BIDI;
    'DDR1_SA_DQS_DP7':'(0,0,0,0,0,0,0,0,P61,0,0,0,0,0,0,0,0,0,0,0,0,0,0,0,0,0,0,~
0,0,0,0,0,0,0,0,0,0,0,0,0,0,0)';$S;BIDI;
    'DDR1_SA_DQS_DP6':'(0,0,0,0,0,0,0,0,W70,0,0,0,0,0,0,0,0,0,0,0,0,0,0,0,0,0,0,~
0,0,0,0,0,0,0,0,0,0,0,0,0,0,0)';$S;BIDI;
    'DDR1_SA_DQS_DP5':'(0,0,0,0,0,0,0,0,P73,0,0,0,0,0,0,0,0,0,0,0,0,0,0,0,0,0,0,~
0,0,0,0,0,0,0,0,0,0,0,0,0,0,0)';$S;BIDI;
    'DDR1_SA_DQS_DP4':'(0,0,0,0,0,0,0,0,K55,0,0,0,0,0,0,0,0,0,0,0,0,0,0,0,0,0,0,~
0,0,0,0,0,0,0,0,0,0,0,0,0,0,0)';$S;BIDI;
    'DDR1_SA_DQS_DP3':'(0,0,0,0,0,0,0,0,U58,0,0,0,0,0,0,0,0,0,0,0,0,0,0,0,0,0,0,~
0,0,0,0,0,0,0,0,0,0,0,0,0,0,0)';$S;BIDI;
    'DDR1_SA_DQS_DP2':'(0,0,0,0,0,0,0,0,K61,0,0,0,0,0,0,0,0,0,0,0,0,0,0,0,0,0,0,~
0,0,0,0,0,0,0,0,0,0,0,0,0,0,0)';$S;BIDI;
    'DDR1_SA_DQS_DP1':'(0,0,0,0,0,0,0,0,U70,0,0,0,0,0,0,0,0,0,0,0,0,0,0,0,0,0,0,~
0,0,0,0,0,0,0,0,0,0,0,0,0,0,0)';$S;BIDI;
    'DDR1_SA_DQS_DP0':'(0,0,0,0,0,0,0,0,K73,0,0,0,0,0,0,0,0,0,0,0,0,0,0,0,0,0,0,~
0,0,0,0,0,0,0,0,0,0,0,0,0,0,0)';$S;BIDI;
    'DDR1_SA_ECC7':'(0,0,0,0,0,0,0,0,M53,0,0,0,0,0,0,0,0,0,0,0,0,0,0,0,0,0,0,0,0~
,0,0,0,0,0,0,0,0,0,0,0,0,0)';$S;BIDI;
    'DDR1_SA_ECC6':'(0,0,0,0,0,0,0,0,N54,0,0,0,0,0,0,0,0,0,0,0,0,0,0,0,0,0,0,0,0~
,0,0,0,0,0,0,0,0,0,0,0,0,0)';$S;BIDI;
    'DDR1_SA_ECC5':'(0,0,0,0,0,0,0,0,K53,0,0,0,0,0,0,0,0,0,0,0,0,0,0,0,0,0,0,0,0~
,0,0,0,0,0,0,0,0,0,0,0,0,0)';$S;BIDI;
    'DDR1_SA_ECC4':'(0,0,0,0,0,0,0,0,J54,0,0,0,0,0,0,0,0,0,0,0,0,0,0,0,0,0,0,0,0~
,0,0,0,0,0,0,0,0,0,0,0,0,0)';$S;BIDI;
    'DDR1_SA_ECC3':'(0,0,0,0,0,0,0,0,N56,0,0,0,0,0,0,0,0,0,0,0,0,0,0,0,0,0,0,0,0~
,0,0,0,0,0,0,0,0,0,0,0,0,0)';$S;BIDI;
    'DDR1_SA_ECC2':'(0,0,0,0,0,0,0,0,M57,0,0,0,0,0,0,0,0,0,0,0,0,0,0,0,0,0,0,0,0~
,0,0,0,0,0,0,0,0,0,0,0,0,0)';$S;BIDI;
    'DDR1_SA_ECC1':'(0,0,0,0,0,0,0,0,J56,0,0,0,0,0,0,0,0,0,0,0,0,0,0,0,0,0,0,0,0~
,0,0,0,0,0,0,0,0,0,0,0,0,0)';$S;BIDI;
    'DDR1_SA_ECC0':'(0,0,0,0,0,0,0,0,K57,0,0,0,0,0,0,0,0,0,0,0,0,0,0,0,0,0,0,0,0~
,0,0,0,0,0,0,0,0,0,0,0,0,0)';$S;BIDI;
    'DDR1_SA_PAR':'(0,0,0,0,0,0,0,0,W43,0,0,0,0,0,0,0,0,0,0,0,0,0,0,0,0,0,0,0,0,~
0,0,0,0,0,0,0,0,0,0,0,0,0)';$S;OUT;
    'DDR1_SB_CA6':'(0,0,0,0,0,0,0,0,H42,0,0,0,0,0,0,0,0,0,0,0,0,0,0,0,0,0,0,0,0,~
0,0,0,0,0,0,0,0,0,0,0,0,0)';$S;OUT;
    'DDR1_SB_CA5':'(0,0,0,0,0,0,0,0,N43,0,0,0,0,0,0,0,0,0,0,0,0,0,0,0,0,0,0,0,0,~
0,0,0,0,0,0,0,0,0,0,0,0,0)';$S;OUT;
    'DDR1_SB_CA4':'(0,0,0,0,0,0,0,0,J43,0,0,0,0,0,0,0,0,0,0,0,0,0,0,0,0,0,0,0,0,~
0,0,0,0,0,0,0,0,0,0,0,0,0)';$S;OUT;
    'DDR1_SB_CA3':'(0,0,0,0,0,0,0,0,M44,0,0,0,0,0,0,0,0,0,0,0,0,0,0,0,0,0,0,0,0,~
0,0,0,0,0,0,0,0,0,0,0,0,0)';$S;OUT;
    'DDR1_SB_CA2':'(0,0,0,0,0,0,0,0,K44,0,0,0,0,0,0,0,0,0,0,0,0,0,0,0,0,0,0,0,0,~
0,0,0,0,0,0,0,0,0,0,0,0,0)';$S;OUT;
    'DDR1_SB_CA1':'(0,0,0,0,0,0,0,0,U43,0,0,0,0,0,0,0,0,0,0,0,0,0,0,0,0,0,0,0,0,~
0,0,0,0,0,0,0,0,0,0,0,0,0)';$S;OUT;
    'DDR1_SB_CA0':'(0,0,0,0,0,0,0,0,T44,0,0,0,0,0,0,0,0,0,0,0,0,0,0,0,0,0,0,0,0,~
0,0,0,0,0,0,0,0,0,0,0,0,0)';$S;OUT;
    'DDR1_SB_CS_N3':'(0,0,0,0,0,0,0,0,M40,0,0,0,0,0,0,0,0,0,0,0,0,0,0,0,0,0,0,0,~
0,0,0,0,0,0,0,0,0,0,0,0,0,0)';$S;OUT;
    'DDR1_SB_CS_N2':'(0,0,0,0,0,0,0,0,N41,0,0,0,0,0,0,0,0,0,0,0,0,0,0,0,0,0,0,0,~
0,0,0,0,0,0,0,0,0,0,0,0,0,0)';$S;OUT;
    'DDR1_SB_CS_N1':'(0,0,0,0,0,0,0,0,K40,0,0,0,0,0,0,0,0,0,0,0,0,0,0,0,0,0,0,0,~
0,0,0,0,0,0,0,0,0,0,0,0,0,0)';$S;OUT;
    'DDR1_SB_CS_N0':'(0,0,0,0,0,0,0,0,J41,0,0,0,0,0,0,0,0,0,0,0,0,0,0,0,0,0,0,0,~
0,0,0,0,0,0,0,0,0,0,0,0,0,0)';$S;OUT;
    'DDR1_SB_DQ31':'(0,0,0,0,0,0,0,0,F14,0,0,0,0,0,0,0,0,0,0,0,0,0,0,0,0,0,0,0,0~
,0,0,0,0,0,0,0,0,0,0,0,0,0)';$S;BIDI;
    'DDR1_SB_DQ30':'(0,0,0,0,0,0,0,0,B14,0,0,0,0,0,0,0,0,0,0,0,0,0,0,0,0,0,0,0,0~
,0,0,0,0,0,0,0,0,0,0,0,0,0)';$S;BIDI;
    'DDR1_SB_DQ29':'(0,0,0,0,0,0,0,0,E13,0,0,0,0,0,0,0,0,0,0,0,0,0,0,0,0,0,0,0,0~
,0,0,0,0,0,0,0,0,0,0,0,0,0)';$S;BIDI;
    'DDR1_SB_DQ28':'(0,0,0,0,0,0,0,0,C13,0,0,0,0,0,0,0,0,0,0,0,0,0,0,0,0,0,0,0,0~
,0,0,0,0,0,0,0,0,0,0,0,0,0)';$S;BIDI;
    'DDR1_SB_DQ27':'(0,0,0,0,0,0,0,0,F16,0,0,0,0,0,0,0,0,0,0,0,0,0,0,0,0,0,0,0,0~
,0,0,0,0,0,0,0,0,0,0,0,0,0)';$S;BIDI;
    'DDR1_SB_DQ26':'(0,0,0,0,0,0,0,0,E17,0,0,0,0,0,0,0,0,0,0,0,0,0,0,0,0,0,0,0,0~
,0,0,0,0,0,0,0,0,0,0,0,0,0)';$S;BIDI;
    'DDR1_SB_DQ25':'(0,0,0,0,0,0,0,0,B16,0,0,0,0,0,0,0,0,0,0,0,0,0,0,0,0,0,0,0,0~
,0,0,0,0,0,0,0,0,0,0,0,0,0)';$S;BIDI;
    'DDR1_SB_DQ24':'(0,0,0,0,0,0,0,0,C17,0,0,0,0,0,0,0,0,0,0,0,0,0,0,0,0,0,0,0,0~
,0,0,0,0,0,0,0,0,0,0,0,0,0)';$S;BIDI;
    'DDR1_SB_DQ23':'(0,0,0,0,0,0,0,0,M16,0,0,0,0,0,0,0,0,0,0,0,0,0,0,0,0,0,0,0,0~
,0,0,0,0,0,0,0,0,0,0,0,0,0)';$S;BIDI;
    'DDR1_SB_DQ22':'(0,0,0,0,0,0,0,0,N17,0,0,0,0,0,0,0,0,0,0,0,0,0,0,0,0,0,0,0,0~
,0,0,0,0,0,0,0,0,0,0,0,0,0)';$S;BIDI;
    'DDR1_SB_DQ21':'(0,0,0,0,0,0,0,0,K16,0,0,0,0,0,0,0,0,0,0,0,0,0,0,0,0,0,0,0,0~
,0,0,0,0,0,0,0,0,0,0,0,0,0)';$S;BIDI;
    'DDR1_SB_DQ20':'(0,0,0,0,0,0,0,0,J17,0,0,0,0,0,0,0,0,0,0,0,0,0,0,0,0,0,0,0,0~
,0,0,0,0,0,0,0,0,0,0,0,0,0)';$S;BIDI;
    'DDR1_SB_DQ19':'(0,0,0,0,0,0,0,0,N19,0,0,0,0,0,0,0,0,0,0,0,0,0,0,0,0,0,0,0,0~
,0,0,0,0,0,0,0,0,0,0,0,0,0)';$S;BIDI;
    'DDR1_SB_DQ18':'(0,0,0,0,0,0,0,0,M20,0,0,0,0,0,0,0,0,0,0,0,0,0,0,0,0,0,0,0,0~
,0,0,0,0,0,0,0,0,0,0,0,0,0)';$S;BIDI;
    'DDR1_SB_DQ17':'(0,0,0,0,0,0,0,0,J19,0,0,0,0,0,0,0,0,0,0,0,0,0,0,0,0,0,0,0,0~
,0,0,0,0,0,0,0,0,0,0,0,0,0)';$S;BIDI;
    'DDR1_SB_DQ16':'(0,0,0,0,0,0,0,0,K20,0,0,0,0,0,0,0,0,0,0,0,0,0,0,0,0,0,0,0,0~
,0,0,0,0,0,0,0,0,0,0,0,0,0)';$S;BIDI;
    'DDR1_SB_DQ15':'(0,0,0,0,0,0,0,0,M22,0,0,0,0,0,0,0,0,0,0,0,0,0,0,0,0,0,0,0,0~
,0,0,0,0,0,0,0,0,0,0,0,0,0)';$S;BIDI;
    'DDR1_SB_DQ14':'(0,0,0,0,0,0,0,0,N23,0,0,0,0,0,0,0,0,0,0,0,0,0,0,0,0,0,0,0,0~
,0,0,0,0,0,0,0,0,0,0,0,0,0)';$S;BIDI;
    'DDR1_SB_DQ13':'(0,0,0,0,0,0,0,0,K22,0,0,0,0,0,0,0,0,0,0,0,0,0,0,0,0,0,0,0,0~
,0,0,0,0,0,0,0,0,0,0,0,0,0)';$S;BIDI;
    'DDR1_SB_DQ12':'(0,0,0,0,0,0,0,0,J23,0,0,0,0,0,0,0,0,0,0,0,0,0,0,0,0,0,0,0,0~
,0,0,0,0,0,0,0,0,0,0,0,0,0)';$S;BIDI;
    'DDR1_SB_DQ11':'(0,0,0,0,0,0,0,0,N25,0,0,0,0,0,0,0,0,0,0,0,0,0,0,0,0,0,0,0,0~
,0,0,0,0,0,0,0,0,0,0,0,0,0)';$S;BIDI;
    'DDR1_SB_DQ10':'(0,0,0,0,0,0,0,0,M26,0,0,0,0,0,0,0,0,0,0,0,0,0,0,0,0,0,0,0,0~
,0,0,0,0,0,0,0,0,0,0,0,0,0)';$S;BIDI;
    'DDR1_SB_DQ9':'(0,0,0,0,0,0,0,0,J25,0,0,0,0,0,0,0,0,0,0,0,0,0,0,0,0,0,0,0,0,~
0,0,0,0,0,0,0,0,0,0,0,0,0)';$S;BIDI;
    'DDR1_SB_DQ8':'(0,0,0,0,0,0,0,0,K26,0,0,0,0,0,0,0,0,0,0,0,0,0,0,0,0,0,0,0,0,~
0,0,0,0,0,0,0,0,0,0,0,0,0)';$S;BIDI;
    'DDR1_SB_DQ7':'(0,0,0,0,0,0,0,0,W25,0,0,0,0,0,0,0,0,0,0,0,0,0,0,0,0,0,0,0,0,~
0,0,0,0,0,0,0,0,0,0,0,0,0)';$S;BIDI;
    'DDR1_SB_DQ6':'(0,0,0,0,0,0,0,0,Y26,0,0,0,0,0,0,0,0,0,0,0,0,0,0,0,0,0,0,0,0,~
0,0,0,0,0,0,0,0,0,0,0,0,0)';$S;BIDI;
    'DDR1_SB_DQ5':'(0,0,0,0,0,0,0,0,U25,0,0,0,0,0,0,0,0,0,0,0,0,0,0,0,0,0,0,0,0,~
0,0,0,0,0,0,0,0,0,0,0,0,0)';$S;BIDI;
    'DDR1_SB_DQ4':'(0,0,0,0,0,0,0,0,T26,0,0,0,0,0,0,0,0,0,0,0,0,0,0,0,0,0,0,0,0,~
0,0,0,0,0,0,0,0,0,0,0,0,0)';$S;BIDI;
    'DDR1_SB_DQ3':'(0,0,0,0,0,0,0,0,Y28,0,0,0,0,0,0,0,0,0,0,0,0,0,0,0,0,0,0,0,0,~
0,0,0,0,0,0,0,0,0,0,0,0,0)';$S;BIDI;
    'DDR1_SB_DQ2':'(0,0,0,0,0,0,0,0,W29,0,0,0,0,0,0,0,0,0,0,0,0,0,0,0,0,0,0,0,0,~
0,0,0,0,0,0,0,0,0,0,0,0,0)';$S;BIDI;
    'DDR1_SB_DQ1':'(0,0,0,0,0,0,0,0,T28,0,0,0,0,0,0,0,0,0,0,0,0,0,0,0,0,0,0,0,0,~
0,0,0,0,0,0,0,0,0,0,0,0,0)';$S;BIDI;
    'DDR1_SB_DQ0':'(0,0,0,0,0,0,0,0,U29,0,0,0,0,0,0,0,0,0,0,0,0,0,0,0,0,0,0,0,0,~
0,0,0,0,0,0,0,0,0,0,0,0,0)';$S;BIDI;
    'DDR1_SB_DQS_DN9':'(0,0,0,0,0,0,0,0,K36,0,0,0,0,0,0,0,0,0,0,0,0,0,0,0,0,0,0,~
0,0,0,0,0,0,0,0,0,0,0,0,0,0,0)';$S;BIDI;
    'DDR1_SB_DQS_DN8':'(0,0,0,0,0,0,0,0,E15,0,0,0,0,0,0,0,0,0,0,0,0,0,0,0,0,0,0,~
0,0,0,0,0,0,0,0,0,0,0,0,0,0,0)';$S;BIDI;
    'DDR1_SB_DQS_DN7':'(0,0,0,0,0,0,0,0,M18,0,0,0,0,0,0,0,0,0,0,0,0,0,0,0,0,0,0,~
0,0,0,0,0,0,0,0,0,0,0,0,0,0,0)';$S;BIDI;
    'DDR1_SB_DQS_DN6':'(0,0,0,0,0,0,0,0,M24,0,0,0,0,0,0,0,0,0,0,0,0,0,0,0,0,0,0,~
0,0,0,0,0,0,0,0,0,0,0,0,0,0,0)';$S;BIDI;
    'DDR1_SB_DQS_DN5':'(0,0,0,0,0,0,0,0,W27,0,0,0,0,0,0,0,0,0,0,0,0,0,0,0,0,0,0,~
0,0,0,0,0,0,0,0,0,0,0,0,0,0,0)';$S;BIDI;
    'DDR1_SB_DQS_DN4':'(0,0,0,0,0,0,0,0,P36,0,0,0,0,0,0,0,0,0,0,0,0,0,0,0,0,0,0,~
0,0,0,0,0,0,0,0,0,0,0,0,0,0,0)';$S;BIDI;
    'DDR1_SB_DQS_DN3':'(0,0,0,0,0,0,0,0,A15,0,0,0,0,0,0,0,0,0,0,0,0,0,0,0,0,0,0,~
0,0,0,0,0,0,0,0,0,0,0,0,0,0,0)';$S;BIDI;
    'DDR1_SB_DQS_DN2':'(0,0,0,0,0,0,0,0,H18,0,0,0,0,0,0,0,0,0,0,0,0,0,0,0,0,0,0,~
0,0,0,0,0,0,0,0,0,0,0,0,0,0,0)';$S;BIDI;
    'DDR1_SB_DQS_DN1':'(0,0,0,0,0,0,0,0,H24,0,0,0,0,0,0,0,0,0,0,0,0,0,0,0,0,0,0,~
0,0,0,0,0,0,0,0,0,0,0,0,0,0,0)';$S;BIDI;
    'DDR1_SB_DQS_DN0':'(0,0,0,0,0,0,0,0,R27,0,0,0,0,0,0,0,0,0,0,0,0,0,0,0,0,0,0,~
0,0,0,0,0,0,0,0,0,0,0,0,0,0,0)';$S;BIDI;
    'DDR1_SB_DQS_DP9':'(0,0,0,0,0,0,0,0,H36,0,0,0,0,0,0,0,0,0,0,0,0,0,0,0,0,0,0,~
0,0,0,0,0,0,0,0,0,0,0,0,0,0,0)';$S;BIDI;
    'DDR1_SB_DQS_DP8':'(0,0,0,0,0,0,0,0,G15,0,0,0,0,0,0,0,0,0,0,0,0,0,0,0,0,0,0,~
0,0,0,0,0,0,0,0,0,0,0,0,0,0,0)';$S;BIDI;
    'DDR1_SB_DQS_DP7':'(0,0,0,0,0,0,0,0,P18,0,0,0,0,0,0,0,0,0,0,0,0,0,0,0,0,0,0,~
0,0,0,0,0,0,0,0,0,0,0,0,0,0,0)';$S;BIDI;
    'DDR1_SB_DQS_DP6':'(0,0,0,0,0,0,0,0,P24,0,0,0,0,0,0,0,0,0,0,0,0,0,0,0,0,0,0,~
0,0,0,0,0,0,0,0,0,0,0,0,0,0,0)';$S;BIDI;
    'DDR1_SB_DQS_DP5':'(0,0,0,0,0,0,0,0,AA27,0,0,0,0,0,0,0,0,0,0,0,0,0,0,0,0,0,0~
,0,0,0,0,0,0,0,0,0,0,0,0,0,0,0)';$S;BIDI;
    'DDR1_SB_DQS_DP4':'(0,0,0,0,0,0,0,0,M36,0,0,0,0,0,0,0,0,0,0,0,0,0,0,0,0,0,0,~
0,0,0,0,0,0,0,0,0,0,0,0,0,0,0)';$S;BIDI;
    'DDR1_SB_DQS_DP3':'(0,0,0,0,0,0,0,0,C15,0,0,0,0,0,0,0,0,0,0,0,0,0,0,0,0,0,0,~
0,0,0,0,0,0,0,0,0,0,0,0,0,0,0)';$S;BIDI;
    'DDR1_SB_DQS_DP2':'(0,0,0,0,0,0,0,0,K18,0,0,0,0,0,0,0,0,0,0,0,0,0,0,0,0,0,0,~
0,0,0,0,0,0,0,0,0,0,0,0,0,0,0)';$S;BIDI;
    'DDR1_SB_DQS_DP1':'(0,0,0,0,0,0,0,0,K24,0,0,0,0,0,0,0,0,0,0,0,0,0,0,0,0,0,0,~
0,0,0,0,0,0,0,0,0,0,0,0,0,0,0)';$S;BIDI;
    'DDR1_SB_DQS_DP0':'(0,0,0,0,0,0,0,0,U27,0,0,0,0,0,0,0,0,0,0,0,0,0,0,0,0,0,0,~
0,0,0,0,0,0,0,0,0,0,0,0,0,0,0)';$S;BIDI;
    'DDR1_SB_ECC7':'(0,0,0,0,0,0,0,0,N37,0,0,0,0,0,0,0,0,0,0,0,0,0,0,0,0,0,0,0,0~
,0,0,0,0,0,0,0,0,0,0,0,0,0)';$S;BIDI;
    'DDR1_SB_ECC6':'(0,0,0,0,0,0,0,0,M38,0,0,0,0,0,0,0,0,0,0,0,0,0,0,0,0,0,0,0,0~
,0,0,0,0,0,0,0,0,0,0,0,0,0)';$S;BIDI;
    'DDR1_SB_ECC5':'(0,0,0,0,0,0,0,0,J37,0,0,0,0,0,0,0,0,0,0,0,0,0,0,0,0,0,0,0,0~
,0,0,0,0,0,0,0,0,0,0,0,0,0)';$S;BIDI;
    'DDR1_SB_ECC4':'(0,0,0,0,0,0,0,0,K38,0,0,0,0,0,0,0,0,0,0,0,0,0,0,0,0,0,0,0,0~
,0,0,0,0,0,0,0,0,0,0,0,0,0)';$S;BIDI;
    'DDR1_SB_ECC3':'(0,0,0,0,0,0,0,0,M34,0,0,0,0,0,0,0,0,0,0,0,0,0,0,0,0,0,0,0,0~
,0,0,0,0,0,0,0,0,0,0,0,0,0)';$S;BIDI;
    'DDR1_SB_ECC2':'(0,0,0,0,0,0,0,0,N35,0,0,0,0,0,0,0,0,0,0,0,0,0,0,0,0,0,0,0,0~
,0,0,0,0,0,0,0,0,0,0,0,0,0)';$S;BIDI;
    'DDR1_SB_ECC1':'(0,0,0,0,0,0,0,0,K34,0,0,0,0,0,0,0,0,0,0,0,0,0,0,0,0,0,0,0,0~
,0,0,0,0,0,0,0,0,0,0,0,0,0)';$S;BIDI;
    'DDR1_SB_ECC0':'(0,0,0,0,0,0,0,0,J35,0,0,0,0,0,0,0,0,0,0,0,0,0,0,0,0,0,0,0,0~
,0,0,0,0,0,0,0,0,0,0,0,0,0)';$S;BIDI;
    'DDR1_SB_PAR':'(0,0,0,0,0,0,0,0,P42,0,0,0,0,0,0,0,0,0,0,0,0,0,0,0,0,0,0,0,0,~
0,0,0,0,0,0,0,0,0,0,0,0,0)';$S;OUT;
    'DDR2_ALERT_N':'(0,0,0,0,0,0,0,0,0,AT47,0,0,0,0,0,0,0,0,0,0,0,0,0,0,0,0,0,0,~
0,0,0,0,0,0,0,0,0,0,0,0,0,0)';$S;IN;
    'DDR2_A_RSP1':'(0,0,0,0,0,0,0,0,0,AD47,0,0,0,0,0,0,0,0,0,0,0,0,0,0,0,0,0,0,0~
,0,0,0,0,0,0,0,0,0,0,0,0,0)';$S;IN;
    'DDR2_A_RSP0':'(0,0,0,0,0,0,0,0,0,AC48,0,0,0,0,0,0,0,0,0,0,0,0,0,0,0,0,0,0,0~
,0,0,0,0,0,0,0,0,0,0,0,0,0)';$S;IN;
    'DDR2_B_RSP1':'(0,0,0,0,0,0,0,0,0,AF47,0,0,0,0,0,0,0,0,0,0,0,0,0,0,0,0,0,0,0~
,0,0,0,0,0,0,0,0,0,0,0,0,0)';$S;IN;
    'DDR2_B_RSP0':'(0,0,0,0,0,0,0,0,0,AG48,0,0,0,0,0,0,0,0,0,0,0,0,0,0,0,0,0,0,0~
,0,0,0,0,0,0,0,0,0,0,0,0,0)';$S;IN;
    'DDR2_CLK_DN1':'(0,0,0,0,0,0,0,0,0,AF49,0,0,0,0,0,0,0,0,0,0,0,0,0,0,0,0,0,0,~
0,0,0,0,0,0,0,0,0,0,0,0,0,0)';$S;OUT;
    'DDR2_CLK_DN0':'(0,0,0,0,0,0,0,0,0,AB49,0,0,0,0,0,0,0,0,0,0,0,0,0,0,0,0,0,0,~
0,0,0,0,0,0,0,0,0,0,0,0,0,0)';$S;OUT;
    'DDR2_CLK_DP1':'(0,0,0,0,0,0,0,0,0,AH49,0,0,0,0,0,0,0,0,0,0,0,0,0,0,0,0,0,0,~
0,0,0,0,0,0,0,0,0,0,0,0,0,0)';$S;OUT;
    'DDR2_CLK_DP0':'(0,0,0,0,0,0,0,0,0,AD49,0,0,0,0,0,0,0,0,0,0,0,0,0,0,0,0,0,0,~
0,0,0,0,0,0,0,0,0,0,0,0,0,0)';$S;OUT;
    'DDR2_SA_CA6':'(0,0,0,0,0,0,0,0,0,U48,0,0,0,0,0,0,0,0,0,0,0,0,0,0,0,0,0,0,0,~
0,0,0,0,0,0,0,0,0,0,0,0,0)';$S;OUT;
    'DDR2_SA_CA5':'(0,0,0,0,0,0,0,0,0,W50,0,0,0,0,0,0,0,0,0,0,0,0,0,0,0,0,0,0,0,~
0,0,0,0,0,0,0,0,0,0,0,0,0)';$S;OUT;
    'DDR2_SA_CA4':'(0,0,0,0,0,0,0,0,0,U50,0,0,0,0,0,0,0,0,0,0,0,0,0,0,0,0,0,0,0,~
0,0,0,0,0,0,0,0,0,0,0,0,0)';$S;OUT;
    'DDR2_SA_CA3':'(0,0,0,0,0,0,0,0,0,Y51,0,0,0,0,0,0,0,0,0,0,0,0,0,0,0,0,0,0,0,~
0,0,0,0,0,0,0,0,0,0,0,0,0)';$S;OUT;
    'DDR2_SA_CA2':'(0,0,0,0,0,0,0,0,0,T51,0,0,0,0,0,0,0,0,0,0,0,0,0,0,0,0,0,0,0,~
0,0,0,0,0,0,0,0,0,0,0,0,0)';$S;OUT;
    'DDR2_SA_CA1':'(0,0,0,0,0,0,0,0,0,AA52,0,0,0,0,0,0,0,0,0,0,0,0,0,0,0,0,0,0,0~
,0,0,0,0,0,0,0,0,0,0,0,0,0)';$S;OUT;
    'DDR2_SA_CA0':'(0,0,0,0,0,0,0,0,0,R52,0,0,0,0,0,0,0,0,0,0,0,0,0,0,0,0,0,0,0,~
0,0,0,0,0,0,0,0,0,0,0,0,0)';$S;OUT;
    'DDR2_SA_CS_N3':'(0,0,0,0,0,0,0,0,0,Y53,0,0,0,0,0,0,0,0,0,0,0,0,0,0,0,0,0,0,~
0,0,0,0,0,0,0,0,0,0,0,0,0,0)';$S;OUT;
    'DDR2_SA_CS_N2':'(0,0,0,0,0,0,0,0,0,W54,0,0,0,0,0,0,0,0,0,0,0,0,0,0,0,0,0,0,~
0,0,0,0,0,0,0,0,0,0,0,0,0,0)';$S;OUT;
    'DDR2_SA_CS_N1':'(0,0,0,0,0,0,0,0,0,T53,0,0,0,0,0,0,0,0,0,0,0,0,0,0,0,0,0,0,~
0,0,0,0,0,0,0,0,0,0,0,0,0,0)';$S;OUT;
    'DDR2_SA_CS_N0':'(0,0,0,0,0,0,0,0,0,U54,0,0,0,0,0,0,0,0,0,0,0,0,0,0,0,0,0,0,~
0,0,0,0,0,0,0,0,0,0,0,0,0,0)';$S;OUT;
    'DDR2_SA_DQ31':'(0,0,0,0,0,0,0,0,0,AF59,0,0,0,0,0,0,0,0,0,0,0,0,0,0,0,0,0,0,~
0,0,0,0,0,0,0,0,0,0,0,0,0,0)';$S;BIDI;
    'DDR2_SA_DQ30':'(0,0,0,0,0,0,0,0,0,AG60,0,0,0,0,0,0,0,0,0,0,0,0,0,0,0,0,0,0,~
0,0,0,0,0,0,0,0,0,0,0,0,0,0)';$S;BIDI;
    'DDR2_SA_DQ29':'(0,0,0,0,0,0,0,0,0,AD59,0,0,0,0,0,0,0,0,0,0,0,0,0,0,0,0,0,0,~
0,0,0,0,0,0,0,0,0,0,0,0,0,0)';$S;BIDI;
    'DDR2_SA_DQ28':'(0,0,0,0,0,0,0,0,0,AC60,0,0,0,0,0,0,0,0,0,0,0,0,0,0,0,0,0,0,~
0,0,0,0,0,0,0,0,0,0,0,0,0,0)';$S;BIDI;
    'DDR2_SA_DQ27':'(0,0,0,0,0,0,0,0,0,AG62,0,0,0,0,0,0,0,0,0,0,0,0,0,0,0,0,0,0,~
0,0,0,0,0,0,0,0,0,0,0,0,0,0)';$S;BIDI;
    'DDR2_SA_DQ26':'(0,0,0,0,0,0,0,0,0,AF63,0,0,0,0,0,0,0,0,0,0,0,0,0,0,0,0,0,0,~
0,0,0,0,0,0,0,0,0,0,0,0,0,0)';$S;BIDI;
    'DDR2_SA_DQ25':'(0,0,0,0,0,0,0,0,0,AC62,0,0,0,0,0,0,0,0,0,0,0,0,0,0,0,0,0,0,~
0,0,0,0,0,0,0,0,0,0,0,0,0,0)';$S;BIDI;
    'DDR2_SA_DQ24':'(0,0,0,0,0,0,0,0,0,AD63,0,0,0,0,0,0,0,0,0,0,0,0,0,0,0,0,0,0,~
0,0,0,0,0,0,0,0,0,0,0,0,0,0)';$S;BIDI;
    'DDR2_SA_DQ23':'(0,0,0,0,0,0,0,0,0,W62,0,0,0,0,0,0,0,0,0,0,0,0,0,0,0,0,0,0,0~
,0,0,0,0,0,0,0,0,0,0,0,0,0)';$S;BIDI;
    'DDR2_SA_DQ22':'(0,0,0,0,0,0,0,0,0,Y63,0,0,0,0,0,0,0,0,0,0,0,0,0,0,0,0,0,0,0~
,0,0,0,0,0,0,0,0,0,0,0,0,0)';$S;BIDI;
    'DDR2_SA_DQ21':'(0,0,0,0,0,0,0,0,0,U62,0,0,0,0,0,0,0,0,0,0,0,0,0,0,0,0,0,0,0~
,0,0,0,0,0,0,0,0,0,0,0,0,0)';$S;BIDI;
    'DDR2_SA_DQ20':'(0,0,0,0,0,0,0,0,0,T63,0,0,0,0,0,0,0,0,0,0,0,0,0,0,0,0,0,0,0~
,0,0,0,0,0,0,0,0,0,0,0,0,0)';$S;BIDI;
    'DDR2_SA_DQ19':'(0,0,0,0,0,0,0,0,0,Y65,0,0,0,0,0,0,0,0,0,0,0,0,0,0,0,0,0,0,0~
,0,0,0,0,0,0,0,0,0,0,0,0,0)';$S;BIDI;
    'DDR2_SA_DQ18':'(0,0,0,0,0,0,0,0,0,W66,0,0,0,0,0,0,0,0,0,0,0,0,0,0,0,0,0,0,0~
,0,0,0,0,0,0,0,0,0,0,0,0,0)';$S;BIDI;
    'DDR2_SA_DQ17':'(0,0,0,0,0,0,0,0,0,T65,0,0,0,0,0,0,0,0,0,0,0,0,0,0,0,0,0,0,0~
,0,0,0,0,0,0,0,0,0,0,0,0,0)';$S;BIDI;
    'DDR2_SA_DQ16':'(0,0,0,0,0,0,0,0,0,U66,0,0,0,0,0,0,0,0,0,0,0,0,0,0,0,0,0,0,0~
,0,0,0,0,0,0,0,0,0,0,0,0,0)';$S;BIDI;
    'DDR2_SA_DQ15':'(0,0,0,0,0,0,0,0,0,AF65,0,0,0,0,0,0,0,0,0,0,0,0,0,0,0,0,0,0,~
0,0,0,0,0,0,0,0,0,0,0,0,0,0)';$S;BIDI;
    'DDR2_SA_DQ14':'(0,0,0,0,0,0,0,0,0,AG66,0,0,0,0,0,0,0,0,0,0,0,0,0,0,0,0,0,0,~
0,0,0,0,0,0,0,0,0,0,0,0,0,0)';$S;BIDI;
    'DDR2_SA_DQ13':'(0,0,0,0,0,0,0,0,0,AD65,0,0,0,0,0,0,0,0,0,0,0,0,0,0,0,0,0,0,~
0,0,0,0,0,0,0,0,0,0,0,0,0,0)';$S;BIDI;
    'DDR2_SA_DQ12':'(0,0,0,0,0,0,0,0,0,AC66,0,0,0,0,0,0,0,0,0,0,0,0,0,0,0,0,0,0,~
0,0,0,0,0,0,0,0,0,0,0,0,0,0)';$S;BIDI;
    'DDR2_SA_DQ11':'(0,0,0,0,0,0,0,0,0,AG68,0,0,0,0,0,0,0,0,0,0,0,0,0,0,0,0,0,0,~
0,0,0,0,0,0,0,0,0,0,0,0,0,0)';$S;BIDI;
    'DDR2_SA_DQ10':'(0,0,0,0,0,0,0,0,0,AF69,0,0,0,0,0,0,0,0,0,0,0,0,0,0,0,0,0,0,~
0,0,0,0,0,0,0,0,0,0,0,0,0,0)';$S;BIDI;
    'DDR2_SA_DQ9':'(0,0,0,0,0,0,0,0,0,AC68,0,0,0,0,0,0,0,0,0,0,0,0,0,0,0,0,0,0,0~
,0,0,0,0,0,0,0,0,0,0,0,0,0)';$S;BIDI;
    'DDR2_SA_DQ8':'(0,0,0,0,0,0,0,0,0,AD69,0,0,0,0,0,0,0,0,0,0,0,0,0,0,0,0,0,0,0~
,0,0,0,0,0,0,0,0,0,0,0,0,0)';$S;BIDI;
    'DDR2_SA_DQ7':'(0,0,0,0,0,0,0,0,0,W74,0,0,0,0,0,0,0,0,0,0,0,0,0,0,0,0,0,0,0,~
0,0,0,0,0,0,0,0,0,0,0,0,0)';$S;BIDI;
    'DDR2_SA_DQ6':'(0,0,0,0,0,0,0,0,0,Y75,0,0,0,0,0,0,0,0,0,0,0,0,0,0,0,0,0,0,0,~
0,0,0,0,0,0,0,0,0,0,0,0,0)';$S;BIDI;
    'DDR2_SA_DQ5':'(0,0,0,0,0,0,0,0,0,U74,0,0,0,0,0,0,0,0,0,0,0,0,0,0,0,0,0,0,0,~
0,0,0,0,0,0,0,0,0,0,0,0,0)';$S;BIDI;
    'DDR2_SA_DQ4':'(0,0,0,0,0,0,0,0,0,T75,0,0,0,0,0,0,0,0,0,0,0,0,0,0,0,0,0,0,0,~
0,0,0,0,0,0,0,0,0,0,0,0,0)';$S;BIDI;
    'DDR2_SA_DQ3':'(0,0,0,0,0,0,0,0,0,Y77,0,0,0,0,0,0,0,0,0,0,0,0,0,0,0,0,0,0,0,~
0,0,0,0,0,0,0,0,0,0,0,0,0)';$S;BIDI;
    'DDR2_SA_DQ2':'(0,0,0,0,0,0,0,0,0,W78,0,0,0,0,0,0,0,0,0,0,0,0,0,0,0,0,0,0,0,~
0,0,0,0,0,0,0,0,0,0,0,0,0)';$S;BIDI;
    'DDR2_SA_DQ1':'(0,0,0,0,0,0,0,0,0,T77,0,0,0,0,0,0,0,0,0,0,0,0,0,0,0,0,0,0,0,~
0,0,0,0,0,0,0,0,0,0,0,0,0)';$S;BIDI;
    'DDR2_SA_DQ0':'(0,0,0,0,0,0,0,0,0,U78,0,0,0,0,0,0,0,0,0,0,0,0,0,0,0,0,0,0,0,~
0,0,0,0,0,0,0,0,0,0,0,0,0)';$S;BIDI;
    'DDR2_SA_DQS_DN9':'(0,0,0,0,0,0,0,0,0,AH55,0,0,0,0,0,0,0,0,0,0,0,0,0,0,0,0,0~
,0,0,0,0,0,0,0,0,0,0,0,0,0,0,0)';$S;BIDI;
    'DDR2_SA_DQS_DN8':'(0,0,0,0,0,0,0,0,0,AF61,0,0,0,0,0,0,0,0,0,0,0,0,0,0,0,0,0~
,0,0,0,0,0,0,0,0,0,0,0,0,0,0,0)';$S;BIDI;
    'DDR2_SA_DQS_DN7':'(0,0,0,0,0,0,0,0,0,AA64,0,0,0,0,0,0,0,0,0,0,0,0,0,0,0,0,0~
,0,0,0,0,0,0,0,0,0,0,0,0,0,0,0)';$S;BIDI;
    'DDR2_SA_DQS_DN6':'(0,0,0,0,0,0,0,0,0,AH67,0,0,0,0,0,0,0,0,0,0,0,0,0,0,0,0,0~
,0,0,0,0,0,0,0,0,0,0,0,0,0,0,0)';$S;BIDI;
    'DDR2_SA_DQS_DN5':'(0,0,0,0,0,0,0,0,0,W76,0,0,0,0,0,0,0,0,0,0,0,0,0,0,0,0,0,~
0,0,0,0,0,0,0,0,0,0,0,0,0,0,0)';$S;BIDI;
    'DDR2_SA_DQS_DN4':'(0,0,0,0,0,0,0,0,0,AD55,0,0,0,0,0,0,0,0,0,0,0,0,0,0,0,0,0~
,0,0,0,0,0,0,0,0,0,0,0,0,0,0,0)';$S;BIDI;
    'DDR2_SA_DQS_DN3':'(0,0,0,0,0,0,0,0,0,AB61,0,0,0,0,0,0,0,0,0,0,0,0,0,0,0,0,0~
,0,0,0,0,0,0,0,0,0,0,0,0,0,0,0)';$S;BIDI;
    'DDR2_SA_DQS_DN2':'(0,0,0,0,0,0,0,0,0,R64,0,0,0,0,0,0,0,0,0,0,0,0,0,0,0,0,0,~
0,0,0,0,0,0,0,0,0,0,0,0,0,0,0)';$S;BIDI;
    'DDR2_SA_DQS_DN1':'(0,0,0,0,0,0,0,0,0,AB67,0,0,0,0,0,0,0,0,0,0,0,0,0,0,0,0,0~
,0,0,0,0,0,0,0,0,0,0,0,0,0,0,0)';$S;BIDI;
    'DDR2_SA_DQS_DN0':'(0,0,0,0,0,0,0,0,0,R76,0,0,0,0,0,0,0,0,0,0,0,0,0,0,0,0,0,~
0,0,0,0,0,0,0,0,0,0,0,0,0,0,0)';$S;BIDI;
    'DDR2_SA_DQS_DP9':'(0,0,0,0,0,0,0,0,0,AF55,0,0,0,0,0,0,0,0,0,0,0,0,0,0,0,0,0~
,0,0,0,0,0,0,0,0,0,0,0,0,0,0,0)';$S;BIDI;
    'DDR2_SA_DQS_DP8':'(0,0,0,0,0,0,0,0,0,AH61,0,0,0,0,0,0,0,0,0,0,0,0,0,0,0,0,0~
,0,0,0,0,0,0,0,0,0,0,0,0,0,0,0)';$S;BIDI;
    'DDR2_SA_DQS_DP7':'(0,0,0,0,0,0,0,0,0,W64,0,0,0,0,0,0,0,0,0,0,0,0,0,0,0,0,0,~
0,0,0,0,0,0,0,0,0,0,0,0,0,0,0)';$S;BIDI;
    'DDR2_SA_DQS_DP6':'(0,0,0,0,0,0,0,0,0,AF67,0,0,0,0,0,0,0,0,0,0,0,0,0,0,0,0,0~
,0,0,0,0,0,0,0,0,0,0,0,0,0,0,0)';$S;BIDI;
    'DDR2_SA_DQS_DP5':'(0,0,0,0,0,0,0,0,0,AA76,0,0,0,0,0,0,0,0,0,0,0,0,0,0,0,0,0~
,0,0,0,0,0,0,0,0,0,0,0,0,0,0,0)';$S;BIDI;
    'DDR2_SA_DQS_DP4':'(0,0,0,0,0,0,0,0,0,AB55,0,0,0,0,0,0,0,0,0,0,0,0,0,0,0,0,0~
,0,0,0,0,0,0,0,0,0,0,0,0,0,0,0)';$S;BIDI;
    'DDR2_SA_DQS_DP3':'(0,0,0,0,0,0,0,0,0,AD61,0,0,0,0,0,0,0,0,0,0,0,0,0,0,0,0,0~
,0,0,0,0,0,0,0,0,0,0,0,0,0,0,0)';$S;BIDI;
    'DDR2_SA_DQS_DP2':'(0,0,0,0,0,0,0,0,0,U64,0,0,0,0,0,0,0,0,0,0,0,0,0,0,0,0,0,~
0,0,0,0,0,0,0,0,0,0,0,0,0,0,0)';$S;BIDI;
    'DDR2_SA_DQS_DP1':'(0,0,0,0,0,0,0,0,0,AD67,0,0,0,0,0,0,0,0,0,0,0,0,0,0,0,0,0~
,0,0,0,0,0,0,0,0,0,0,0,0,0,0,0)';$S;BIDI;
    'DDR2_SA_DQS_DP0':'(0,0,0,0,0,0,0,0,0,U76,0,0,0,0,0,0,0,0,0,0,0,0,0,0,0,0,0,~
0,0,0,0,0,0,0,0,0,0,0,0,0,0,0)';$S;BIDI;
    'DDR2_SA_ECC7':'(0,0,0,0,0,0,0,0,0,AF53,0,0,0,0,0,0,0,0,0,0,0,0,0,0,0,0,0,0,~
0,0,0,0,0,0,0,0,0,0,0,0,0,0)';$S;BIDI;
    'DDR2_SA_ECC6':'(0,0,0,0,0,0,0,0,0,AG54,0,0,0,0,0,0,0,0,0,0,0,0,0,0,0,0,0,0,~
0,0,0,0,0,0,0,0,0,0,0,0,0,0)';$S;BIDI;
    'DDR2_SA_ECC5':'(0,0,0,0,0,0,0,0,0,AD53,0,0,0,0,0,0,0,0,0,0,0,0,0,0,0,0,0,0,~
0,0,0,0,0,0,0,0,0,0,0,0,0,0)';$S;BIDI;
    'DDR2_SA_ECC4':'(0,0,0,0,0,0,0,0,0,AC54,0,0,0,0,0,0,0,0,0,0,0,0,0,0,0,0,0,0,~
0,0,0,0,0,0,0,0,0,0,0,0,0,0)';$S;BIDI;
    'DDR2_SA_ECC3':'(0,0,0,0,0,0,0,0,0,AG56,0,0,0,0,0,0,0,0,0,0,0,0,0,0,0,0,0,0,~
0,0,0,0,0,0,0,0,0,0,0,0,0,0)';$S;BIDI;
    'DDR2_SA_ECC2':'(0,0,0,0,0,0,0,0,0,AF57,0,0,0,0,0,0,0,0,0,0,0,0,0,0,0,0,0,0,~
0,0,0,0,0,0,0,0,0,0,0,0,0,0)';$S;BIDI;
    'DDR2_SA_ECC1':'(0,0,0,0,0,0,0,0,0,AC56,0,0,0,0,0,0,0,0,0,0,0,0,0,0,0,0,0,0,~
0,0,0,0,0,0,0,0,0,0,0,0,0,0)';$S;BIDI;
    'DDR2_SA_ECC0':'(0,0,0,0,0,0,0,0,0,AD57,0,0,0,0,0,0,0,0,0,0,0,0,0,0,0,0,0,0,~
0,0,0,0,0,0,0,0,0,0,0,0,0,0)';$S;BIDI;
    'DDR2_SA_PAR':'(0,0,0,0,0,0,0,0,0,T47,0,0,0,0,0,0,0,0,0,0,0,0,0,0,0,0,0,0,0,~
0,0,0,0,0,0,0,0,0,0,0,0,0)';$S;OUT;
    'DDR2_SB_CA6':'(0,0,0,0,0,0,0,0,0,R39,0,0,0,0,0,0,0,0,0,0,0,0,0,0,0,0,0,0,0,~
0,0,0,0,0,0,0,0,0,0,0,0,0)';$S;OUT;
    'DDR2_SB_CA5':'(0,0,0,0,0,0,0,0,0,Y40,0,0,0,0,0,0,0,0,0,0,0,0,0,0,0,0,0,0,0,~
0,0,0,0,0,0,0,0,0,0,0,0,0)';$S;OUT;
    'DDR2_SB_CA4':'(0,0,0,0,0,0,0,0,0,T40,0,0,0,0,0,0,0,0,0,0,0,0,0,0,0,0,0,0,0,~
0,0,0,0,0,0,0,0,0,0,0,0,0)';$S;OUT;
    'DDR2_SB_CA3':'(0,0,0,0,0,0,0,0,0,W41,0,0,0,0,0,0,0,0,0,0,0,0,0,0,0,0,0,0,0,~
0,0,0,0,0,0,0,0,0,0,0,0,0)';$S;OUT;
    'DDR2_SB_CA2':'(0,0,0,0,0,0,0,0,0,U41,0,0,0,0,0,0,0,0,0,0,0,0,0,0,0,0,0,0,0,~
0,0,0,0,0,0,0,0,0,0,0,0,0)';$S;OUT;
    'DDR2_SB_CA1':'(0,0,0,0,0,0,0,0,0,Y47,0,0,0,0,0,0,0,0,0,0,0,0,0,0,0,0,0,0,0,~
0,0,0,0,0,0,0,0,0,0,0,0,0)';$S;OUT;
    'DDR2_SB_CA0':'(0,0,0,0,0,0,0,0,0,W48,0,0,0,0,0,0,0,0,0,0,0,0,0,0,0,0,0,0,0,~
0,0,0,0,0,0,0,0,0,0,0,0,0)';$S;OUT;
    'DDR2_SB_CS_N3':'(0,0,0,0,0,0,0,0,0,W37,0,0,0,0,0,0,0,0,0,0,0,0,0,0,0,0,0,0,~
0,0,0,0,0,0,0,0,0,0,0,0,0,0)';$S;OUT;
    'DDR2_SB_CS_N2':'(0,0,0,0,0,0,0,0,0,Y38,0,0,0,0,0,0,0,0,0,0,0,0,0,0,0,0,0,0,~
0,0,0,0,0,0,0,0,0,0,0,0,0,0)';$S;OUT;
    'DDR2_SB_CS_N1':'(0,0,0,0,0,0,0,0,0,U37,0,0,0,0,0,0,0,0,0,0,0,0,0,0,0,0,0,0,~
0,0,0,0,0,0,0,0,0,0,0,0,0,0)';$S;OUT;
    'DDR2_SB_CS_N0':'(0,0,0,0,0,0,0,0,0,T38,0,0,0,0,0,0,0,0,0,0,0,0,0,0,0,0,0,0,~
0,0,0,0,0,0,0,0,0,0,0,0,0,0)';$S;OUT;
    'DDR2_SB_DQ31':'(0,0,0,0,0,0,0,0,0,AJ17,0,0,0,0,0,0,0,0,0,0,0,0,0,0,0,0,0,0,~
0,0,0,0,0,0,0,0,0,0,0,0,0,0)';$S;BIDI;
    'DDR2_SB_DQ30':'(0,0,0,0,0,0,0,0,0,AC17,0,0,0,0,0,0,0,0,0,0,0,0,0,0,0,0,0,0,~
0,0,0,0,0,0,0,0,0,0,0,0,0,0)';$S;BIDI;
    'DDR2_SB_DQ29':'(0,0,0,0,0,0,0,0,0,AG17,0,0,0,0,0,0,0,0,0,0,0,0,0,0,0,0,0,0,~
0,0,0,0,0,0,0,0,0,0,0,0,0,0)';$S;BIDI;
    'DDR2_SB_DQ28':'(0,0,0,0,0,0,0,0,0,AA17,0,0,0,0,0,0,0,0,0,0,0,0,0,0,0,0,0,0,~
0,0,0,0,0,0,0,0,0,0,0,0,0,0)';$S;BIDI;
    'DDR2_SB_DQ27':'(0,0,0,0,0,0,0,0,0,AG19,0,0,0,0,0,0,0,0,0,0,0,0,0,0,0,0,0,0,~
0,0,0,0,0,0,0,0,0,0,0,0,0,0)';$S;BIDI;
    'DDR2_SB_DQ26':'(0,0,0,0,0,0,0,0,0,AF20,0,0,0,0,0,0,0,0,0,0,0,0,0,0,0,0,0,0,~
0,0,0,0,0,0,0,0,0,0,0,0,0,0)';$S;BIDI;
    'DDR2_SB_DQ25':'(0,0,0,0,0,0,0,0,0,AC19,0,0,0,0,0,0,0,0,0,0,0,0,0,0,0,0,0,0,~
0,0,0,0,0,0,0,0,0,0,0,0,0,0)';$S;BIDI;
    'DDR2_SB_DQ24':'(0,0,0,0,0,0,0,0,0,AD20,0,0,0,0,0,0,0,0,0,0,0,0,0,0,0,0,0,0,~
0,0,0,0,0,0,0,0,0,0,0,0,0,0)';$S;BIDI;
    'DDR2_SB_DQ23':'(0,0,0,0,0,0,0,0,0,W19,0,0,0,0,0,0,0,0,0,0,0,0,0,0,0,0,0,0,0~
,0,0,0,0,0,0,0,0,0,0,0,0,0)';$S;BIDI;
    'DDR2_SB_DQ22':'(0,0,0,0,0,0,0,0,0,Y20,0,0,0,0,0,0,0,0,0,0,0,0,0,0,0,0,0,0,0~
,0,0,0,0,0,0,0,0,0,0,0,0,0)';$S;BIDI;
    'DDR2_SB_DQ21':'(0,0,0,0,0,0,0,0,0,U19,0,0,0,0,0,0,0,0,0,0,0,0,0,0,0,0,0,0,0~
,0,0,0,0,0,0,0,0,0,0,0,0,0)';$S;BIDI;
    'DDR2_SB_DQ20':'(0,0,0,0,0,0,0,0,0,T20,0,0,0,0,0,0,0,0,0,0,0,0,0,0,0,0,0,0,0~
,0,0,0,0,0,0,0,0,0,0,0,0,0)';$S;BIDI;
    'DDR2_SB_DQ19':'(0,0,0,0,0,0,0,0,0,Y22,0,0,0,0,0,0,0,0,0,0,0,0,0,0,0,0,0,0,0~
,0,0,0,0,0,0,0,0,0,0,0,0,0)';$S;BIDI;
    'DDR2_SB_DQ18':'(0,0,0,0,0,0,0,0,0,W23,0,0,0,0,0,0,0,0,0,0,0,0,0,0,0,0,0,0,0~
,0,0,0,0,0,0,0,0,0,0,0,0,0)';$S;BIDI;
    'DDR2_SB_DQ17':'(0,0,0,0,0,0,0,0,0,T22,0,0,0,0,0,0,0,0,0,0,0,0,0,0,0,0,0,0,0~
,0,0,0,0,0,0,0,0,0,0,0,0,0)';$S;BIDI;
    'DDR2_SB_DQ16':'(0,0,0,0,0,0,0,0,0,U23,0,0,0,0,0,0,0,0,0,0,0,0,0,0,0,0,0,0,0~
,0,0,0,0,0,0,0,0,0,0,0,0,0)';$S;BIDI;
    'DDR2_SB_DQ15':'(0,0,0,0,0,0,0,0,0,AF28,0,0,0,0,0,0,0,0,0,0,0,0,0,0,0,0,0,0,~
0,0,0,0,0,0,0,0,0,0,0,0,0,0)';$S;BIDI;
    'DDR2_SB_DQ14':'(0,0,0,0,0,0,0,0,0,AG29,0,0,0,0,0,0,0,0,0,0,0,0,0,0,0,0,0,0,~
0,0,0,0,0,0,0,0,0,0,0,0,0,0)';$S;BIDI;
    'DDR2_SB_DQ13':'(0,0,0,0,0,0,0,0,0,AD28,0,0,0,0,0,0,0,0,0,0,0,0,0,0,0,0,0,0,~
0,0,0,0,0,0,0,0,0,0,0,0,0,0)';$S;BIDI;
    'DDR2_SB_DQ12':'(0,0,0,0,0,0,0,0,0,AC29,0,0,0,0,0,0,0,0,0,0,0,0,0,0,0,0,0,0,~
0,0,0,0,0,0,0,0,0,0,0,0,0,0)';$S;BIDI;
    'DDR2_SB_DQ11':'(0,0,0,0,0,0,0,0,0,AG31,0,0,0,0,0,0,0,0,0,0,0,0,0,0,0,0,0,0,~
0,0,0,0,0,0,0,0,0,0,0,0,0,0)';$S;BIDI;
    'DDR2_SB_DQ10':'(0,0,0,0,0,0,0,0,0,AF32,0,0,0,0,0,0,0,0,0,0,0,0,0,0,0,0,0,0,~
0,0,0,0,0,0,0,0,0,0,0,0,0,0)';$S;BIDI;
    'DDR2_SB_DQ9':'(0,0,0,0,0,0,0,0,0,AC31,0,0,0,0,0,0,0,0,0,0,0,0,0,0,0,0,0,0,0~
,0,0,0,0,0,0,0,0,0,0,0,0,0)';$S;BIDI;
    'DDR2_SB_DQ8':'(0,0,0,0,0,0,0,0,0,AD32,0,0,0,0,0,0,0,0,0,0,0,0,0,0,0,0,0,0,0~
,0,0,0,0,0,0,0,0,0,0,0,0,0)';$S;BIDI;
    'DDR2_SB_DQ7':'(0,0,0,0,0,0,0,0,0,AF34,0,0,0,0,0,0,0,0,0,0,0,0,0,0,0,0,0,0,0~
,0,0,0,0,0,0,0,0,0,0,0,0,0)';$S;BIDI;
    'DDR2_SB_DQ6':'(0,0,0,0,0,0,0,0,0,AG35,0,0,0,0,0,0,0,0,0,0,0,0,0,0,0,0,0,0,0~
,0,0,0,0,0,0,0,0,0,0,0,0,0)';$S;BIDI;
    'DDR2_SB_DQ5':'(0,0,0,0,0,0,0,0,0,AD34,0,0,0,0,0,0,0,0,0,0,0,0,0,0,0,0,0,0,0~
,0,0,0,0,0,0,0,0,0,0,0,0,0)';$S;BIDI;
    'DDR2_SB_DQ4':'(0,0,0,0,0,0,0,0,0,AC35,0,0,0,0,0,0,0,0,0,0,0,0,0,0,0,0,0,0,0~
,0,0,0,0,0,0,0,0,0,0,0,0,0)';$S;BIDI;
    'DDR2_SB_DQ3':'(0,0,0,0,0,0,0,0,0,AG37,0,0,0,0,0,0,0,0,0,0,0,0,0,0,0,0,0,0,0~
,0,0,0,0,0,0,0,0,0,0,0,0,0)';$S;BIDI;
    'DDR2_SB_DQ2':'(0,0,0,0,0,0,0,0,0,AF38,0,0,0,0,0,0,0,0,0,0,0,0,0,0,0,0,0,0,0~
,0,0,0,0,0,0,0,0,0,0,0,0,0)';$S;BIDI;
    'DDR2_SB_DQ1':'(0,0,0,0,0,0,0,0,0,AC37,0,0,0,0,0,0,0,0,0,0,0,0,0,0,0,0,0,0,0~
,0,0,0,0,0,0,0,0,0,0,0,0,0)';$S;BIDI;
    'DDR2_SB_DQ0':'(0,0,0,0,0,0,0,0,0,AD38,0,0,0,0,0,0,0,0,0,0,0,0,0,0,0,0,0,0,0~
,0,0,0,0,0,0,0,0,0,0,0,0,0)';$S;BIDI;
    'DDR2_SB_DQS_DN9':'(0,0,0,0,0,0,0,0,0,R33,0,0,0,0,0,0,0,0,0,0,0,0,0,0,0,0,0,~
0,0,0,0,0,0,0,0,0,0,0,0,0,0,0)';$S;BIDI;
    'DDR2_SB_DQS_DN8':'(0,0,0,0,0,0,0,0,0,AF18,0,0,0,0,0,0,0,0,0,0,0,0,0,0,0,0,0~
,0,0,0,0,0,0,0,0,0,0,0,0,0,0,0)';$S;BIDI;
    'DDR2_SB_DQS_DN7':'(0,0,0,0,0,0,0,0,0,W21,0,0,0,0,0,0,0,0,0,0,0,0,0,0,0,0,0,~
0,0,0,0,0,0,0,0,0,0,0,0,0,0,0)';$S;BIDI;
    'DDR2_SB_DQS_DN6':'(0,0,0,0,0,0,0,0,0,AF30,0,0,0,0,0,0,0,0,0,0,0,0,0,0,0,0,0~
,0,0,0,0,0,0,0,0,0,0,0,0,0,0,0)';$S;BIDI;
    'DDR2_SB_DQS_DN5':'(0,0,0,0,0,0,0,0,0,AF36,0,0,0,0,0,0,0,0,0,0,0,0,0,0,0,0,0~
,0,0,0,0,0,0,0,0,0,0,0,0,0,0,0)';$S;BIDI;
    'DDR2_SB_DQS_DN4':'(0,0,0,0,0,0,0,0,0,W33,0,0,0,0,0,0,0,0,0,0,0,0,0,0,0,0,0,~
0,0,0,0,0,0,0,0,0,0,0,0,0,0,0)';$S;BIDI;
    'DDR2_SB_DQS_DN3':'(0,0,0,0,0,0,0,0,0,AB18,0,0,0,0,0,0,0,0,0,0,0,0,0,0,0,0,0~
,0,0,0,0,0,0,0,0,0,0,0,0,0,0,0)';$S;BIDI;
    'DDR2_SB_DQS_DN2':'(0,0,0,0,0,0,0,0,0,R21,0,0,0,0,0,0,0,0,0,0,0,0,0,0,0,0,0,~
0,0,0,0,0,0,0,0,0,0,0,0,0,0,0)';$S;BIDI;
    'DDR2_SB_DQS_DN1':'(0,0,0,0,0,0,0,0,0,AB30,0,0,0,0,0,0,0,0,0,0,0,0,0,0,0,0,0~
,0,0,0,0,0,0,0,0,0,0,0,0,0,0,0)';$S;BIDI;
    'DDR2_SB_DQS_DN0':'(0,0,0,0,0,0,0,0,0,AB36,0,0,0,0,0,0,0,0,0,0,0,0,0,0,0,0,0~
,0,0,0,0,0,0,0,0,0,0,0,0,0,0,0)';$S;BIDI;
    'DDR2_SB_DQS_DP9':'(0,0,0,0,0,0,0,0,0,U33,0,0,0,0,0,0,0,0,0,0,0,0,0,0,0,0,0,~
0,0,0,0,0,0,0,0,0,0,0,0,0,0,0)';$S;BIDI;
    'DDR2_SB_DQS_DP8':'(0,0,0,0,0,0,0,0,0,AH18,0,0,0,0,0,0,0,0,0,0,0,0,0,0,0,0,0~
,0,0,0,0,0,0,0,0,0,0,0,0,0,0,0)';$S;BIDI;
    'DDR2_SB_DQS_DP7':'(0,0,0,0,0,0,0,0,0,AA21,0,0,0,0,0,0,0,0,0,0,0,0,0,0,0,0,0~
,0,0,0,0,0,0,0,0,0,0,0,0,0,0,0)';$S;BIDI;
    'DDR2_SB_DQS_DP6':'(0,0,0,0,0,0,0,0,0,AH30,0,0,0,0,0,0,0,0,0,0,0,0,0,0,0,0,0~
,0,0,0,0,0,0,0,0,0,0,0,0,0,0,0)';$S;BIDI;
    'DDR2_SB_DQS_DP5':'(0,0,0,0,0,0,0,0,0,AH36,0,0,0,0,0,0,0,0,0,0,0,0,0,0,0,0,0~
,0,0,0,0,0,0,0,0,0,0,0,0,0,0,0)';$S;BIDI;
    'DDR2_SB_DQS_DP4':'(0,0,0,0,0,0,0,0,0,AA33,0,0,0,0,0,0,0,0,0,0,0,0,0,0,0,0,0~
,0,0,0,0,0,0,0,0,0,0,0,0,0,0,0)';$S;BIDI;
    'DDR2_SB_DQS_DP3':'(0,0,0,0,0,0,0,0,0,AD18,0,0,0,0,0,0,0,0,0,0,0,0,0,0,0,0,0~
,0,0,0,0,0,0,0,0,0,0,0,0,0,0,0)';$S;BIDI;
    'DDR2_SB_DQS_DP2':'(0,0,0,0,0,0,0,0,0,U21,0,0,0,0,0,0,0,0,0,0,0,0,0,0,0,0,0,~
0,0,0,0,0,0,0,0,0,0,0,0,0,0,0)';$S;BIDI;
    'DDR2_SB_DQS_DP1':'(0,0,0,0,0,0,0,0,0,AD30,0,0,0,0,0,0,0,0,0,0,0,0,0,0,0,0,0~
,0,0,0,0,0,0,0,0,0,0,0,0,0,0,0)';$S;BIDI;
    'DDR2_SB_DQS_DP0':'(0,0,0,0,0,0,0,0,0,AD36,0,0,0,0,0,0,0,0,0,0,0,0,0,0,0,0,0~
,0,0,0,0,0,0,0,0,0,0,0,0,0,0,0)';$S;BIDI;
    'DDR2_SB_ECC7':'(0,0,0,0,0,0,0,0,0,Y34,0,0,0,0,0,0,0,0,0,0,0,0,0,0,0,0,0,0,0~
,0,0,0,0,0,0,0,0,0,0,0,0,0)';$S;BIDI;
    'DDR2_SB_ECC6':'(0,0,0,0,0,0,0,0,0,W35,0,0,0,0,0,0,0,0,0,0,0,0,0,0,0,0,0,0,0~
,0,0,0,0,0,0,0,0,0,0,0,0,0)';$S;BIDI;
    'DDR2_SB_ECC5':'(0,0,0,0,0,0,0,0,0,T34,0,0,0,0,0,0,0,0,0,0,0,0,0,0,0,0,0,0,0~
,0,0,0,0,0,0,0,0,0,0,0,0,0)';$S;BIDI;
    'DDR2_SB_ECC4':'(0,0,0,0,0,0,0,0,0,U35,0,0,0,0,0,0,0,0,0,0,0,0,0,0,0,0,0,0,0~
,0,0,0,0,0,0,0,0,0,0,0,0,0)';$S;BIDI;
    'DDR2_SB_ECC3':'(0,0,0,0,0,0,0,0,0,W31,0,0,0,0,0,0,0,0,0,0,0,0,0,0,0,0,0,0,0~
,0,0,0,0,0,0,0,0,0,0,0,0,0)';$S;BIDI;
    'DDR2_SB_ECC2':'(0,0,0,0,0,0,0,0,0,Y32,0,0,0,0,0,0,0,0,0,0,0,0,0,0,0,0,0,0,0~
,0,0,0,0,0,0,0,0,0,0,0,0,0)';$S;BIDI;
    'DDR2_SB_ECC1':'(0,0,0,0,0,0,0,0,0,U31,0,0,0,0,0,0,0,0,0,0,0,0,0,0,0,0,0,0,0~
,0,0,0,0,0,0,0,0,0,0,0,0,0)';$S;BIDI;
    'DDR2_SB_ECC0':'(0,0,0,0,0,0,0,0,0,T32,0,0,0,0,0,0,0,0,0,0,0,0,0,0,0,0,0,0,0~
,0,0,0,0,0,0,0,0,0,0,0,0,0)';$S;BIDI;
    'DDR2_SB_PAR':'(0,0,0,0,0,0,0,0,0,AA39,0,0,0,0,0,0,0,0,0,0,0,0,0,0,0,0,0,0,0~
,0,0,0,0,0,0,0,0,0,0,0,0,0)';$S;OUT;
    'DDR3_ALERT_N':'(0,0,0,0,0,0,0,0,0,0,AV47,0,0,0,0,0,0,0,0,0,0,0,0,0,0,0,0,0,~
0,0,0,0,0,0,0,0,0,0,0,0,0,0)';$S;IN;
    'DDR3_A_RSP1':'(0,0,0,0,0,0,0,0,0,0,AC50,0,0,0,0,0,0,0,0,0,0,0,0,0,0,0,0,0,0~
,0,0,0,0,0,0,0,0,0,0,0,0,0)';$S;IN;
    'DDR3_A_RSP0':'(0,0,0,0,0,0,0,0,0,0,AD51,0,0,0,0,0,0,0,0,0,0,0,0,0,0,0,0,0,0~
,0,0,0,0,0,0,0,0,0,0,0,0,0)';$S;IN;
    'DDR3_B_RSP1':'(0,0,0,0,0,0,0,0,0,0,AG50,0,0,0,0,0,0,0,0,0,0,0,0,0,0,0,0,0,0~
,0,0,0,0,0,0,0,0,0,0,0,0,0)';$S;IN;
    'DDR3_B_RSP0':'(0,0,0,0,0,0,0,0,0,0,AF51,0,0,0,0,0,0,0,0,0,0,0,0,0,0,0,0,0,0~
,0,0,0,0,0,0,0,0,0,0,0,0,0)';$S;IN;
    'DDR3_CLK_DN1':'(0,0,0,0,0,0,0,0,0,0,AN45,0,0,0,0,0,0,0,0,0,0,0,0,0,0,0,0,0,~
0,0,0,0,0,0,0,0,0,0,0,0,0,0)';$S;OUT;
    'DDR3_CLK_DN0':'(0,0,0,0,0,0,0,0,0,0,AJ45,0,0,0,0,0,0,0,0,0,0,0,0,0,0,0,0,0,~
0,0,0,0,0,0,0,0,0,0,0,0,0,0)';$S;OUT;
    'DDR3_CLK_DP1':'(0,0,0,0,0,0,0,0,0,0,AR45,0,0,0,0,0,0,0,0,0,0,0,0,0,0,0,0,0,~
0,0,0,0,0,0,0,0,0,0,0,0,0,0)';$S;OUT;
    'DDR3_CLK_DP0':'(0,0,0,0,0,0,0,0,0,0,AL45,0,0,0,0,0,0,0,0,0,0,0,0,0,0,0,0,0,~
0,0,0,0,0,0,0,0,0,0,0,0,0,0)';$S;OUT;
    'DDR3_SA_CA6':'(0,0,0,0,0,0,0,0,0,0,AN43,0,0,0,0,0,0,0,0,0,0,0,0,0,0,0,0,0,0~
,0,0,0,0,0,0,0,0,0,0,0,0,0)';$S;OUT;
    'DDR3_SA_CA5':'(0,0,0,0,0,0,0,0,0,0,AN50,0,0,0,0,0,0,0,0,0,0,0,0,0,0,0,0,0,0~
,0,0,0,0,0,0,0,0,0,0,0,0,0)';$S;OUT;
    'DDR3_SA_CA4':'(0,0,0,0,0,0,0,0,0,0,AL50,0,0,0,0,0,0,0,0,0,0,0,0,0,0,0,0,0,0~
,0,0,0,0,0,0,0,0,0,0,0,0,0)';$S;OUT;
    'DDR3_SA_CA3':'(0,0,0,0,0,0,0,0,0,0,AP51,0,0,0,0,0,0,0,0,0,0,0,0,0,0,0,0,0,0~
,0,0,0,0,0,0,0,0,0,0,0,0,0)';$S;OUT;
    'DDR3_SA_CA2':'(0,0,0,0,0,0,0,0,0,0,AK51,0,0,0,0,0,0,0,0,0,0,0,0,0,0,0,0,0,0~
,0,0,0,0,0,0,0,0,0,0,0,0,0)';$S;OUT;
    'DDR3_SA_CA1':'(0,0,0,0,0,0,0,0,0,0,AR52,0,0,0,0,0,0,0,0,0,0,0,0,0,0,0,0,0,0~
,0,0,0,0,0,0,0,0,0,0,0,0,0)';$S;OUT;
    'DDR3_SA_CA0':'(0,0,0,0,0,0,0,0,0,0,AJ52,0,0,0,0,0,0,0,0,0,0,0,0,0,0,0,0,0,0~
,0,0,0,0,0,0,0,0,0,0,0,0,0)';$S;OUT;
    'DDR3_SA_CS_N3':'(0,0,0,0,0,0,0,0,0,0,AP53,0,0,0,0,0,0,0,0,0,0,0,0,0,0,0,0,0~
,0,0,0,0,0,0,0,0,0,0,0,0,0,0)';$S;OUT;
    'DDR3_SA_CS_N2':'(0,0,0,0,0,0,0,0,0,0,AN54,0,0,0,0,0,0,0,0,0,0,0,0,0,0,0,0,0~
,0,0,0,0,0,0,0,0,0,0,0,0,0,0)';$S;OUT;
    'DDR3_SA_CS_N1':'(0,0,0,0,0,0,0,0,0,0,AK53,0,0,0,0,0,0,0,0,0,0,0,0,0,0,0,0,0~
,0,0,0,0,0,0,0,0,0,0,0,0,0,0)';$S;OUT;
    'DDR3_SA_CS_N0':'(0,0,0,0,0,0,0,0,0,0,AL54,0,0,0,0,0,0,0,0,0,0,0,0,0,0,0,0,0~
,0,0,0,0,0,0,0,0,0,0,0,0,0,0)';$S;OUT;
    'DDR3_SA_DQ31':'(0,0,0,0,0,0,0,0,0,0,AN62,0,0,0,0,0,0,0,0,0,0,0,0,0,0,0,0,0,~
0,0,0,0,0,0,0,0,0,0,0,0,0,0)';$S;BIDI;
    'DDR3_SA_DQ30':'(0,0,0,0,0,0,0,0,0,0,AP63,0,0,0,0,0,0,0,0,0,0,0,0,0,0,0,0,0,~
0,0,0,0,0,0,0,0,0,0,0,0,0,0)';$S;BIDI;
    'DDR3_SA_DQ29':'(0,0,0,0,0,0,0,0,0,0,AL62,0,0,0,0,0,0,0,0,0,0,0,0,0,0,0,0,0,~
0,0,0,0,0,0,0,0,0,0,0,0,0,0)';$S;BIDI;
    'DDR3_SA_DQ28':'(0,0,0,0,0,0,0,0,0,0,AK63,0,0,0,0,0,0,0,0,0,0,0,0,0,0,0,0,0,~
0,0,0,0,0,0,0,0,0,0,0,0,0,0)';$S;BIDI;
    'DDR3_SA_DQ27':'(0,0,0,0,0,0,0,0,0,0,AP65,0,0,0,0,0,0,0,0,0,0,0,0,0,0,0,0,0,~
0,0,0,0,0,0,0,0,0,0,0,0,0,0)';$S;BIDI;
    'DDR3_SA_DQ26':'(0,0,0,0,0,0,0,0,0,0,AN66,0,0,0,0,0,0,0,0,0,0,0,0,0,0,0,0,0,~
0,0,0,0,0,0,0,0,0,0,0,0,0,0)';$S;BIDI;
    'DDR3_SA_DQ25':'(0,0,0,0,0,0,0,0,0,0,AK65,0,0,0,0,0,0,0,0,0,0,0,0,0,0,0,0,0,~
0,0,0,0,0,0,0,0,0,0,0,0,0,0)';$S;BIDI;
    'DDR3_SA_DQ24':'(0,0,0,0,0,0,0,0,0,0,AL66,0,0,0,0,0,0,0,0,0,0,0,0,0,0,0,0,0,~
0,0,0,0,0,0,0,0,0,0,0,0,0,0)';$S;BIDI;
    'DDR3_SA_DQ23':'(0,0,0,0,0,0,0,0,0,0,AN68,0,0,0,0,0,0,0,0,0,0,0,0,0,0,0,0,0,~
0,0,0,0,0,0,0,0,0,0,0,0,0,0)';$S;BIDI;
    'DDR3_SA_DQ22':'(0,0,0,0,0,0,0,0,0,0,AP69,0,0,0,0,0,0,0,0,0,0,0,0,0,0,0,0,0,~
0,0,0,0,0,0,0,0,0,0,0,0,0,0)';$S;BIDI;
    'DDR3_SA_DQ21':'(0,0,0,0,0,0,0,0,0,0,AL68,0,0,0,0,0,0,0,0,0,0,0,0,0,0,0,0,0,~
0,0,0,0,0,0,0,0,0,0,0,0,0,0)';$S;BIDI;
    'DDR3_SA_DQ20':'(0,0,0,0,0,0,0,0,0,0,AK69,0,0,0,0,0,0,0,0,0,0,0,0,0,0,0,0,0,~
0,0,0,0,0,0,0,0,0,0,0,0,0,0)';$S;BIDI;
    'DDR3_SA_DQ19':'(0,0,0,0,0,0,0,0,0,0,AP71,0,0,0,0,0,0,0,0,0,0,0,0,0,0,0,0,0,~
0,0,0,0,0,0,0,0,0,0,0,0,0,0)';$S;BIDI;
    'DDR3_SA_DQ18':'(0,0,0,0,0,0,0,0,0,0,AN72,0,0,0,0,0,0,0,0,0,0,0,0,0,0,0,0,0,~
0,0,0,0,0,0,0,0,0,0,0,0,0,0)';$S;BIDI;
    'DDR3_SA_DQ17':'(0,0,0,0,0,0,0,0,0,0,AK71,0,0,0,0,0,0,0,0,0,0,0,0,0,0,0,0,0,~
0,0,0,0,0,0,0,0,0,0,0,0,0,0)';$S;BIDI;
    'DDR3_SA_DQ16':'(0,0,0,0,0,0,0,0,0,0,AL72,0,0,0,0,0,0,0,0,0,0,0,0,0,0,0,0,0,~
0,0,0,0,0,0,0,0,0,0,0,0,0,0)';$S;BIDI;
    'DDR3_SA_DQ15':'(0,0,0,0,0,0,0,0,0,0,AN74,0,0,0,0,0,0,0,0,0,0,0,0,0,0,0,0,0,~
0,0,0,0,0,0,0,0,0,0,0,0,0,0)';$S;BIDI;
    'DDR3_SA_DQ14':'(0,0,0,0,0,0,0,0,0,0,AP75,0,0,0,0,0,0,0,0,0,0,0,0,0,0,0,0,0,~
0,0,0,0,0,0,0,0,0,0,0,0,0,0)';$S;BIDI;
    'DDR3_SA_DQ13':'(0,0,0,0,0,0,0,0,0,0,AL74,0,0,0,0,0,0,0,0,0,0,0,0,0,0,0,0,0,~
0,0,0,0,0,0,0,0,0,0,0,0,0,0)';$S;BIDI;
    'DDR3_SA_DQ12':'(0,0,0,0,0,0,0,0,0,0,AK75,0,0,0,0,0,0,0,0,0,0,0,0,0,0,0,0,0,~
0,0,0,0,0,0,0,0,0,0,0,0,0,0)';$S;BIDI;
    'DDR3_SA_DQ11':'(0,0,0,0,0,0,0,0,0,0,AP77,0,0,0,0,0,0,0,0,0,0,0,0,0,0,0,0,0,~
0,0,0,0,0,0,0,0,0,0,0,0,0,0)';$S;BIDI;
    'DDR3_SA_DQ10':'(0,0,0,0,0,0,0,0,0,0,AN78,0,0,0,0,0,0,0,0,0,0,0,0,0,0,0,0,0,~
0,0,0,0,0,0,0,0,0,0,0,0,0,0)';$S;BIDI;
    'DDR3_SA_DQ9':'(0,0,0,0,0,0,0,0,0,0,AK77,0,0,0,0,0,0,0,0,0,0,0,0,0,0,0,0,0,0~
,0,0,0,0,0,0,0,0,0,0,0,0,0)';$S;BIDI;
    'DDR3_SA_DQ8':'(0,0,0,0,0,0,0,0,0,0,AL78,0,0,0,0,0,0,0,0,0,0,0,0,0,0,0,0,0,0~
,0,0,0,0,0,0,0,0,0,0,0,0,0)';$S;BIDI;
    'DDR3_SA_DQ7':'(0,0,0,0,0,0,0,0,0,0,AF71,0,0,0,0,0,0,0,0,0,0,0,0,0,0,0,0,0,0~
,0,0,0,0,0,0,0,0,0,0,0,0,0)';$S;BIDI;
    'DDR3_SA_DQ6':'(0,0,0,0,0,0,0,0,0,0,AG72,0,0,0,0,0,0,0,0,0,0,0,0,0,0,0,0,0,0~
,0,0,0,0,0,0,0,0,0,0,0,0,0)';$S;BIDI;
    'DDR3_SA_DQ5':'(0,0,0,0,0,0,0,0,0,0,AD71,0,0,0,0,0,0,0,0,0,0,0,0,0,0,0,0,0,0~
,0,0,0,0,0,0,0,0,0,0,0,0,0)';$S;BIDI;
    'DDR3_SA_DQ4':'(0,0,0,0,0,0,0,0,0,0,AC72,0,0,0,0,0,0,0,0,0,0,0,0,0,0,0,0,0,0~
,0,0,0,0,0,0,0,0,0,0,0,0,0)';$S;BIDI;
    'DDR3_SA_DQ3':'(0,0,0,0,0,0,0,0,0,0,AG74,0,0,0,0,0,0,0,0,0,0,0,0,0,0,0,0,0,0~
,0,0,0,0,0,0,0,0,0,0,0,0,0)';$S;BIDI;
    'DDR3_SA_DQ2':'(0,0,0,0,0,0,0,0,0,0,AF75,0,0,0,0,0,0,0,0,0,0,0,0,0,0,0,0,0,0~
,0,0,0,0,0,0,0,0,0,0,0,0,0)';$S;BIDI;
    'DDR3_SA_DQ1':'(0,0,0,0,0,0,0,0,0,0,AC74,0,0,0,0,0,0,0,0,0,0,0,0,0,0,0,0,0,0~
,0,0,0,0,0,0,0,0,0,0,0,0,0)';$S;BIDI;
    'DDR3_SA_DQ0':'(0,0,0,0,0,0,0,0,0,0,AD75,0,0,0,0,0,0,0,0,0,0,0,0,0,0,0,0,0,0~
,0,0,0,0,0,0,0,0,0,0,0,0,0)';$S;BIDI;
    'DDR3_SA_DQS_DN9':'(0,0,0,0,0,0,0,0,0,0,AN58,0,0,0,0,0,0,0,0,0,0,0,0,0,0,0,0~
,0,0,0,0,0,0,0,0,0,0,0,0,0,0,0)';$S;BIDI;
    'DDR3_SA_DQS_DN8':'(0,0,0,0,0,0,0,0,0,0,AN64,0,0,0,0,0,0,0,0,0,0,0,0,0,0,0,0~
,0,0,0,0,0,0,0,0,0,0,0,0,0,0,0)';$S;BIDI;
    'DDR3_SA_DQS_DN7':'(0,0,0,0,0,0,0,0,0,0,AN70,0,0,0,0,0,0,0,0,0,0,0,0,0,0,0,0~
,0,0,0,0,0,0,0,0,0,0,0,0,0,0,0)';$S;BIDI;
    'DDR3_SA_DQS_DN6':'(0,0,0,0,0,0,0,0,0,0,AN76,0,0,0,0,0,0,0,0,0,0,0,0,0,0,0,0~
,0,0,0,0,0,0,0,0,0,0,0,0,0,0,0)';$S;BIDI;
    'DDR3_SA_DQS_DN5':'(0,0,0,0,0,0,0,0,0,0,AH73,0,0,0,0,0,0,0,0,0,0,0,0,0,0,0,0~
,0,0,0,0,0,0,0,0,0,0,0,0,0,0,0)';$S;BIDI;
    'DDR3_SA_DQS_DN4':'(0,0,0,0,0,0,0,0,0,0,AJ58,0,0,0,0,0,0,0,0,0,0,0,0,0,0,0,0~
,0,0,0,0,0,0,0,0,0,0,0,0,0,0,0)';$S;BIDI;
    'DDR3_SA_DQS_DN3':'(0,0,0,0,0,0,0,0,0,0,AJ64,0,0,0,0,0,0,0,0,0,0,0,0,0,0,0,0~
,0,0,0,0,0,0,0,0,0,0,0,0,0,0,0)';$S;BIDI;
    'DDR3_SA_DQS_DN2':'(0,0,0,0,0,0,0,0,0,0,AJ70,0,0,0,0,0,0,0,0,0,0,0,0,0,0,0,0~
,0,0,0,0,0,0,0,0,0,0,0,0,0,0,0)';$S;BIDI;
    'DDR3_SA_DQS_DN1':'(0,0,0,0,0,0,0,0,0,0,AJ76,0,0,0,0,0,0,0,0,0,0,0,0,0,0,0,0~
,0,0,0,0,0,0,0,0,0,0,0,0,0,0,0)';$S;BIDI;
    'DDR3_SA_DQS_DN0':'(0,0,0,0,0,0,0,0,0,0,AB73,0,0,0,0,0,0,0,0,0,0,0,0,0,0,0,0~
,0,0,0,0,0,0,0,0,0,0,0,0,0,0,0)';$S;BIDI;
    'DDR3_SA_DQS_DP9':'(0,0,0,0,0,0,0,0,0,0,AR58,0,0,0,0,0,0,0,0,0,0,0,0,0,0,0,0~
,0,0,0,0,0,0,0,0,0,0,0,0,0,0,0)';$S;BIDI;
    'DDR3_SA_DQS_DP8':'(0,0,0,0,0,0,0,0,0,0,AR64,0,0,0,0,0,0,0,0,0,0,0,0,0,0,0,0~
,0,0,0,0,0,0,0,0,0,0,0,0,0,0,0)';$S;BIDI;
    'DDR3_SA_DQS_DP7':'(0,0,0,0,0,0,0,0,0,0,AR70,0,0,0,0,0,0,0,0,0,0,0,0,0,0,0,0~
,0,0,0,0,0,0,0,0,0,0,0,0,0,0,0)';$S;BIDI;
    'DDR3_SA_DQS_DP6':'(0,0,0,0,0,0,0,0,0,0,AR76,0,0,0,0,0,0,0,0,0,0,0,0,0,0,0,0~
,0,0,0,0,0,0,0,0,0,0,0,0,0,0,0)';$S;BIDI;
    'DDR3_SA_DQS_DP5':'(0,0,0,0,0,0,0,0,0,0,AF73,0,0,0,0,0,0,0,0,0,0,0,0,0,0,0,0~
,0,0,0,0,0,0,0,0,0,0,0,0,0,0,0)';$S;BIDI;
    'DDR3_SA_DQS_DP4':'(0,0,0,0,0,0,0,0,0,0,AL58,0,0,0,0,0,0,0,0,0,0,0,0,0,0,0,0~
,0,0,0,0,0,0,0,0,0,0,0,0,0,0,0)';$S;BIDI;
    'DDR3_SA_DQS_DP3':'(0,0,0,0,0,0,0,0,0,0,AL64,0,0,0,0,0,0,0,0,0,0,0,0,0,0,0,0~
,0,0,0,0,0,0,0,0,0,0,0,0,0,0,0)';$S;BIDI;
    'DDR3_SA_DQS_DP2':'(0,0,0,0,0,0,0,0,0,0,AL70,0,0,0,0,0,0,0,0,0,0,0,0,0,0,0,0~
,0,0,0,0,0,0,0,0,0,0,0,0,0,0,0)';$S;BIDI;
    'DDR3_SA_DQS_DP1':'(0,0,0,0,0,0,0,0,0,0,AL76,0,0,0,0,0,0,0,0,0,0,0,0,0,0,0,0~
,0,0,0,0,0,0,0,0,0,0,0,0,0,0,0)';$S;BIDI;
    'DDR3_SA_DQS_DP0':'(0,0,0,0,0,0,0,0,0,0,AD73,0,0,0,0,0,0,0,0,0,0,0,0,0,0,0,0~
,0,0,0,0,0,0,0,0,0,0,0,0,0,0,0)';$S;BIDI;
    'DDR3_SA_ECC7':'(0,0,0,0,0,0,0,0,0,0,AN56,0,0,0,0,0,0,0,0,0,0,0,0,0,0,0,0,0,~
0,0,0,0,0,0,0,0,0,0,0,0,0,0)';$S;BIDI;
    'DDR3_SA_ECC6':'(0,0,0,0,0,0,0,0,0,0,AP57,0,0,0,0,0,0,0,0,0,0,0,0,0,0,0,0,0,~
0,0,0,0,0,0,0,0,0,0,0,0,0,0)';$S;BIDI;
    'DDR3_SA_ECC5':'(0,0,0,0,0,0,0,0,0,0,AL56,0,0,0,0,0,0,0,0,0,0,0,0,0,0,0,0,0,~
0,0,0,0,0,0,0,0,0,0,0,0,0,0)';$S;BIDI;
    'DDR3_SA_ECC4':'(0,0,0,0,0,0,0,0,0,0,AK57,0,0,0,0,0,0,0,0,0,0,0,0,0,0,0,0,0,~
0,0,0,0,0,0,0,0,0,0,0,0,0,0)';$S;BIDI;
    'DDR3_SA_ECC3':'(0,0,0,0,0,0,0,0,0,0,AP59,0,0,0,0,0,0,0,0,0,0,0,0,0,0,0,0,0,~
0,0,0,0,0,0,0,0,0,0,0,0,0,0)';$S;BIDI;
    'DDR3_SA_ECC2':'(0,0,0,0,0,0,0,0,0,0,AN60,0,0,0,0,0,0,0,0,0,0,0,0,0,0,0,0,0,~
0,0,0,0,0,0,0,0,0,0,0,0,0,0)';$S;BIDI;
    'DDR3_SA_ECC1':'(0,0,0,0,0,0,0,0,0,0,AK59,0,0,0,0,0,0,0,0,0,0,0,0,0,0,0,0,0,~
0,0,0,0,0,0,0,0,0,0,0,0,0,0)';$S;BIDI;
    'DDR3_SA_ECC0':'(0,0,0,0,0,0,0,0,0,0,AL60,0,0,0,0,0,0,0,0,0,0,0,0,0,0,0,0,0,~
0,0,0,0,0,0,0,0,0,0,0,0,0,0)';$S;BIDI;
    'DDR3_SA_PAR':'(0,0,0,0,0,0,0,0,0,0,AP44,0,0,0,0,0,0,0,0,0,0,0,0,0,0,0,0,0,0~
,0,0,0,0,0,0,0,0,0,0,0,0,0)';$S;OUT;
    'DDR3_SB_CA6':'(0,0,0,0,0,0,0,0,0,0,AB42,0,0,0,0,0,0,0,0,0,0,0,0,0,0,0,0,0,0~
,0,0,0,0,0,0,0,0,0,0,0,0,0)';$S;OUT;
    'DDR3_SB_CA5':'(0,0,0,0,0,0,0,0,0,0,AG43,0,0,0,0,0,0,0,0,0,0,0,0,0,0,0,0,0,0~
,0,0,0,0,0,0,0,0,0,0,0,0,0)';$S;OUT;
    'DDR3_SB_CA4':'(0,0,0,0,0,0,0,0,0,0,AC43,0,0,0,0,0,0,0,0,0,0,0,0,0,0,0,0,0,0~
,0,0,0,0,0,0,0,0,0,0,0,0,0)';$S;OUT;
    'DDR3_SB_CA3':'(0,0,0,0,0,0,0,0,0,0,AF44,0,0,0,0,0,0,0,0,0,0,0,0,0,0,0,0,0,0~
,0,0,0,0,0,0,0,0,0,0,0,0,0)';$S;OUT;
    'DDR3_SB_CA2':'(0,0,0,0,0,0,0,0,0,0,AD44,0,0,0,0,0,0,0,0,0,0,0,0,0,0,0,0,0,0~
,0,0,0,0,0,0,0,0,0,0,0,0,0)';$S;OUT;
    'DDR3_SB_CA1':'(0,0,0,0,0,0,0,0,0,0,AL43,0,0,0,0,0,0,0,0,0,0,0,0,0,0,0,0,0,0~
,0,0,0,0,0,0,0,0,0,0,0,0,0)';$S;OUT;
    'DDR3_SB_CA0':'(0,0,0,0,0,0,0,0,0,0,AK44,0,0,0,0,0,0,0,0,0,0,0,0,0,0,0,0,0,0~
,0,0,0,0,0,0,0,0,0,0,0,0,0)';$S;OUT;
    'DDR3_SB_CS_N3':'(0,0,0,0,0,0,0,0,0,0,AD40,0,0,0,0,0,0,0,0,0,0,0,0,0,0,0,0,0~
,0,0,0,0,0,0,0,0,0,0,0,0,0,0)';$S;OUT;
    'DDR3_SB_CS_N2':'(0,0,0,0,0,0,0,0,0,0,AF40,0,0,0,0,0,0,0,0,0,0,0,0,0,0,0,0,0~
,0,0,0,0,0,0,0,0,0,0,0,0,0,0)';$S;OUT;
    'DDR3_SB_CS_N1':'(0,0,0,0,0,0,0,0,0,0,AG41,0,0,0,0,0,0,0,0,0,0,0,0,0,0,0,0,0~
,0,0,0,0,0,0,0,0,0,0,0,0,0,0)';$S;OUT;
    'DDR3_SB_CS_N0':'(0,0,0,0,0,0,0,0,0,0,AC41,0,0,0,0,0,0,0,0,0,0,0,0,0,0,0,0,0~
,0,0,0,0,0,0,0,0,0,0,0,0,0,0)';$S;OUT;
    'DDR3_SB_DQ31':'(0,0,0,0,0,0,0,0,0,0,AN19,0,0,0,0,0,0,0,0,0,0,0,0,0,0,0,0,0,~
0,0,0,0,0,0,0,0,0,0,0,0,0,0)';$S;BIDI;
    'DDR3_SB_DQ30':'(0,0,0,0,0,0,0,0,0,0,AP20,0,0,0,0,0,0,0,0,0,0,0,0,0,0,0,0,0,~
0,0,0,0,0,0,0,0,0,0,0,0,0,0)';$S;BIDI;
    'DDR3_SB_DQ29':'(0,0,0,0,0,0,0,0,0,0,AL19,0,0,0,0,0,0,0,0,0,0,0,0,0,0,0,0,0,~
0,0,0,0,0,0,0,0,0,0,0,0,0,0)';$S;BIDI;
    'DDR3_SB_DQ28':'(0,0,0,0,0,0,0,0,0,0,AK20,0,0,0,0,0,0,0,0,0,0,0,0,0,0,0,0,0,~
0,0,0,0,0,0,0,0,0,0,0,0,0,0)';$S;BIDI;
    'DDR3_SB_DQ27':'(0,0,0,0,0,0,0,0,0,0,AP22,0,0,0,0,0,0,0,0,0,0,0,0,0,0,0,0,0,~
0,0,0,0,0,0,0,0,0,0,0,0,0,0)';$S;BIDI;
    'DDR3_SB_DQ26':'(0,0,0,0,0,0,0,0,0,0,AN23,0,0,0,0,0,0,0,0,0,0,0,0,0,0,0,0,0,~
0,0,0,0,0,0,0,0,0,0,0,0,0,0)';$S;BIDI;
    'DDR3_SB_DQ25':'(0,0,0,0,0,0,0,0,0,0,AK22,0,0,0,0,0,0,0,0,0,0,0,0,0,0,0,0,0,~
0,0,0,0,0,0,0,0,0,0,0,0,0,0)';$S;BIDI;
    'DDR3_SB_DQ24':'(0,0,0,0,0,0,0,0,0,0,AL23,0,0,0,0,0,0,0,0,0,0,0,0,0,0,0,0,0,~
0,0,0,0,0,0,0,0,0,0,0,0,0,0)';$S;BIDI;
    'DDR3_SB_DQ23':'(0,0,0,0,0,0,0,0,0,0,AF22,0,0,0,0,0,0,0,0,0,0,0,0,0,0,0,0,0,~
0,0,0,0,0,0,0,0,0,0,0,0,0,0)';$S;BIDI;
    'DDR3_SB_DQ22':'(0,0,0,0,0,0,0,0,0,0,AG23,0,0,0,0,0,0,0,0,0,0,0,0,0,0,0,0,0,~
0,0,0,0,0,0,0,0,0,0,0,0,0,0)';$S;BIDI;
    'DDR3_SB_DQ21':'(0,0,0,0,0,0,0,0,0,0,AD22,0,0,0,0,0,0,0,0,0,0,0,0,0,0,0,0,0,~
0,0,0,0,0,0,0,0,0,0,0,0,0,0)';$S;BIDI;
    'DDR3_SB_DQ20':'(0,0,0,0,0,0,0,0,0,0,AC23,0,0,0,0,0,0,0,0,0,0,0,0,0,0,0,0,0,~
0,0,0,0,0,0,0,0,0,0,0,0,0,0)';$S;BIDI;
    'DDR3_SB_DQ19':'(0,0,0,0,0,0,0,0,0,0,AG25,0,0,0,0,0,0,0,0,0,0,0,0,0,0,0,0,0,~
0,0,0,0,0,0,0,0,0,0,0,0,0,0)';$S;BIDI;
    'DDR3_SB_DQ18':'(0,0,0,0,0,0,0,0,0,0,AF26,0,0,0,0,0,0,0,0,0,0,0,0,0,0,0,0,0,~
0,0,0,0,0,0,0,0,0,0,0,0,0,0)';$S;BIDI;
    'DDR3_SB_DQ17':'(0,0,0,0,0,0,0,0,0,0,AC25,0,0,0,0,0,0,0,0,0,0,0,0,0,0,0,0,0,~
0,0,0,0,0,0,0,0,0,0,0,0,0,0)';$S;BIDI;
    'DDR3_SB_DQ16':'(0,0,0,0,0,0,0,0,0,0,AD26,0,0,0,0,0,0,0,0,0,0,0,0,0,0,0,0,0,~
0,0,0,0,0,0,0,0,0,0,0,0,0,0)';$S;BIDI;
    'DDR3_SB_DQ15':'(0,0,0,0,0,0,0,0,0,0,AN25,0,0,0,0,0,0,0,0,0,0,0,0,0,0,0,0,0,~
0,0,0,0,0,0,0,0,0,0,0,0,0,0)';$S;BIDI;
    'DDR3_SB_DQ14':'(0,0,0,0,0,0,0,0,0,0,AP26,0,0,0,0,0,0,0,0,0,0,0,0,0,0,0,0,0,~
0,0,0,0,0,0,0,0,0,0,0,0,0,0)';$S;BIDI;
    'DDR3_SB_DQ13':'(0,0,0,0,0,0,0,0,0,0,AL25,0,0,0,0,0,0,0,0,0,0,0,0,0,0,0,0,0,~
0,0,0,0,0,0,0,0,0,0,0,0,0,0)';$S;BIDI;
    'DDR3_SB_DQ12':'(0,0,0,0,0,0,0,0,0,0,AK26,0,0,0,0,0,0,0,0,0,0,0,0,0,0,0,0,0,~
0,0,0,0,0,0,0,0,0,0,0,0,0,0)';$S;BIDI;
    'DDR3_SB_DQ11':'(0,0,0,0,0,0,0,0,0,0,AP28,0,0,0,0,0,0,0,0,0,0,0,0,0,0,0,0,0,~
0,0,0,0,0,0,0,0,0,0,0,0,0,0)';$S;BIDI;
    'DDR3_SB_DQ10':'(0,0,0,0,0,0,0,0,0,0,AN29,0,0,0,0,0,0,0,0,0,0,0,0,0,0,0,0,0,~
0,0,0,0,0,0,0,0,0,0,0,0,0,0)';$S;BIDI;
    'DDR3_SB_DQ9':'(0,0,0,0,0,0,0,0,0,0,AK28,0,0,0,0,0,0,0,0,0,0,0,0,0,0,0,0,0,0~
,0,0,0,0,0,0,0,0,0,0,0,0,0)';$S;BIDI;
    'DDR3_SB_DQ8':'(0,0,0,0,0,0,0,0,0,0,AL29,0,0,0,0,0,0,0,0,0,0,0,0,0,0,0,0,0,0~
,0,0,0,0,0,0,0,0,0,0,0,0,0)';$S;BIDI;
    'DDR3_SB_DQ7':'(0,0,0,0,0,0,0,0,0,0,AN31,0,0,0,0,0,0,0,0,0,0,0,0,0,0,0,0,0,0~
,0,0,0,0,0,0,0,0,0,0,0,0,0)';$S;BIDI;
    'DDR3_SB_DQ6':'(0,0,0,0,0,0,0,0,0,0,AP32,0,0,0,0,0,0,0,0,0,0,0,0,0,0,0,0,0,0~
,0,0,0,0,0,0,0,0,0,0,0,0,0)';$S;BIDI;
    'DDR3_SB_DQ5':'(0,0,0,0,0,0,0,0,0,0,AL31,0,0,0,0,0,0,0,0,0,0,0,0,0,0,0,0,0,0~
,0,0,0,0,0,0,0,0,0,0,0,0,0)';$S;BIDI;
    'DDR3_SB_DQ4':'(0,0,0,0,0,0,0,0,0,0,AK32,0,0,0,0,0,0,0,0,0,0,0,0,0,0,0,0,0,0~
,0,0,0,0,0,0,0,0,0,0,0,0,0)';$S;BIDI;
    'DDR3_SB_DQ3':'(0,0,0,0,0,0,0,0,0,0,AP34,0,0,0,0,0,0,0,0,0,0,0,0,0,0,0,0,0,0~
,0,0,0,0,0,0,0,0,0,0,0,0,0)';$S;BIDI;
    'DDR3_SB_DQ2':'(0,0,0,0,0,0,0,0,0,0,AN35,0,0,0,0,0,0,0,0,0,0,0,0,0,0,0,0,0,0~
,0,0,0,0,0,0,0,0,0,0,0,0,0)';$S;BIDI;
    'DDR3_SB_DQ1':'(0,0,0,0,0,0,0,0,0,0,AK34,0,0,0,0,0,0,0,0,0,0,0,0,0,0,0,0,0,0~
,0,0,0,0,0,0,0,0,0,0,0,0,0)';$S;BIDI;
    'DDR3_SB_DQ0':'(0,0,0,0,0,0,0,0,0,0,AL35,0,0,0,0,0,0,0,0,0,0,0,0,0,0,0,0,0,0~
,0,0,0,0,0,0,0,0,0,0,0,0,0)';$S;BIDI;
    'DDR3_SB_DQS_DN9':'(0,0,0,0,0,0,0,0,0,0,AJ39,0,0,0,0,0,0,0,0,0,0,0,0,0,0,0,0~
,0,0,0,0,0,0,0,0,0,0,0,0,0,0,0)';$S;BIDI;
    'DDR3_SB_DQS_DN8':'(0,0,0,0,0,0,0,0,0,0,AN21,0,0,0,0,0,0,0,0,0,0,0,0,0,0,0,0~
,0,0,0,0,0,0,0,0,0,0,0,0,0,0,0)';$S;BIDI;
    'DDR3_SB_DQS_DN7':'(0,0,0,0,0,0,0,0,0,0,AF24,0,0,0,0,0,0,0,0,0,0,0,0,0,0,0,0~
,0,0,0,0,0,0,0,0,0,0,0,0,0,0,0)';$S;BIDI;
    'DDR3_SB_DQS_DN6':'(0,0,0,0,0,0,0,0,0,0,AN27,0,0,0,0,0,0,0,0,0,0,0,0,0,0,0,0~
,0,0,0,0,0,0,0,0,0,0,0,0,0,0,0)';$S;BIDI;
    'DDR3_SB_DQS_DN5':'(0,0,0,0,0,0,0,0,0,0,AN33,0,0,0,0,0,0,0,0,0,0,0,0,0,0,0,0~
,0,0,0,0,0,0,0,0,0,0,0,0,0,0,0)';$S;BIDI;
    'DDR3_SB_DQS_DN4':'(0,0,0,0,0,0,0,0,0,0,AR39,0,0,0,0,0,0,0,0,0,0,0,0,0,0,0,0~
,0,0,0,0,0,0,0,0,0,0,0,0,0,0,0)';$S;BIDI;
    'DDR3_SB_DQS_DN3':'(0,0,0,0,0,0,0,0,0,0,AJ21,0,0,0,0,0,0,0,0,0,0,0,0,0,0,0,0~
,0,0,0,0,0,0,0,0,0,0,0,0,0,0,0)';$S;BIDI;
    'DDR3_SB_DQS_DN2':'(0,0,0,0,0,0,0,0,0,0,AB24,0,0,0,0,0,0,0,0,0,0,0,0,0,0,0,0~
,0,0,0,0,0,0,0,0,0,0,0,0,0,0,0)';$S;BIDI;
    'DDR3_SB_DQS_DN1':'(0,0,0,0,0,0,0,0,0,0,AJ27,0,0,0,0,0,0,0,0,0,0,0,0,0,0,0,0~
,0,0,0,0,0,0,0,0,0,0,0,0,0,0,0)';$S;BIDI;
    'DDR3_SB_DQS_DN0':'(0,0,0,0,0,0,0,0,0,0,AJ33,0,0,0,0,0,0,0,0,0,0,0,0,0,0,0,0~
,0,0,0,0,0,0,0,0,0,0,0,0,0,0,0)';$S;BIDI;
    'DDR3_SB_DQS_DP9':'(0,0,0,0,0,0,0,0,0,0,AL39,0,0,0,0,0,0,0,0,0,0,0,0,0,0,0,0~
,0,0,0,0,0,0,0,0,0,0,0,0,0,0,0)';$S;BIDI;
    'DDR3_SB_DQS_DP8':'(0,0,0,0,0,0,0,0,0,0,AR21,0,0,0,0,0,0,0,0,0,0,0,0,0,0,0,0~
,0,0,0,0,0,0,0,0,0,0,0,0,0,0,0)';$S;BIDI;
    'DDR3_SB_DQS_DP7':'(0,0,0,0,0,0,0,0,0,0,AH24,0,0,0,0,0,0,0,0,0,0,0,0,0,0,0,0~
,0,0,0,0,0,0,0,0,0,0,0,0,0,0,0)';$S;BIDI;
    'DDR3_SB_DQS_DP6':'(0,0,0,0,0,0,0,0,0,0,AR27,0,0,0,0,0,0,0,0,0,0,0,0,0,0,0,0~
,0,0,0,0,0,0,0,0,0,0,0,0,0,0,0)';$S;BIDI;
    'DDR3_SB_DQS_DP5':'(0,0,0,0,0,0,0,0,0,0,AR33,0,0,0,0,0,0,0,0,0,0,0,0,0,0,0,0~
,0,0,0,0,0,0,0,0,0,0,0,0,0,0,0)';$S;BIDI;
    'DDR3_SB_DQS_DP4':'(0,0,0,0,0,0,0,0,0,0,AN39,0,0,0,0,0,0,0,0,0,0,0,0,0,0,0,0~
,0,0,0,0,0,0,0,0,0,0,0,0,0,0,0)';$S;BIDI;
    'DDR3_SB_DQS_DP3':'(0,0,0,0,0,0,0,0,0,0,AL21,0,0,0,0,0,0,0,0,0,0,0,0,0,0,0,0~
,0,0,0,0,0,0,0,0,0,0,0,0,0,0,0)';$S;BIDI;
    'DDR3_SB_DQS_DP2':'(0,0,0,0,0,0,0,0,0,0,AD24,0,0,0,0,0,0,0,0,0,0,0,0,0,0,0,0~
,0,0,0,0,0,0,0,0,0,0,0,0,0,0,0)';$S;BIDI;
    'DDR3_SB_DQS_DP1':'(0,0,0,0,0,0,0,0,0,0,AL27,0,0,0,0,0,0,0,0,0,0,0,0,0,0,0,0~
,0,0,0,0,0,0,0,0,0,0,0,0,0,0,0)';$S;BIDI;
    'DDR3_SB_DQS_DP0':'(0,0,0,0,0,0,0,0,0,0,AL33,0,0,0,0,0,0,0,0,0,0,0,0,0,0,0,0~
,0,0,0,0,0,0,0,0,0,0,0,0,0,0,0)';$S;BIDI;
    'DDR3_SB_ECC7':'(0,0,0,0,0,0,0,0,0,0,AP40,0,0,0,0,0,0,0,0,0,0,0,0,0,0,0,0,0,~
0,0,0,0,0,0,0,0,0,0,0,0,0,0)';$S;BIDI;
    'DDR3_SB_ECC6':'(0,0,0,0,0,0,0,0,0,0,AN41,0,0,0,0,0,0,0,0,0,0,0,0,0,0,0,0,0,~
0,0,0,0,0,0,0,0,0,0,0,0,0,0)';$S;BIDI;
    'DDR3_SB_ECC5':'(0,0,0,0,0,0,0,0,0,0,AK40,0,0,0,0,0,0,0,0,0,0,0,0,0,0,0,0,0,~
0,0,0,0,0,0,0,0,0,0,0,0,0,0)';$S;BIDI;
    'DDR3_SB_ECC4':'(0,0,0,0,0,0,0,0,0,0,AL41,0,0,0,0,0,0,0,0,0,0,0,0,0,0,0,0,0,~
0,0,0,0,0,0,0,0,0,0,0,0,0,0)';$S;BIDI;
    'DDR3_SB_ECC3':'(0,0,0,0,0,0,0,0,0,0,AN37,0,0,0,0,0,0,0,0,0,0,0,0,0,0,0,0,0,~
0,0,0,0,0,0,0,0,0,0,0,0,0,0)';$S;BIDI;
    'DDR3_SB_ECC2':'(0,0,0,0,0,0,0,0,0,0,AP38,0,0,0,0,0,0,0,0,0,0,0,0,0,0,0,0,0,~
0,0,0,0,0,0,0,0,0,0,0,0,0,0)';$S;BIDI;
    'DDR3_SB_ECC1':'(0,0,0,0,0,0,0,0,0,0,AL37,0,0,0,0,0,0,0,0,0,0,0,0,0,0,0,0,0,~
0,0,0,0,0,0,0,0,0,0,0,0,0,0)';$S;BIDI;
    'DDR3_SB_ECC0':'(0,0,0,0,0,0,0,0,0,0,AK38,0,0,0,0,0,0,0,0,0,0,0,0,0,0,0,0,0,~
0,0,0,0,0,0,0,0,0,0,0,0,0,0)';$S;BIDI;
    'DDR3_SB_PAR':'(0,0,0,0,0,0,0,0,0,0,AH42,0,0,0,0,0,0,0,0,0,0,0,0,0,0,0,0,0,0~
,0,0,0,0,0,0,0,0,0,0,0,0,0)';$S;OUT;
    'DDR4_ALERT_N':'(0,0,0,0,0,0,0,0,0,0,0,CY47,0,0,0,0,0,0,0,0,0,0,0,0,0,0,0,0,~
0,0,0,0,0,0,0,0,0,0,0,0,0,0)';$S;IN;
    'DDR4_A_RSP1':'(0,0,0,0,0,0,0,0,0,0,0,DC43,0,0,0,0,0,0,0,0,0,0,0,0,0,0,0,0,0~
,0,0,0,0,0,0,0,0,0,0,0,0,0)';$S;IN;
    'DDR4_A_RSP0':'(0,0,0,0,0,0,0,0,0,0,0,DD44,0,0,0,0,0,0,0,0,0,0,0,0,0,0,0,0,0~
,0,0,0,0,0,0,0,0,0,0,0,0,0)';$S;IN;
    'DDR4_B_RSP1':'(0,0,0,0,0,0,0,0,0,0,0,DG43,0,0,0,0,0,0,0,0,0,0,0,0,0,0,0,0,0~
,0,0,0,0,0,0,0,0,0,0,0,0,0)';$S;IN;
    'DDR4_B_RSP0':'(0,0,0,0,0,0,0,0,0,0,0,DF44,0,0,0,0,0,0,0,0,0,0,0,0,0,0,0,0,0~
,0,0,0,0,0,0,0,0,0,0,0,0,0)';$S;IN;
    'DDR4_CLK_DN1':'(0,0,0,0,0,0,0,0,0,0,0,EE45,0,0,0,0,0,0,0,0,0,0,0,0,0,0,0,0,~
0,0,0,0,0,0,0,0,0,0,0,0,0,0)';$S;OUT;
    'DDR4_CLK_DN0':'(0,0,0,0,0,0,0,0,0,0,0,EJ45,0,0,0,0,0,0,0,0,0,0,0,0,0,0,0,0,~
0,0,0,0,0,0,0,0,0,0,0,0,0,0)';$S;OUT;
    'DDR4_CLK_DP1':'(0,0,0,0,0,0,0,0,0,0,0,EC45,0,0,0,0,0,0,0,0,0,0,0,0,0,0,0,0,~
0,0,0,0,0,0,0,0,0,0,0,0,0,0)';$S;OUT;
    'DDR4_CLK_DP0':'(0,0,0,0,0,0,0,0,0,0,0,EG45,0,0,0,0,0,0,0,0,0,0,0,0,0,0,0,0,~
0,0,0,0,0,0,0,0,0,0,0,0,0,0)';$S;OUT;
    'DDR4_SA_CA6':'(0,0,0,0,0,0,0,0,0,0,0,ED44,0,0,0,0,0,0,0,0,0,0,0,0,0,0,0,0,0~
,0,0,0,0,0,0,0,0,0,0,0,0,0)';$S;OUT;
    'DDR4_SA_CA5':'(0,0,0,0,0,0,0,0,0,0,0,EP47,0,0,0,0,0,0,0,0,0,0,0,0,0,0,0,0,0~
,0,0,0,0,0,0,0,0,0,0,0,0,0)';$S;OUT;
    'DDR4_SA_CA4':'(0,0,0,0,0,0,0,0,0,0,0,EM47,0,0,0,0,0,0,0,0,0,0,0,0,0,0,0,0,0~
,0,0,0,0,0,0,0,0,0,0,0,0,0)';$S;OUT;
    'DDR4_SA_CA3':'(0,0,0,0,0,0,0,0,0,0,0,EL48,0,0,0,0,0,0,0,0,0,0,0,0,0,0,0,0,0~
,0,0,0,0,0,0,0,0,0,0,0,0,0)';$S;OUT;
    'DDR4_SA_CA2':'(0,0,0,0,0,0,0,0,0,0,0,EK49,0,0,0,0,0,0,0,0,0,0,0,0,0,0,0,0,0~
,0,0,0,0,0,0,0,0,0,0,0,0,0)';$S;OUT;
    'DDR4_SA_CA1':'(0,0,0,0,0,0,0,0,0,0,0,ET49,0,0,0,0,0,0,0,0,0,0,0,0,0,0,0,0,0~
,0,0,0,0,0,0,0,0,0,0,0,0,0)';$S;OUT;
    'DDR4_SA_CA0':'(0,0,0,0,0,0,0,0,0,0,0,EP49,0,0,0,0,0,0,0,0,0,0,0,0,0,0,0,0,0~
,0,0,0,0,0,0,0,0,0,0,0,0,0)';$S;OUT;
    'DDR4_SA_CS_N3':'(0,0,0,0,0,0,0,0,0,0,0,EL50,0,0,0,0,0,0,0,0,0,0,0,0,0,0,0,0~
,0,0,0,0,0,0,0,0,0,0,0,0,0,0)';$S;OUT;
    'DDR4_SA_CS_N2':'(0,0,0,0,0,0,0,0,0,0,0,EM51,0,0,0,0,0,0,0,0,0,0,0,0,0,0,0,0~
,0,0,0,0,0,0,0,0,0,0,0,0,0,0)';$S;OUT;
    'DDR4_SA_CS_N1':'(0,0,0,0,0,0,0,0,0,0,0,ET51,0,0,0,0,0,0,0,0,0,0,0,0,0,0,0,0~
,0,0,0,0,0,0,0,0,0,0,0,0,0,0)';$S;OUT;
    'DDR4_SA_CS_N0':'(0,0,0,0,0,0,0,0,0,0,0,EP51,0,0,0,0,0,0,0,0,0,0,0,0,0,0,0,0~
,0,0,0,0,0,0,0,0,0,0,0,0,0,0)';$S;OUT;
    'DDR4_SA_DQ31':'(0,0,0,0,0,0,0,0,0,0,0,EP59,0,0,0,0,0,0,0,0,0,0,0,0,0,0,0,0,~
0,0,0,0,0,0,0,0,0,0,0,0,0,0)';$S;BIDI;
    'DDR4_SA_DQ30':'(0,0,0,0,0,0,0,0,0,0,0,ER60,0,0,0,0,0,0,0,0,0,0,0,0,0,0,0,0,~
0,0,0,0,0,0,0,0,0,0,0,0,0,0)';$S;BIDI;
    'DDR4_SA_DQ29':'(0,0,0,0,0,0,0,0,0,0,0,EM59,0,0,0,0,0,0,0,0,0,0,0,0,0,0,0,0,~
0,0,0,0,0,0,0,0,0,0,0,0,0,0)';$S;BIDI;
    'DDR4_SA_DQ28':'(0,0,0,0,0,0,0,0,0,0,0,EL60,0,0,0,0,0,0,0,0,0,0,0,0,0,0,0,0,~
0,0,0,0,0,0,0,0,0,0,0,0,0,0)';$S;BIDI;
    'DDR4_SA_DQ27':'(0,0,0,0,0,0,0,0,0,0,0,ER62,0,0,0,0,0,0,0,0,0,0,0,0,0,0,0,0,~
0,0,0,0,0,0,0,0,0,0,0,0,0,0)';$S;BIDI;
    'DDR4_SA_DQ26':'(0,0,0,0,0,0,0,0,0,0,0,EP63,0,0,0,0,0,0,0,0,0,0,0,0,0,0,0,0,~
0,0,0,0,0,0,0,0,0,0,0,0,0,0)';$S;BIDI;
    'DDR4_SA_DQ25':'(0,0,0,0,0,0,0,0,0,0,0,EL62,0,0,0,0,0,0,0,0,0,0,0,0,0,0,0,0,~
0,0,0,0,0,0,0,0,0,0,0,0,0,0)';$S;BIDI;
    'DDR4_SA_DQ24':'(0,0,0,0,0,0,0,0,0,0,0,EM63,0,0,0,0,0,0,0,0,0,0,0,0,0,0,0,0,~
0,0,0,0,0,0,0,0,0,0,0,0,0,0)';$S;BIDI;
    'DDR4_SA_DQ23':'(0,0,0,0,0,0,0,0,0,0,0,EP65,0,0,0,0,0,0,0,0,0,0,0,0,0,0,0,0,~
0,0,0,0,0,0,0,0,0,0,0,0,0,0)';$S;BIDI;
    'DDR4_SA_DQ22':'(0,0,0,0,0,0,0,0,0,0,0,EL66,0,0,0,0,0,0,0,0,0,0,0,0,0,0,0,0,~
0,0,0,0,0,0,0,0,0,0,0,0,0,0)';$S;BIDI;
    'DDR4_SA_DQ21':'(0,0,0,0,0,0,0,0,0,0,0,EM65,0,0,0,0,0,0,0,0,0,0,0,0,0,0,0,0,~
0,0,0,0,0,0,0,0,0,0,0,0,0,0)';$S;BIDI;
    'DDR4_SA_DQ20':'(0,0,0,0,0,0,0,0,0,0,0,ER66,0,0,0,0,0,0,0,0,0,0,0,0,0,0,0,0,~
0,0,0,0,0,0,0,0,0,0,0,0,0,0)';$S;BIDI;
    'DDR4_SA_DQ19':'(0,0,0,0,0,0,0,0,0,0,0,ER68,0,0,0,0,0,0,0,0,0,0,0,0,0,0,0,0,~
0,0,0,0,0,0,0,0,0,0,0,0,0,0)';$S;BIDI;
    'DDR4_SA_DQ18':'(0,0,0,0,0,0,0,0,0,0,0,EN70,0,0,0,0,0,0,0,0,0,0,0,0,0,0,0,0,~
0,0,0,0,0,0,0,0,0,0,0,0,0,0)';$S;BIDI;
    'DDR4_SA_DQ17':'(0,0,0,0,0,0,0,0,0,0,0,EM69,0,0,0,0,0,0,0,0,0,0,0,0,0,0,0,0,~
0,0,0,0,0,0,0,0,0,0,0,0,0,0)';$S;BIDI;
    'DDR4_SA_DQ16':'(0,0,0,0,0,0,0,0,0,0,0,EM71,0,0,0,0,0,0,0,0,0,0,0,0,0,0,0,0,~
0,0,0,0,0,0,0,0,0,0,0,0,0,0)';$S;BIDI;
    'DDR4_SA_DQ15':'(0,0,0,0,0,0,0,0,0,0,0,EG68,0,0,0,0,0,0,0,0,0,0,0,0,0,0,0,0,~
0,0,0,0,0,0,0,0,0,0,0,0,0,0)';$S;BIDI;
    'DDR4_SA_DQ14':'(0,0,0,0,0,0,0,0,0,0,0,EH69,0,0,0,0,0,0,0,0,0,0,0,0,0,0,0,0,~
0,0,0,0,0,0,0,0,0,0,0,0,0,0)';$S;BIDI;
    'DDR4_SA_DQ13':'(0,0,0,0,0,0,0,0,0,0,0,EE68,0,0,0,0,0,0,0,0,0,0,0,0,0,0,0,0,~
0,0,0,0,0,0,0,0,0,0,0,0,0,0)';$S;BIDI;
    'DDR4_SA_DQ12':'(0,0,0,0,0,0,0,0,0,0,0,ED69,0,0,0,0,0,0,0,0,0,0,0,0,0,0,0,0,~
0,0,0,0,0,0,0,0,0,0,0,0,0,0)';$S;BIDI;
    'DDR4_SA_DQ11':'(0,0,0,0,0,0,0,0,0,0,0,EH71,0,0,0,0,0,0,0,0,0,0,0,0,0,0,0,0,~
0,0,0,0,0,0,0,0,0,0,0,0,0,0)';$S;BIDI;
    'DDR4_SA_DQ10':'(0,0,0,0,0,0,0,0,0,0,0,EG72,0,0,0,0,0,0,0,0,0,0,0,0,0,0,0,0,~
0,0,0,0,0,0,0,0,0,0,0,0,0,0)';$S;BIDI;
    'DDR4_SA_DQ9':'(0,0,0,0,0,0,0,0,0,0,0,ED71,0,0,0,0,0,0,0,0,0,0,0,0,0,0,0,0,0~
,0,0,0,0,0,0,0,0,0,0,0,0,0)';$S;BIDI;
    'DDR4_SA_DQ8':'(0,0,0,0,0,0,0,0,0,0,0,EE72,0,0,0,0,0,0,0,0,0,0,0,0,0,0,0,0,0~
,0,0,0,0,0,0,0,0,0,0,0,0,0)';$S;BIDI;
    'DDR4_SA_DQ7':'(0,0,0,0,0,0,0,0,0,0,0,ER72,0,0,0,0,0,0,0,0,0,0,0,0,0,0,0,0,0~
,0,0,0,0,0,0,0,0,0,0,0,0,0)';$S;BIDI;
    'DDR4_SA_DQ6':'(0,0,0,0,0,0,0,0,0,0,0,EP73,0,0,0,0,0,0,0,0,0,0,0,0,0,0,0,0,0~
,0,0,0,0,0,0,0,0,0,0,0,0,0)';$S;BIDI;
    'DDR4_SA_DQ5':'(0,0,0,0,0,0,0,0,0,0,0,EK73,0,0,0,0,0,0,0,0,0,0,0,0,0,0,0,0,0~
,0,0,0,0,0,0,0,0,0,0,0,0,0)';$S;BIDI;
    'DDR4_SA_DQ4':'(0,0,0,0,0,0,0,0,0,0,0,EL74,0,0,0,0,0,0,0,0,0,0,0,0,0,0,0,0,0~
,0,0,0,0,0,0,0,0,0,0,0,0,0)';$S;BIDI;
    'DDR4_SA_DQ3':'(0,0,0,0,0,0,0,0,0,0,0,ER76,0,0,0,0,0,0,0,0,0,0,0,0,0,0,0,0,0~
,0,0,0,0,0,0,0,0,0,0,0,0,0)';$S;BIDI;
    'DDR4_SA_DQ2':'(0,0,0,0,0,0,0,0,0,0,0,EP79,0,0,0,0,0,0,0,0,0,0,0,0,0,0,0,0,0~
,0,0,0,0,0,0,0,0,0,0,0,0,0)';$S;BIDI;
    'DDR4_SA_DQ1':'(0,0,0,0,0,0,0,0,0,0,0,EM77,0,0,0,0,0,0,0,0,0,0,0,0,0,0,0,0,0~
,0,0,0,0,0,0,0,0,0,0,0,0,0)';$S;BIDI;
    'DDR4_SA_DQ0':'(0,0,0,0,0,0,0,0,0,0,0,EL78,0,0,0,0,0,0,0,0,0,0,0,0,0,0,0,0,0~
,0,0,0,0,0,0,0,0,0,0,0,0,0)';$S;BIDI;
    'DDR4_SA_DQS_DN9':'(0,0,0,0,0,0,0,0,0,0,0,ET55,0,0,0,0,0,0,0,0,0,0,0,0,0,0,0~
,0,0,0,0,0,0,0,0,0,0,0,0,0,0,0)';$S;BIDI;
    'DDR4_SA_DQS_DN8':'(0,0,0,0,0,0,0,0,0,0,0,ET61,0,0,0,0,0,0,0,0,0,0,0,0,0,0,0~
,0,0,0,0,0,0,0,0,0,0,0,0,0,0,0)';$S;BIDI;
    'DDR4_SA_DQS_DN7':'(0,0,0,0,0,0,0,0,0,0,0,EN68,0,0,0,0,0,0,0,0,0,0,0,0,0,0,0~
,0,0,0,0,0,0,0,0,0,0,0,0,0,0,0)';$S;BIDI;
    'DDR4_SA_DQS_DN6':'(0,0,0,0,0,0,0,0,0,0,0,EJ70,0,0,0,0,0,0,0,0,0,0,0,0,0,0,0~
,0,0,0,0,0,0,0,0,0,0,0,0,0,0,0)';$S;BIDI;
    'DDR4_SA_DQS_DN5':'(0,0,0,0,0,0,0,0,0,0,0,EM75,0,0,0,0,0,0,0,0,0,0,0,0,0,0,0~
,0,0,0,0,0,0,0,0,0,0,0,0,0,0,0)';$S;BIDI;
    'DDR4_SA_DQS_DN4':'(0,0,0,0,0,0,0,0,0,0,0,EM55,0,0,0,0,0,0,0,0,0,0,0,0,0,0,0~
,0,0,0,0,0,0,0,0,0,0,0,0,0,0,0)';$S;BIDI;
    'DDR4_SA_DQS_DN3':'(0,0,0,0,0,0,0,0,0,0,0,EK61,0,0,0,0,0,0,0,0,0,0,0,0,0,0,0~
,0,0,0,0,0,0,0,0,0,0,0,0,0,0,0)';$S;BIDI;
    'DDR4_SA_DQS_DN2':'(0,0,0,0,0,0,0,0,0,0,0,EK67,0,0,0,0,0,0,0,0,0,0,0,0,0,0,0~
,0,0,0,0,0,0,0,0,0,0,0,0,0,0,0)';$S;BIDI;
    'DDR4_SA_DQS_DN1':'(0,0,0,0,0,0,0,0,0,0,0,EC70,0,0,0,0,0,0,0,0,0,0,0,0,0,0,0~
,0,0,0,0,0,0,0,0,0,0,0,0,0,0,0)';$S;BIDI;
    'DDR4_SA_DQS_DN0':'(0,0,0,0,0,0,0,0,0,0,0,EP75,0,0,0,0,0,0,0,0,0,0,0,0,0,0,0~
,0,0,0,0,0,0,0,0,0,0,0,0,0,0,0)';$S;BIDI;
    'DDR4_SA_DQS_DP9':'(0,0,0,0,0,0,0,0,0,0,0,EP55,0,0,0,0,0,0,0,0,0,0,0,0,0,0,0~
,0,0,0,0,0,0,0,0,0,0,0,0,0,0,0)';$S;BIDI;
    'DDR4_SA_DQS_DP8':'(0,0,0,0,0,0,0,0,0,0,0,EP61,0,0,0,0,0,0,0,0,0,0,0,0,0,0,0~
,0,0,0,0,0,0,0,0,0,0,0,0,0,0,0)';$S;BIDI;
    'DDR4_SA_DQS_DP7':'(0,0,0,0,0,0,0,0,0,0,0,EM67,0,0,0,0,0,0,0,0,0,0,0,0,0,0,0~
,0,0,0,0,0,0,0,0,0,0,0,0,0,0,0)';$S;BIDI;
    'DDR4_SA_DQS_DP6':'(0,0,0,0,0,0,0,0,0,0,0,EG70,0,0,0,0,0,0,0,0,0,0,0,0,0,0,0~
,0,0,0,0,0,0,0,0,0,0,0,0,0,0,0)';$S;BIDI;
    'DDR4_SA_DQS_DP5':'(0,0,0,0,0,0,0,0,0,0,0,EN74,0,0,0,0,0,0,0,0,0,0,0,0,0,0,0~
,0,0,0,0,0,0,0,0,0,0,0,0,0,0,0)';$S;BIDI;
    'DDR4_SA_DQS_DP4':'(0,0,0,0,0,0,0,0,0,0,0,EK55,0,0,0,0,0,0,0,0,0,0,0,0,0,0,0~
,0,0,0,0,0,0,0,0,0,0,0,0,0,0,0)';$S;BIDI;
    'DDR4_SA_DQS_DP3':'(0,0,0,0,0,0,0,0,0,0,0,EM61,0,0,0,0,0,0,0,0,0,0,0,0,0,0,0~
,0,0,0,0,0,0,0,0,0,0,0,0,0,0,0)';$S;BIDI;
    'DDR4_SA_DQS_DP2':'(0,0,0,0,0,0,0,0,0,0,0,EL68,0,0,0,0,0,0,0,0,0,0,0,0,0,0,0~
,0,0,0,0,0,0,0,0,0,0,0,0,0,0,0)';$S;BIDI;
    'DDR4_SA_DQS_DP1':'(0,0,0,0,0,0,0,0,0,0,0,EE70,0,0,0,0,0,0,0,0,0,0,0,0,0,0,0~
,0,0,0,0,0,0,0,0,0,0,0,0,0,0,0)';$S;BIDI;
    'DDR4_SA_DQS_DP0':'(0,0,0,0,0,0,0,0,0,0,0,EN76,0,0,0,0,0,0,0,0,0,0,0,0,0,0,0~
,0,0,0,0,0,0,0,0,0,0,0,0,0,0,0)';$S;BIDI;
    'DDR4_SA_ECC7':'(0,0,0,0,0,0,0,0,0,0,0,EP53,0,0,0,0,0,0,0,0,0,0,0,0,0,0,0,0,~
0,0,0,0,0,0,0,0,0,0,0,0,0,0)';$S;BIDI;
    'DDR4_SA_ECC6':'(0,0,0,0,0,0,0,0,0,0,0,ER54,0,0,0,0,0,0,0,0,0,0,0,0,0,0,0,0,~
0,0,0,0,0,0,0,0,0,0,0,0,0,0)';$S;BIDI;
    'DDR4_SA_ECC5':'(0,0,0,0,0,0,0,0,0,0,0,EM53,0,0,0,0,0,0,0,0,0,0,0,0,0,0,0,0,~
0,0,0,0,0,0,0,0,0,0,0,0,0,0)';$S;BIDI;
    'DDR4_SA_ECC4':'(0,0,0,0,0,0,0,0,0,0,0,EL54,0,0,0,0,0,0,0,0,0,0,0,0,0,0,0,0,~
0,0,0,0,0,0,0,0,0,0,0,0,0,0)';$S;BIDI;
    'DDR4_SA_ECC3':'(0,0,0,0,0,0,0,0,0,0,0,ER56,0,0,0,0,0,0,0,0,0,0,0,0,0,0,0,0,~
0,0,0,0,0,0,0,0,0,0,0,0,0,0)';$S;BIDI;
    'DDR4_SA_ECC2':'(0,0,0,0,0,0,0,0,0,0,0,EP57,0,0,0,0,0,0,0,0,0,0,0,0,0,0,0,0,~
0,0,0,0,0,0,0,0,0,0,0,0,0,0)';$S;BIDI;
    'DDR4_SA_ECC1':'(0,0,0,0,0,0,0,0,0,0,0,EL56,0,0,0,0,0,0,0,0,0,0,0,0,0,0,0,0,~
0,0,0,0,0,0,0,0,0,0,0,0,0,0)';$S;BIDI;
    'DDR4_SA_ECC0':'(0,0,0,0,0,0,0,0,0,0,0,EM57,0,0,0,0,0,0,0,0,0,0,0,0,0,0,0,0,~
0,0,0,0,0,0,0,0,0,0,0,0,0,0)';$S;BIDI;
    'DDR4_SA_PAR':'(0,0,0,0,0,0,0,0,0,0,0,EE43,0,0,0,0,0,0,0,0,0,0,0,0,0,0,0,0,0~
,0,0,0,0,0,0,0,0,0,0,0,0,0)';$S;OUT;
    'DDR4_SB_CA6':'(0,0,0,0,0,0,0,0,0,0,0,EK42,0,0,0,0,0,0,0,0,0,0,0,0,0,0,0,0,0~
,0,0,0,0,0,0,0,0,0,0,0,0,0)';$S;OUT;
    'DDR4_SB_CA5':'(0,0,0,0,0,0,0,0,0,0,0,ET42,0,0,0,0,0,0,0,0,0,0,0,0,0,0,0,0,0~
,0,0,0,0,0,0,0,0,0,0,0,0,0)';$S;OUT;
    'DDR4_SB_CA4':'(0,0,0,0,0,0,0,0,0,0,0,EL43,0,0,0,0,0,0,0,0,0,0,0,0,0,0,0,0,0~
,0,0,0,0,0,0,0,0,0,0,0,0,0)';$S;OUT;
    'DDR4_SB_CA3':'(0,0,0,0,0,0,0,0,0,0,0,EP44,0,0,0,0,0,0,0,0,0,0,0,0,0,0,0,0,0~
,0,0,0,0,0,0,0,0,0,0,0,0,0)';$S;OUT;
    'DDR4_SB_CA2':'(0,0,0,0,0,0,0,0,0,0,0,EM44,0,0,0,0,0,0,0,0,0,0,0,0,0,0,0,0,0~
,0,0,0,0,0,0,0,0,0,0,0,0,0)';$S;OUT;
    'DDR4_SB_CA1':'(0,0,0,0,0,0,0,0,0,0,0,EH44,0,0,0,0,0,0,0,0,0,0,0,0,0,0,0,0,0~
,0,0,0,0,0,0,0,0,0,0,0,0,0)';$S;OUT;
    'DDR4_SB_CA0':'(0,0,0,0,0,0,0,0,0,0,0,EG43,0,0,0,0,0,0,0,0,0,0,0,0,0,0,0,0,0~
,0,0,0,0,0,0,0,0,0,0,0,0,0)';$S;OUT;
    'DDR4_SB_CS_N3':'(0,0,0,0,0,0,0,0,0,0,0,EL41,0,0,0,0,0,0,0,0,0,0,0,0,0,0,0,0~
,0,0,0,0,0,0,0,0,0,0,0,0,0,0)';$S;OUT;
    'DDR4_SB_CS_N2':'(0,0,0,0,0,0,0,0,0,0,0,EM40,0,0,0,0,0,0,0,0,0,0,0,0,0,0,0,0~
,0,0,0,0,0,0,0,0,0,0,0,0,0,0)';$S;OUT;
    'DDR4_SB_CS_N1':'(0,0,0,0,0,0,0,0,0,0,0,ET40,0,0,0,0,0,0,0,0,0,0,0,0,0,0,0,0~
,0,0,0,0,0,0,0,0,0,0,0,0,0,0)';$S;OUT;
    'DDR4_SB_CS_N0':'(0,0,0,0,0,0,0,0,0,0,0,EP40,0,0,0,0,0,0,0,0,0,0,0,0,0,0,0,0~
,0,0,0,0,0,0,0,0,0,0,0,0,0,0)';$S;OUT;
    'DDR4_SB_DQ31':'(0,0,0,0,0,0,0,0,0,0,0,EP16,0,0,0,0,0,0,0,0,0,0,0,0,0,0,0,0,~
0,0,0,0,0,0,0,0,0,0,0,0,0,0)';$S;BIDI;
    'DDR4_SB_DQ30':'(0,0,0,0,0,0,0,0,0,0,0,ER17,0,0,0,0,0,0,0,0,0,0,0,0,0,0,0,0,~
0,0,0,0,0,0,0,0,0,0,0,0,0,0)';$S;BIDI;
    'DDR4_SB_DQ29':'(0,0,0,0,0,0,0,0,0,0,0,EM16,0,0,0,0,0,0,0,0,0,0,0,0,0,0,0,0,~
0,0,0,0,0,0,0,0,0,0,0,0,0,0)';$S;BIDI;
    'DDR4_SB_DQ28':'(0,0,0,0,0,0,0,0,0,0,0,EL17,0,0,0,0,0,0,0,0,0,0,0,0,0,0,0,0,~
0,0,0,0,0,0,0,0,0,0,0,0,0,0)';$S;BIDI;
    'DDR4_SB_DQ27':'(0,0,0,0,0,0,0,0,0,0,0,ER19,0,0,0,0,0,0,0,0,0,0,0,0,0,0,0,0,~
0,0,0,0,0,0,0,0,0,0,0,0,0,0)';$S;BIDI;
    'DDR4_SB_DQ26':'(0,0,0,0,0,0,0,0,0,0,0,EP20,0,0,0,0,0,0,0,0,0,0,0,0,0,0,0,0,~
0,0,0,0,0,0,0,0,0,0,0,0,0,0)';$S;BIDI;
    'DDR4_SB_DQ25':'(0,0,0,0,0,0,0,0,0,0,0,EL19,0,0,0,0,0,0,0,0,0,0,0,0,0,0,0,0,~
0,0,0,0,0,0,0,0,0,0,0,0,0,0)';$S;BIDI;
    'DDR4_SB_DQ24':'(0,0,0,0,0,0,0,0,0,0,0,EM20,0,0,0,0,0,0,0,0,0,0,0,0,0,0,0,0,~
0,0,0,0,0,0,0,0,0,0,0,0,0,0)';$S;BIDI;
    'DDR4_SB_DQ23':'(0,0,0,0,0,0,0,0,0,0,0,EP22,0,0,0,0,0,0,0,0,0,0,0,0,0,0,0,0,~
0,0,0,0,0,0,0,0,0,0,0,0,0,0)';$S;BIDI;
    'DDR4_SB_DQ22':'(0,0,0,0,0,0,0,0,0,0,0,ER23,0,0,0,0,0,0,0,0,0,0,0,0,0,0,0,0,~
0,0,0,0,0,0,0,0,0,0,0,0,0,0)';$S;BIDI;
    'DDR4_SB_DQ21':'(0,0,0,0,0,0,0,0,0,0,0,EM22,0,0,0,0,0,0,0,0,0,0,0,0,0,0,0,0,~
0,0,0,0,0,0,0,0,0,0,0,0,0,0)';$S;BIDI;
    'DDR4_SB_DQ20':'(0,0,0,0,0,0,0,0,0,0,0,EL23,0,0,0,0,0,0,0,0,0,0,0,0,0,0,0,0,~
0,0,0,0,0,0,0,0,0,0,0,0,0,0)';$S;BIDI;
    'DDR4_SB_DQ19':'(0,0,0,0,0,0,0,0,0,0,0,ER25,0,0,0,0,0,0,0,0,0,0,0,0,0,0,0,0,~
0,0,0,0,0,0,0,0,0,0,0,0,0,0)';$S;BIDI;
    'DDR4_SB_DQ18':'(0,0,0,0,0,0,0,0,0,0,0,EP26,0,0,0,0,0,0,0,0,0,0,0,0,0,0,0,0,~
0,0,0,0,0,0,0,0,0,0,0,0,0,0)';$S;BIDI;
    'DDR4_SB_DQ17':'(0,0,0,0,0,0,0,0,0,0,0,EL25,0,0,0,0,0,0,0,0,0,0,0,0,0,0,0,0,~
0,0,0,0,0,0,0,0,0,0,0,0,0,0)';$S;BIDI;
    'DDR4_SB_DQ16':'(0,0,0,0,0,0,0,0,0,0,0,EM26,0,0,0,0,0,0,0,0,0,0,0,0,0,0,0,0,~
0,0,0,0,0,0,0,0,0,0,0,0,0,0)';$S;BIDI;
    'DDR4_SB_DQ15':'(0,0,0,0,0,0,0,0,0,0,0,EP28,0,0,0,0,0,0,0,0,0,0,0,0,0,0,0,0,~
0,0,0,0,0,0,0,0,0,0,0,0,0,0)';$S;BIDI;
    'DDR4_SB_DQ14':'(0,0,0,0,0,0,0,0,0,0,0,ER29,0,0,0,0,0,0,0,0,0,0,0,0,0,0,0,0,~
0,0,0,0,0,0,0,0,0,0,0,0,0,0)';$S;BIDI;
    'DDR4_SB_DQ13':'(0,0,0,0,0,0,0,0,0,0,0,EM28,0,0,0,0,0,0,0,0,0,0,0,0,0,0,0,0,~
0,0,0,0,0,0,0,0,0,0,0,0,0,0)';$S;BIDI;
    'DDR4_SB_DQ12':'(0,0,0,0,0,0,0,0,0,0,0,EL29,0,0,0,0,0,0,0,0,0,0,0,0,0,0,0,0,~
0,0,0,0,0,0,0,0,0,0,0,0,0,0)';$S;BIDI;
    'DDR4_SB_DQ11':'(0,0,0,0,0,0,0,0,0,0,0,ER31,0,0,0,0,0,0,0,0,0,0,0,0,0,0,0,0,~
0,0,0,0,0,0,0,0,0,0,0,0,0,0)';$S;BIDI;
    'DDR4_SB_DQ10':'(0,0,0,0,0,0,0,0,0,0,0,EP32,0,0,0,0,0,0,0,0,0,0,0,0,0,0,0,0,~
0,0,0,0,0,0,0,0,0,0,0,0,0,0)';$S;BIDI;
    'DDR4_SB_DQ9':'(0,0,0,0,0,0,0,0,0,0,0,EL31,0,0,0,0,0,0,0,0,0,0,0,0,0,0,0,0,0~
,0,0,0,0,0,0,0,0,0,0,0,0,0)';$S;BIDI;
    'DDR4_SB_DQ8':'(0,0,0,0,0,0,0,0,0,0,0,EM32,0,0,0,0,0,0,0,0,0,0,0,0,0,0,0,0,0~
,0,0,0,0,0,0,0,0,0,0,0,0,0)';$S;BIDI;
    'DDR4_SB_DQ7':'(0,0,0,0,0,0,0,0,0,0,0,EG25,0,0,0,0,0,0,0,0,0,0,0,0,0,0,0,0,0~
,0,0,0,0,0,0,0,0,0,0,0,0,0)';$S;BIDI;
    'DDR4_SB_DQ6':'(0,0,0,0,0,0,0,0,0,0,0,EH26,0,0,0,0,0,0,0,0,0,0,0,0,0,0,0,0,0~
,0,0,0,0,0,0,0,0,0,0,0,0,0)';$S;BIDI;
    'DDR4_SB_DQ5':'(0,0,0,0,0,0,0,0,0,0,0,EE25,0,0,0,0,0,0,0,0,0,0,0,0,0,0,0,0,0~
,0,0,0,0,0,0,0,0,0,0,0,0,0)';$S;BIDI;
    'DDR4_SB_DQ4':'(0,0,0,0,0,0,0,0,0,0,0,ED26,0,0,0,0,0,0,0,0,0,0,0,0,0,0,0,0,0~
,0,0,0,0,0,0,0,0,0,0,0,0,0)';$S;BIDI;
    'DDR4_SB_DQ3':'(0,0,0,0,0,0,0,0,0,0,0,EH28,0,0,0,0,0,0,0,0,0,0,0,0,0,0,0,0,0~
,0,0,0,0,0,0,0,0,0,0,0,0,0)';$S;BIDI;
    'DDR4_SB_DQ2':'(0,0,0,0,0,0,0,0,0,0,0,EG29,0,0,0,0,0,0,0,0,0,0,0,0,0,0,0,0,0~
,0,0,0,0,0,0,0,0,0,0,0,0,0)';$S;BIDI;
    'DDR4_SB_DQ1':'(0,0,0,0,0,0,0,0,0,0,0,ED28,0,0,0,0,0,0,0,0,0,0,0,0,0,0,0,0,0~
,0,0,0,0,0,0,0,0,0,0,0,0,0)';$S;BIDI;
    'DDR4_SB_DQ0':'(0,0,0,0,0,0,0,0,0,0,0,EE29,0,0,0,0,0,0,0,0,0,0,0,0,0,0,0,0,0~
,0,0,0,0,0,0,0,0,0,0,0,0,0)';$S;BIDI;
    'DDR4_SB_DQS_DN9':'(0,0,0,0,0,0,0,0,0,0,0,EK36,0,0,0,0,0,0,0,0,0,0,0,0,0,0,0~
,0,0,0,0,0,0,0,0,0,0,0,0,0,0,0)';$S;BIDI;
    'DDR4_SB_DQS_DN8':'(0,0,0,0,0,0,0,0,0,0,0,ET18,0,0,0,0,0,0,0,0,0,0,0,0,0,0,0~
,0,0,0,0,0,0,0,0,0,0,0,0,0,0,0)';$S;BIDI;
    'DDR4_SB_DQS_DN7':'(0,0,0,0,0,0,0,0,0,0,0,ET24,0,0,0,0,0,0,0,0,0,0,0,0,0,0,0~
,0,0,0,0,0,0,0,0,0,0,0,0,0,0,0)';$S;BIDI;
    'DDR4_SB_DQS_DN6':'(0,0,0,0,0,0,0,0,0,0,0,ET30,0,0,0,0,0,0,0,0,0,0,0,0,0,0,0~
,0,0,0,0,0,0,0,0,0,0,0,0,0,0,0)';$S;BIDI;
    'DDR4_SB_DQS_DN5':'(0,0,0,0,0,0,0,0,0,0,0,EJ27,0,0,0,0,0,0,0,0,0,0,0,0,0,0,0~
,0,0,0,0,0,0,0,0,0,0,0,0,0,0,0)';$S;BIDI;
    'DDR4_SB_DQS_DN4':'(0,0,0,0,0,0,0,0,0,0,0,ET36,0,0,0,0,0,0,0,0,0,0,0,0,0,0,0~
,0,0,0,0,0,0,0,0,0,0,0,0,0,0,0)';$S;BIDI;
    'DDR4_SB_DQS_DN3':'(0,0,0,0,0,0,0,0,0,0,0,EK18,0,0,0,0,0,0,0,0,0,0,0,0,0,0,0~
,0,0,0,0,0,0,0,0,0,0,0,0,0,0,0)';$S;BIDI;
    'DDR4_SB_DQS_DN2':'(0,0,0,0,0,0,0,0,0,0,0,EK24,0,0,0,0,0,0,0,0,0,0,0,0,0,0,0~
,0,0,0,0,0,0,0,0,0,0,0,0,0,0,0)';$S;BIDI;
    'DDR4_SB_DQS_DN1':'(0,0,0,0,0,0,0,0,0,0,0,EK30,0,0,0,0,0,0,0,0,0,0,0,0,0,0,0~
,0,0,0,0,0,0,0,0,0,0,0,0,0,0,0)';$S;BIDI;
    'DDR4_SB_DQS_DN0':'(0,0,0,0,0,0,0,0,0,0,0,EE27,0,0,0,0,0,0,0,0,0,0,0,0,0,0,0~
,0,0,0,0,0,0,0,0,0,0,0,0,0,0,0)';$S;BIDI;
    'DDR4_SB_DQS_DP9':'(0,0,0,0,0,0,0,0,0,0,0,EM36,0,0,0,0,0,0,0,0,0,0,0,0,0,0,0~
,0,0,0,0,0,0,0,0,0,0,0,0,0,0,0)';$S;BIDI;
    'DDR4_SB_DQS_DP8':'(0,0,0,0,0,0,0,0,0,0,0,EP18,0,0,0,0,0,0,0,0,0,0,0,0,0,0,0~
,0,0,0,0,0,0,0,0,0,0,0,0,0,0,0)';$S;BIDI;
    'DDR4_SB_DQS_DP7':'(0,0,0,0,0,0,0,0,0,0,0,EP24,0,0,0,0,0,0,0,0,0,0,0,0,0,0,0~
,0,0,0,0,0,0,0,0,0,0,0,0,0,0,0)';$S;BIDI;
    'DDR4_SB_DQS_DP6':'(0,0,0,0,0,0,0,0,0,0,0,EP30,0,0,0,0,0,0,0,0,0,0,0,0,0,0,0~
,0,0,0,0,0,0,0,0,0,0,0,0,0,0,0)';$S;BIDI;
    'DDR4_SB_DQS_DP5':'(0,0,0,0,0,0,0,0,0,0,0,EG27,0,0,0,0,0,0,0,0,0,0,0,0,0,0,0~
,0,0,0,0,0,0,0,0,0,0,0,0,0,0,0)';$S;BIDI;
    'DDR4_SB_DQS_DP4':'(0,0,0,0,0,0,0,0,0,0,0,EP36,0,0,0,0,0,0,0,0,0,0,0,0,0,0,0~
,0,0,0,0,0,0,0,0,0,0,0,0,0,0,0)';$S;BIDI;
    'DDR4_SB_DQS_DP3':'(0,0,0,0,0,0,0,0,0,0,0,EM18,0,0,0,0,0,0,0,0,0,0,0,0,0,0,0~
,0,0,0,0,0,0,0,0,0,0,0,0,0,0,0)';$S;BIDI;
    'DDR4_SB_DQS_DP2':'(0,0,0,0,0,0,0,0,0,0,0,EM24,0,0,0,0,0,0,0,0,0,0,0,0,0,0,0~
,0,0,0,0,0,0,0,0,0,0,0,0,0,0,0)';$S;BIDI;
    'DDR4_SB_DQS_DP1':'(0,0,0,0,0,0,0,0,0,0,0,EM30,0,0,0,0,0,0,0,0,0,0,0,0,0,0,0~
,0,0,0,0,0,0,0,0,0,0,0,0,0,0,0)';$S;BIDI;
    'DDR4_SB_DQS_DP0':'(0,0,0,0,0,0,0,0,0,0,0,EC27,0,0,0,0,0,0,0,0,0,0,0,0,0,0,0~
,0,0,0,0,0,0,0,0,0,0,0,0,0,0,0)';$S;BIDI;
    'DDR4_SB_ECC7':'(0,0,0,0,0,0,0,0,0,0,0,ER37,0,0,0,0,0,0,0,0,0,0,0,0,0,0,0,0,~
0,0,0,0,0,0,0,0,0,0,0,0,0,0)';$S;BIDI;
    'DDR4_SB_ECC6':'(0,0,0,0,0,0,0,0,0,0,0,EP38,0,0,0,0,0,0,0,0,0,0,0,0,0,0,0,0,~
0,0,0,0,0,0,0,0,0,0,0,0,0,0)';$S;BIDI;
    'DDR4_SB_ECC5':'(0,0,0,0,0,0,0,0,0,0,0,EL37,0,0,0,0,0,0,0,0,0,0,0,0,0,0,0,0,~
0,0,0,0,0,0,0,0,0,0,0,0,0,0)';$S;BIDI;
    'DDR4_SB_ECC4':'(0,0,0,0,0,0,0,0,0,0,0,EM38,0,0,0,0,0,0,0,0,0,0,0,0,0,0,0,0,~
0,0,0,0,0,0,0,0,0,0,0,0,0,0)';$S;BIDI;
    'DDR4_SB_ECC3':'(0,0,0,0,0,0,0,0,0,0,0,EP34,0,0,0,0,0,0,0,0,0,0,0,0,0,0,0,0,~
0,0,0,0,0,0,0,0,0,0,0,0,0,0)';$S;BIDI;
    'DDR4_SB_ECC2':'(0,0,0,0,0,0,0,0,0,0,0,ER35,0,0,0,0,0,0,0,0,0,0,0,0,0,0,0,0,~
0,0,0,0,0,0,0,0,0,0,0,0,0,0)';$S;BIDI;
    'DDR4_SB_ECC1':'(0,0,0,0,0,0,0,0,0,0,0,EM34,0,0,0,0,0,0,0,0,0,0,0,0,0,0,0,0,~
0,0,0,0,0,0,0,0,0,0,0,0,0,0)';$S;BIDI;
    'DDR4_SB_ECC0':'(0,0,0,0,0,0,0,0,0,0,0,EL35,0,0,0,0,0,0,0,0,0,0,0,0,0,0,0,0,~
0,0,0,0,0,0,0,0,0,0,0,0,0,0)';$S;BIDI;
    'DDR4_SB_PAR':'(0,0,0,0,0,0,0,0,0,0,0,EP42,0,0,0,0,0,0,0,0,0,0,0,0,0,0,0,0,0~
,0,0,0,0,0,0,0,0,0,0,0,0,0)';$S;OUT;
    'DDR5_ALERT_N':'(0,0,0,0,0,0,0,0,0,0,0,0,CW48,0,0,0,0,0,0,0,0,0,0,0,0,0,0,0,~
0,0,0,0,0,0,0,0,0,0,0,0,0,0)';$S;IN;
    'DDR5_A_RSP1':'(0,0,0,0,0,0,0,0,0,0,0,0,DP47,0,0,0,0,0,0,0,0,0,0,0,0,0,0,0,0~
,0,0,0,0,0,0,0,0,0,0,0,0,0)';$S;IN;
    'DDR5_A_RSP0':'(0,0,0,0,0,0,0,0,0,0,0,0,DN48,0,0,0,0,0,0,0,0,0,0,0,0,0,0,0,0~
,0,0,0,0,0,0,0,0,0,0,0,0,0)';$S;IN;
    'DDR5_B_RSP1':'(0,0,0,0,0,0,0,0,0,0,0,0,DK47,0,0,0,0,0,0,0,0,0,0,0,0,0,0,0,0~
,0,0,0,0,0,0,0,0,0,0,0,0,0)';$S;IN;
    'DDR5_B_RSP0':'(0,0,0,0,0,0,0,0,0,0,0,0,DL48,0,0,0,0,0,0,0,0,0,0,0,0,0,0,0,0~
,0,0,0,0,0,0,0,0,0,0,0,0,0)';$S;IN;
    'DDR5_CLK_DN1':'(0,0,0,0,0,0,0,0,0,0,0,0,DV49,0,0,0,0,0,0,0,0,0,0,0,0,0,0,0,~
0,0,0,0,0,0,0,0,0,0,0,0,0,0)';$S;OUT;
    'DDR5_CLK_DN0':'(0,0,0,0,0,0,0,0,0,0,0,0,DY49,0,0,0,0,0,0,0,0,0,0,0,0,0,0,0,~
0,0,0,0,0,0,0,0,0,0,0,0,0,0)';$S;OUT;
    'DDR5_CLK_DP1':'(0,0,0,0,0,0,0,0,0,0,0,0,DT49,0,0,0,0,0,0,0,0,0,0,0,0,0,0,0,~
0,0,0,0,0,0,0,0,0,0,0,0,0,0)';$S;OUT;
    'DDR5_CLK_DP0':'(0,0,0,0,0,0,0,0,0,0,0,0,EB49,0,0,0,0,0,0,0,0,0,0,0,0,0,0,0,~
0,0,0,0,0,0,0,0,0,0,0,0,0,0)';$S;OUT;
    'DDR5_SA_CA6':'(0,0,0,0,0,0,0,0,0,0,0,0,DY51,0,0,0,0,0,0,0,0,0,0,0,0,0,0,0,0~
,0,0,0,0,0,0,0,0,0,0,0,0,0)';$S;OUT;
    'DDR5_SA_CA5':'(0,0,0,0,0,0,0,0,0,0,0,0,EG50,0,0,0,0,0,0,0,0,0,0,0,0,0,0,0,0~
,0,0,0,0,0,0,0,0,0,0,0,0,0)';$S;OUT;
    'DDR5_SA_CA4':'(0,0,0,0,0,0,0,0,0,0,0,0,EE50,0,0,0,0,0,0,0,0,0,0,0,0,0,0,0,0~
,0,0,0,0,0,0,0,0,0,0,0,0,0)';$S;OUT;
    'DDR5_SA_CA3':'(0,0,0,0,0,0,0,0,0,0,0,0,EH51,0,0,0,0,0,0,0,0,0,0,0,0,0,0,0,0~
,0,0,0,0,0,0,0,0,0,0,0,0,0)';$S;OUT;
    'DDR5_SA_CA2':'(0,0,0,0,0,0,0,0,0,0,0,0,ED51,0,0,0,0,0,0,0,0,0,0,0,0,0,0,0,0~
,0,0,0,0,0,0,0,0,0,0,0,0,0)';$S;OUT;
    'DDR5_SA_CA1':'(0,0,0,0,0,0,0,0,0,0,0,0,EJ52,0,0,0,0,0,0,0,0,0,0,0,0,0,0,0,0~
,0,0,0,0,0,0,0,0,0,0,0,0,0)';$S;OUT;
    'DDR5_SA_CA0':'(0,0,0,0,0,0,0,0,0,0,0,0,EC52,0,0,0,0,0,0,0,0,0,0,0,0,0,0,0,0~
,0,0,0,0,0,0,0,0,0,0,0,0,0)';$S;OUT;
    'DDR5_SA_CS_N3':'(0,0,0,0,0,0,0,0,0,0,0,0,ED53,0,0,0,0,0,0,0,0,0,0,0,0,0,0,0~
,0,0,0,0,0,0,0,0,0,0,0,0,0,0)';$S;OUT;
    'DDR5_SA_CS_N2':'(0,0,0,0,0,0,0,0,0,0,0,0,EE54,0,0,0,0,0,0,0,0,0,0,0,0,0,0,0~
,0,0,0,0,0,0,0,0,0,0,0,0,0,0)';$S;OUT;
    'DDR5_SA_CS_N1':'(0,0,0,0,0,0,0,0,0,0,0,0,EH53,0,0,0,0,0,0,0,0,0,0,0,0,0,0,0~
,0,0,0,0,0,0,0,0,0,0,0,0,0,0)';$S;OUT;
    'DDR5_SA_CS_N0':'(0,0,0,0,0,0,0,0,0,0,0,0,EG54,0,0,0,0,0,0,0,0,0,0,0,0,0,0,0~
,0,0,0,0,0,0,0,0,0,0,0,0,0,0)';$S;OUT;
    'DDR5_SA_DQ31':'(0,0,0,0,0,0,0,0,0,0,0,0,DY53,0,0,0,0,0,0,0,0,0,0,0,0,0,0,0,~
0,0,0,0,0,0,0,0,0,0,0,0,0,0)';$S;BIDI;
    'DDR5_SA_DQ30':'(0,0,0,0,0,0,0,0,0,0,0,0,EA54,0,0,0,0,0,0,0,0,0,0,0,0,0,0,0,~
0,0,0,0,0,0,0,0,0,0,0,0,0,0)';$S;BIDI;
    'DDR5_SA_DQ29':'(0,0,0,0,0,0,0,0,0,0,0,0,DV53,0,0,0,0,0,0,0,0,0,0,0,0,0,0,0,~
0,0,0,0,0,0,0,0,0,0,0,0,0,0)';$S;BIDI;
    'DDR5_SA_DQ28':'(0,0,0,0,0,0,0,0,0,0,0,0,DU54,0,0,0,0,0,0,0,0,0,0,0,0,0,0,0,~
0,0,0,0,0,0,0,0,0,0,0,0,0,0)';$S;BIDI;
    'DDR5_SA_DQ27':'(0,0,0,0,0,0,0,0,0,0,0,0,EA56,0,0,0,0,0,0,0,0,0,0,0,0,0,0,0,~
0,0,0,0,0,0,0,0,0,0,0,0,0,0)';$S;BIDI;
    'DDR5_SA_DQ26':'(0,0,0,0,0,0,0,0,0,0,0,0,DY57,0,0,0,0,0,0,0,0,0,0,0,0,0,0,0,~
0,0,0,0,0,0,0,0,0,0,0,0,0,0)';$S;BIDI;
    'DDR5_SA_DQ25':'(0,0,0,0,0,0,0,0,0,0,0,0,DU56,0,0,0,0,0,0,0,0,0,0,0,0,0,0,0,~
0,0,0,0,0,0,0,0,0,0,0,0,0,0)';$S;BIDI;
    'DDR5_SA_DQ24':'(0,0,0,0,0,0,0,0,0,0,0,0,DV57,0,0,0,0,0,0,0,0,0,0,0,0,0,0,0,~
0,0,0,0,0,0,0,0,0,0,0,0,0,0)';$S;BIDI;
    'DDR5_SA_DQ23':'(0,0,0,0,0,0,0,0,0,0,0,0,EG62,0,0,0,0,0,0,0,0,0,0,0,0,0,0,0,~
0,0,0,0,0,0,0,0,0,0,0,0,0,0)';$S;BIDI;
    'DDR5_SA_DQ22':'(0,0,0,0,0,0,0,0,0,0,0,0,EH63,0,0,0,0,0,0,0,0,0,0,0,0,0,0,0,~
0,0,0,0,0,0,0,0,0,0,0,0,0,0)';$S;BIDI;
    'DDR5_SA_DQ21':'(0,0,0,0,0,0,0,0,0,0,0,0,EE62,0,0,0,0,0,0,0,0,0,0,0,0,0,0,0,~
0,0,0,0,0,0,0,0,0,0,0,0,0,0)';$S;BIDI;
    'DDR5_SA_DQ20':'(0,0,0,0,0,0,0,0,0,0,0,0,ED63,0,0,0,0,0,0,0,0,0,0,0,0,0,0,0,~
0,0,0,0,0,0,0,0,0,0,0,0,0,0)';$S;BIDI;
    'DDR5_SA_DQ19':'(0,0,0,0,0,0,0,0,0,0,0,0,EH65,0,0,0,0,0,0,0,0,0,0,0,0,0,0,0,~
0,0,0,0,0,0,0,0,0,0,0,0,0,0)';$S;BIDI;
    'DDR5_SA_DQ18':'(0,0,0,0,0,0,0,0,0,0,0,0,EG66,0,0,0,0,0,0,0,0,0,0,0,0,0,0,0,~
0,0,0,0,0,0,0,0,0,0,0,0,0,0)';$S;BIDI;
    'DDR5_SA_DQ17':'(0,0,0,0,0,0,0,0,0,0,0,0,ED65,0,0,0,0,0,0,0,0,0,0,0,0,0,0,0,~
0,0,0,0,0,0,0,0,0,0,0,0,0,0)';$S;BIDI;
    'DDR5_SA_DQ16':'(0,0,0,0,0,0,0,0,0,0,0,0,EE66,0,0,0,0,0,0,0,0,0,0,0,0,0,0,0,~
0,0,0,0,0,0,0,0,0,0,0,0,0,0)';$S;BIDI;
    'DDR5_SA_DQ15':'(0,0,0,0,0,0,0,0,0,0,0,0,DY65,0,0,0,0,0,0,0,0,0,0,0,0,0,0,0,~
0,0,0,0,0,0,0,0,0,0,0,0,0,0)';$S;BIDI;
    'DDR5_SA_DQ14':'(0,0,0,0,0,0,0,0,0,0,0,0,EA66,0,0,0,0,0,0,0,0,0,0,0,0,0,0,0,~
0,0,0,0,0,0,0,0,0,0,0,0,0,0)';$S;BIDI;
    'DDR5_SA_DQ13':'(0,0,0,0,0,0,0,0,0,0,0,0,DV65,0,0,0,0,0,0,0,0,0,0,0,0,0,0,0,~
0,0,0,0,0,0,0,0,0,0,0,0,0,0)';$S;BIDI;
    'DDR5_SA_DQ12':'(0,0,0,0,0,0,0,0,0,0,0,0,DU66,0,0,0,0,0,0,0,0,0,0,0,0,0,0,0,~
0,0,0,0,0,0,0,0,0,0,0,0,0,0)';$S;BIDI;
    'DDR5_SA_DQ11':'(0,0,0,0,0,0,0,0,0,0,0,0,EA68,0,0,0,0,0,0,0,0,0,0,0,0,0,0,0,~
0,0,0,0,0,0,0,0,0,0,0,0,0,0)';$S;BIDI;
    'DDR5_SA_DQ10':'(0,0,0,0,0,0,0,0,0,0,0,0,DY69,0,0,0,0,0,0,0,0,0,0,0,0,0,0,0,~
0,0,0,0,0,0,0,0,0,0,0,0,0,0)';$S;BIDI;
    'DDR5_SA_DQ9':'(0,0,0,0,0,0,0,0,0,0,0,0,DU68,0,0,0,0,0,0,0,0,0,0,0,0,0,0,0,0~
,0,0,0,0,0,0,0,0,0,0,0,0,0)';$S;BIDI;
    'DDR5_SA_DQ8':'(0,0,0,0,0,0,0,0,0,0,0,0,DV69,0,0,0,0,0,0,0,0,0,0,0,0,0,0,0,0~
,0,0,0,0,0,0,0,0,0,0,0,0,0)';$S;BIDI;
    'DDR5_SA_DQ7':'(0,0,0,0,0,0,0,0,0,0,0,0,EG74,0,0,0,0,0,0,0,0,0,0,0,0,0,0,0,0~
,0,0,0,0,0,0,0,0,0,0,0,0,0)';$S;BIDI;
    'DDR5_SA_DQ6':'(0,0,0,0,0,0,0,0,0,0,0,0,EH75,0,0,0,0,0,0,0,0,0,0,0,0,0,0,0,0~
,0,0,0,0,0,0,0,0,0,0,0,0,0)';$S;BIDI;
    'DDR5_SA_DQ5':'(0,0,0,0,0,0,0,0,0,0,0,0,EE74,0,0,0,0,0,0,0,0,0,0,0,0,0,0,0,0~
,0,0,0,0,0,0,0,0,0,0,0,0,0)';$S;BIDI;
    'DDR5_SA_DQ4':'(0,0,0,0,0,0,0,0,0,0,0,0,ED75,0,0,0,0,0,0,0,0,0,0,0,0,0,0,0,0~
,0,0,0,0,0,0,0,0,0,0,0,0,0)';$S;BIDI;
    'DDR5_SA_DQ3':'(0,0,0,0,0,0,0,0,0,0,0,0,EG78,0,0,0,0,0,0,0,0,0,0,0,0,0,0,0,0~
,0,0,0,0,0,0,0,0,0,0,0,0,0)';$S;BIDI;
    'DDR5_SA_DQ2':'(0,0,0,0,0,0,0,0,0,0,0,0,ED77,0,0,0,0,0,0,0,0,0,0,0,0,0,0,0,0~
,0,0,0,0,0,0,0,0,0,0,0,0,0)';$S;BIDI;
    'DDR5_SA_DQ1':'(0,0,0,0,0,0,0,0,0,0,0,0,EH77,0,0,0,0,0,0,0,0,0,0,0,0,0,0,0,0~
,0,0,0,0,0,0,0,0,0,0,0,0,0)';$S;BIDI;
    'DDR5_SA_DQ0':'(0,0,0,0,0,0,0,0,0,0,0,0,EB77,0,0,0,0,0,0,0,0,0,0,0,0,0,0,0,0~
,0,0,0,0,0,0,0,0,0,0,0,0,0)';$S;BIDI;
    'DDR5_SA_DQS_DN9':'(0,0,0,0,0,0,0,0,0,0,0,0,EJ58,0,0,0,0,0,0,0,0,0,0,0,0,0,0~
,0,0,0,0,0,0,0,0,0,0,0,0,0,0,0)';$S;BIDI;
    'DDR5_SA_DQS_DN8':'(0,0,0,0,0,0,0,0,0,0,0,0,EB55,0,0,0,0,0,0,0,0,0,0,0,0,0,0~
,0,0,0,0,0,0,0,0,0,0,0,0,0,0,0)';$S;BIDI;
    'DDR5_SA_DQS_DN7':'(0,0,0,0,0,0,0,0,0,0,0,0,EJ64,0,0,0,0,0,0,0,0,0,0,0,0,0,0~
,0,0,0,0,0,0,0,0,0,0,0,0,0,0,0)';$S;BIDI;
    'DDR5_SA_DQS_DN6':'(0,0,0,0,0,0,0,0,0,0,0,0,EB67,0,0,0,0,0,0,0,0,0,0,0,0,0,0~
,0,0,0,0,0,0,0,0,0,0,0,0,0,0,0)';$S;BIDI;
    'DDR5_SA_DQS_DN5':'(0,0,0,0,0,0,0,0,0,0,0,0,EJ76,0,0,0,0,0,0,0,0,0,0,0,0,0,0~
,0,0,0,0,0,0,0,0,0,0,0,0,0,0,0)';$S;BIDI;
    'DDR5_SA_DQS_DN4':'(0,0,0,0,0,0,0,0,0,0,0,0,EE58,0,0,0,0,0,0,0,0,0,0,0,0,0,0~
,0,0,0,0,0,0,0,0,0,0,0,0,0,0,0)';$S;BIDI;
    'DDR5_SA_DQS_DN3':'(0,0,0,0,0,0,0,0,0,0,0,0,DV55,0,0,0,0,0,0,0,0,0,0,0,0,0,0~
,0,0,0,0,0,0,0,0,0,0,0,0,0,0,0)';$S;BIDI;
    'DDR5_SA_DQS_DN2':'(0,0,0,0,0,0,0,0,0,0,0,0,EC64,0,0,0,0,0,0,0,0,0,0,0,0,0,0~
,0,0,0,0,0,0,0,0,0,0,0,0,0,0,0)';$S;BIDI;
    'DDR5_SA_DQS_DN1':'(0,0,0,0,0,0,0,0,0,0,0,0,DT67,0,0,0,0,0,0,0,0,0,0,0,0,0,0~
,0,0,0,0,0,0,0,0,0,0,0,0,0,0,0)';$S;BIDI;
    'DDR5_SA_DQS_DN0':'(0,0,0,0,0,0,0,0,0,0,0,0,EE76,0,0,0,0,0,0,0,0,0,0,0,0,0,0~
,0,0,0,0,0,0,0,0,0,0,0,0,0,0,0)';$S;BIDI;
    'DDR5_SA_DQS_DP9':'(0,0,0,0,0,0,0,0,0,0,0,0,EG58,0,0,0,0,0,0,0,0,0,0,0,0,0,0~
,0,0,0,0,0,0,0,0,0,0,0,0,0,0,0)';$S;BIDI;
    'DDR5_SA_DQS_DP8':'(0,0,0,0,0,0,0,0,0,0,0,0,DY55,0,0,0,0,0,0,0,0,0,0,0,0,0,0~
,0,0,0,0,0,0,0,0,0,0,0,0,0,0,0)';$S;BIDI;
    'DDR5_SA_DQS_DP7':'(0,0,0,0,0,0,0,0,0,0,0,0,EG64,0,0,0,0,0,0,0,0,0,0,0,0,0,0~
,0,0,0,0,0,0,0,0,0,0,0,0,0,0,0)';$S;BIDI;
    'DDR5_SA_DQS_DP6':'(0,0,0,0,0,0,0,0,0,0,0,0,DY67,0,0,0,0,0,0,0,0,0,0,0,0,0,0~
,0,0,0,0,0,0,0,0,0,0,0,0,0,0,0)';$S;BIDI;
    'DDR5_SA_DQS_DP5':'(0,0,0,0,0,0,0,0,0,0,0,0,EG76,0,0,0,0,0,0,0,0,0,0,0,0,0,0~
,0,0,0,0,0,0,0,0,0,0,0,0,0,0,0)';$S;BIDI;
    'DDR5_SA_DQS_DP4':'(0,0,0,0,0,0,0,0,0,0,0,0,EC58,0,0,0,0,0,0,0,0,0,0,0,0,0,0~
,0,0,0,0,0,0,0,0,0,0,0,0,0,0,0)';$S;BIDI;
    'DDR5_SA_DQS_DP3':'(0,0,0,0,0,0,0,0,0,0,0,0,DT55,0,0,0,0,0,0,0,0,0,0,0,0,0,0~
,0,0,0,0,0,0,0,0,0,0,0,0,0,0,0)';$S;BIDI;
    'DDR5_SA_DQS_DP2':'(0,0,0,0,0,0,0,0,0,0,0,0,EE64,0,0,0,0,0,0,0,0,0,0,0,0,0,0~
,0,0,0,0,0,0,0,0,0,0,0,0,0,0,0)';$S;BIDI;
    'DDR5_SA_DQS_DP1':'(0,0,0,0,0,0,0,0,0,0,0,0,DV67,0,0,0,0,0,0,0,0,0,0,0,0,0,0~
,0,0,0,0,0,0,0,0,0,0,0,0,0,0,0)';$S;BIDI;
    'DDR5_SA_DQS_DP0':'(0,0,0,0,0,0,0,0,0,0,0,0,EC76,0,0,0,0,0,0,0,0,0,0,0,0,0,0~
,0,0,0,0,0,0,0,0,0,0,0,0,0,0,0)';$S;BIDI;
    'DDR5_SA_ECC7':'(0,0,0,0,0,0,0,0,0,0,0,0,EG56,0,0,0,0,0,0,0,0,0,0,0,0,0,0,0,~
0,0,0,0,0,0,0,0,0,0,0,0,0,0)';$S;BIDI;
    'DDR5_SA_ECC6':'(0,0,0,0,0,0,0,0,0,0,0,0,EH57,0,0,0,0,0,0,0,0,0,0,0,0,0,0,0,~
0,0,0,0,0,0,0,0,0,0,0,0,0,0)';$S;BIDI;
    'DDR5_SA_ECC5':'(0,0,0,0,0,0,0,0,0,0,0,0,EE56,0,0,0,0,0,0,0,0,0,0,0,0,0,0,0,~
0,0,0,0,0,0,0,0,0,0,0,0,0,0)';$S;BIDI;
    'DDR5_SA_ECC4':'(0,0,0,0,0,0,0,0,0,0,0,0,ED57,0,0,0,0,0,0,0,0,0,0,0,0,0,0,0,~
0,0,0,0,0,0,0,0,0,0,0,0,0,0)';$S;BIDI;
    'DDR5_SA_ECC3':'(0,0,0,0,0,0,0,0,0,0,0,0,EH59,0,0,0,0,0,0,0,0,0,0,0,0,0,0,0,~
0,0,0,0,0,0,0,0,0,0,0,0,0,0)';$S;BIDI;
    'DDR5_SA_ECC2':'(0,0,0,0,0,0,0,0,0,0,0,0,EG60,0,0,0,0,0,0,0,0,0,0,0,0,0,0,0,~
0,0,0,0,0,0,0,0,0,0,0,0,0,0)';$S;BIDI;
    'DDR5_SA_ECC1':'(0,0,0,0,0,0,0,0,0,0,0,0,ED59,0,0,0,0,0,0,0,0,0,0,0,0,0,0,0,~
0,0,0,0,0,0,0,0,0,0,0,0,0,0)';$S;BIDI;
    'DDR5_SA_ECC0':'(0,0,0,0,0,0,0,0,0,0,0,0,EE60,0,0,0,0,0,0,0,0,0,0,0,0,0,0,0,~
0,0,0,0,0,0,0,0,0,0,0,0,0,0)';$S;BIDI;
    'DDR5_SA_PAR':'(0,0,0,0,0,0,0,0,0,0,0,0,EA50,0,0,0,0,0,0,0,0,0,0,0,0,0,0,0,0~
,0,0,0,0,0,0,0,0,0,0,0,0,0)';$S;OUT;
    'DDR5_SB_CA6':'(0,0,0,0,0,0,0,0,0,0,0,0,EC39,0,0,0,0,0,0,0,0,0,0,0,0,0,0,0,0~
,0,0,0,0,0,0,0,0,0,0,0,0,0)';$S;OUT;
    'DDR5_SB_CA5':'(0,0,0,0,0,0,0,0,0,0,0,0,EH40,0,0,0,0,0,0,0,0,0,0,0,0,0,0,0,0~
,0,0,0,0,0,0,0,0,0,0,0,0,0)';$S;OUT;
    'DDR5_SB_CA4':'(0,0,0,0,0,0,0,0,0,0,0,0,ED40,0,0,0,0,0,0,0,0,0,0,0,0,0,0,0,0~
,0,0,0,0,0,0,0,0,0,0,0,0,0)';$S;OUT;
    'DDR5_SB_CA3':'(0,0,0,0,0,0,0,0,0,0,0,0,EG41,0,0,0,0,0,0,0,0,0,0,0,0,0,0,0,0~
,0,0,0,0,0,0,0,0,0,0,0,0,0)';$S;OUT;
    'DDR5_SB_CA2':'(0,0,0,0,0,0,0,0,0,0,0,0,EE41,0,0,0,0,0,0,0,0,0,0,0,0,0,0,0,0~
,0,0,0,0,0,0,0,0,0,0,0,0,0)';$S;OUT;
    'DDR5_SB_CA1':'(0,0,0,0,0,0,0,0,0,0,0,0,DU50,0,0,0,0,0,0,0,0,0,0,0,0,0,0,0,0~
,0,0,0,0,0,0,0,0,0,0,0,0,0)';$S;OUT;
    'DDR5_SB_CA0':'(0,0,0,0,0,0,0,0,0,0,0,0,DV51,0,0,0,0,0,0,0,0,0,0,0,0,0,0,0,0~
,0,0,0,0,0,0,0,0,0,0,0,0,0)';$S;OUT;
    'DDR5_SB_CS_N3':'(0,0,0,0,0,0,0,0,0,0,0,0,EE37,0,0,0,0,0,0,0,0,0,0,0,0,0,0,0~
,0,0,0,0,0,0,0,0,0,0,0,0,0,0)';$S;OUT;
    'DDR5_SB_CS_N2':'(0,0,0,0,0,0,0,0,0,0,0,0,ED38,0,0,0,0,0,0,0,0,0,0,0,0,0,0,0~
,0,0,0,0,0,0,0,0,0,0,0,0,0,0)';$S;OUT;
    'DDR5_SB_CS_N1':'(0,0,0,0,0,0,0,0,0,0,0,0,EG37,0,0,0,0,0,0,0,0,0,0,0,0,0,0,0~
,0,0,0,0,0,0,0,0,0,0,0,0,0,0)';$S;OUT;
    'DDR5_SB_CS_N0':'(0,0,0,0,0,0,0,0,0,0,0,0,EH38,0,0,0,0,0,0,0,0,0,0,0,0,0,0,0~
,0,0,0,0,0,0,0,0,0,0,0,0,0,0)';$S;OUT;
    'DDR5_SB_DQ31':'(0,0,0,0,0,0,0,0,0,0,0,0,DR17,0,0,0,0,0,0,0,0,0,0,0,0,0,0,0,~
0,0,0,0,0,0,0,0,0,0,0,0,0,0)';$S;BIDI;
    'DDR5_SB_DQ30':'(0,0,0,0,0,0,0,0,0,0,0,0,EC17,0,0,0,0,0,0,0,0,0,0,0,0,0,0,0,~
0,0,0,0,0,0,0,0,0,0,0,0,0,0)';$S;BIDI;
    'DDR5_SB_DQ29':'(0,0,0,0,0,0,0,0,0,0,0,0,DU17,0,0,0,0,0,0,0,0,0,0,0,0,0,0,0,~
0,0,0,0,0,0,0,0,0,0,0,0,0,0)';$S;BIDI;
    'DDR5_SB_DQ28':'(0,0,0,0,0,0,0,0,0,0,0,0,EA17,0,0,0,0,0,0,0,0,0,0,0,0,0,0,0,~
0,0,0,0,0,0,0,0,0,0,0,0,0,0)';$S;BIDI;
    'DDR5_SB_DQ27':'(0,0,0,0,0,0,0,0,0,0,0,0,EA19,0,0,0,0,0,0,0,0,0,0,0,0,0,0,0,~
0,0,0,0,0,0,0,0,0,0,0,0,0,0)';$S;BIDI;
    'DDR5_SB_DQ26':'(0,0,0,0,0,0,0,0,0,0,0,0,DY20,0,0,0,0,0,0,0,0,0,0,0,0,0,0,0,~
0,0,0,0,0,0,0,0,0,0,0,0,0,0)';$S;BIDI;
    'DDR5_SB_DQ25':'(0,0,0,0,0,0,0,0,0,0,0,0,DU19,0,0,0,0,0,0,0,0,0,0,0,0,0,0,0,~
0,0,0,0,0,0,0,0,0,0,0,0,0,0)';$S;BIDI;
    'DDR5_SB_DQ24':'(0,0,0,0,0,0,0,0,0,0,0,0,DV20,0,0,0,0,0,0,0,0,0,0,0,0,0,0,0,~
0,0,0,0,0,0,0,0,0,0,0,0,0,0)';$S;BIDI;
    'DDR5_SB_DQ23':'(0,0,0,0,0,0,0,0,0,0,0,0,EP10,0,0,0,0,0,0,0,0,0,0,0,0,0,0,0,~
0,0,0,0,0,0,0,0,0,0,0,0,0,0)';$S;BIDI;
    'DDR5_SB_DQ22':'(0,0,0,0,0,0,0,0,0,0,0,0,ER11,0,0,0,0,0,0,0,0,0,0,0,0,0,0,0,~
0,0,0,0,0,0,0,0,0,0,0,0,0,0)';$S;BIDI;
    'DDR5_SB_DQ21':'(0,0,0,0,0,0,0,0,0,0,0,0,EM10,0,0,0,0,0,0,0,0,0,0,0,0,0,0,0,~
0,0,0,0,0,0,0,0,0,0,0,0,0,0)';$S;BIDI;
    'DDR5_SB_DQ20':'(0,0,0,0,0,0,0,0,0,0,0,0,EL11,0,0,0,0,0,0,0,0,0,0,0,0,0,0,0,~
0,0,0,0,0,0,0,0,0,0,0,0,0,0)';$S;BIDI;
    'DDR5_SB_DQ19':'(0,0,0,0,0,0,0,0,0,0,0,0,ER13,0,0,0,0,0,0,0,0,0,0,0,0,0,0,0,~
0,0,0,0,0,0,0,0,0,0,0,0,0,0)';$S;BIDI;
    'DDR5_SB_DQ18':'(0,0,0,0,0,0,0,0,0,0,0,0,EP14,0,0,0,0,0,0,0,0,0,0,0,0,0,0,0,~
0,0,0,0,0,0,0,0,0,0,0,0,0,0)';$S;BIDI;
    'DDR5_SB_DQ17':'(0,0,0,0,0,0,0,0,0,0,0,0,EL13,0,0,0,0,0,0,0,0,0,0,0,0,0,0,0,~
0,0,0,0,0,0,0,0,0,0,0,0,0,0)';$S;BIDI;
    'DDR5_SB_DQ16':'(0,0,0,0,0,0,0,0,0,0,0,0,EM14,0,0,0,0,0,0,0,0,0,0,0,0,0,0,0,~
0,0,0,0,0,0,0,0,0,0,0,0,0,0)';$S;BIDI;
    'DDR5_SB_DQ15':'(0,0,0,0,0,0,0,0,0,0,0,0,EG19,0,0,0,0,0,0,0,0,0,0,0,0,0,0,0,~
0,0,0,0,0,0,0,0,0,0,0,0,0,0)';$S;BIDI;
    'DDR5_SB_DQ14':'(0,0,0,0,0,0,0,0,0,0,0,0,EH20,0,0,0,0,0,0,0,0,0,0,0,0,0,0,0,~
0,0,0,0,0,0,0,0,0,0,0,0,0,0)';$S;BIDI;
    'DDR5_SB_DQ13':'(0,0,0,0,0,0,0,0,0,0,0,0,EE19,0,0,0,0,0,0,0,0,0,0,0,0,0,0,0,~
0,0,0,0,0,0,0,0,0,0,0,0,0,0)';$S;BIDI;
    'DDR5_SB_DQ12':'(0,0,0,0,0,0,0,0,0,0,0,0,ED20,0,0,0,0,0,0,0,0,0,0,0,0,0,0,0,~
0,0,0,0,0,0,0,0,0,0,0,0,0,0)';$S;BIDI;
    'DDR5_SB_DQ11':'(0,0,0,0,0,0,0,0,0,0,0,0,EH22,0,0,0,0,0,0,0,0,0,0,0,0,0,0,0,~
0,0,0,0,0,0,0,0,0,0,0,0,0,0)';$S;BIDI;
    'DDR5_SB_DQ10':'(0,0,0,0,0,0,0,0,0,0,0,0,EG23,0,0,0,0,0,0,0,0,0,0,0,0,0,0,0,~
0,0,0,0,0,0,0,0,0,0,0,0,0,0)';$S;BIDI;
    'DDR5_SB_DQ9':'(0,0,0,0,0,0,0,0,0,0,0,0,ED22,0,0,0,0,0,0,0,0,0,0,0,0,0,0,0,0~
,0,0,0,0,0,0,0,0,0,0,0,0,0)';$S;BIDI;
    'DDR5_SB_DQ8':'(0,0,0,0,0,0,0,0,0,0,0,0,EE23,0,0,0,0,0,0,0,0,0,0,0,0,0,0,0,0~
,0,0,0,0,0,0,0,0,0,0,0,0,0)';$S;BIDI;
    'DDR5_SB_DQ7':'(0,0,0,0,0,0,0,0,0,0,0,0,DY28,0,0,0,0,0,0,0,0,0,0,0,0,0,0,0,0~
,0,0,0,0,0,0,0,0,0,0,0,0,0)';$S;BIDI;
    'DDR5_SB_DQ6':'(0,0,0,0,0,0,0,0,0,0,0,0,EA29,0,0,0,0,0,0,0,0,0,0,0,0,0,0,0,0~
,0,0,0,0,0,0,0,0,0,0,0,0,0)';$S;BIDI;
    'DDR5_SB_DQ5':'(0,0,0,0,0,0,0,0,0,0,0,0,DV28,0,0,0,0,0,0,0,0,0,0,0,0,0,0,0,0~
,0,0,0,0,0,0,0,0,0,0,0,0,0)';$S;BIDI;
    'DDR5_SB_DQ4':'(0,0,0,0,0,0,0,0,0,0,0,0,DU29,0,0,0,0,0,0,0,0,0,0,0,0,0,0,0,0~
,0,0,0,0,0,0,0,0,0,0,0,0,0)';$S;BIDI;
    'DDR5_SB_DQ3':'(0,0,0,0,0,0,0,0,0,0,0,0,EA31,0,0,0,0,0,0,0,0,0,0,0,0,0,0,0,0~
,0,0,0,0,0,0,0,0,0,0,0,0,0)';$S;BIDI;
    'DDR5_SB_DQ2':'(0,0,0,0,0,0,0,0,0,0,0,0,DY32,0,0,0,0,0,0,0,0,0,0,0,0,0,0,0,0~
,0,0,0,0,0,0,0,0,0,0,0,0,0)';$S;BIDI;
    'DDR5_SB_DQ1':'(0,0,0,0,0,0,0,0,0,0,0,0,DU31,0,0,0,0,0,0,0,0,0,0,0,0,0,0,0,0~
,0,0,0,0,0,0,0,0,0,0,0,0,0)';$S;BIDI;
    'DDR5_SB_DQ0':'(0,0,0,0,0,0,0,0,0,0,0,0,DV32,0,0,0,0,0,0,0,0,0,0,0,0,0,0,0,0~
,0,0,0,0,0,0,0,0,0,0,0,0,0)';$S;BIDI;
    'DDR5_SB_DQS_DN9':'(0,0,0,0,0,0,0,0,0,0,0,0,EE33,0,0,0,0,0,0,0,0,0,0,0,0,0,0~
,0,0,0,0,0,0,0,0,0,0,0,0,0,0,0)';$S;BIDI;
    'DDR5_SB_DQS_DN8':'(0,0,0,0,0,0,0,0,0,0,0,0,DY18,0,0,0,0,0,0,0,0,0,0,0,0,0,0~
,0,0,0,0,0,0,0,0,0,0,0,0,0,0,0)';$S;BIDI;
    'DDR5_SB_DQS_DN7':'(0,0,0,0,0,0,0,0,0,0,0,0,ET12,0,0,0,0,0,0,0,0,0,0,0,0,0,0~
,0,0,0,0,0,0,0,0,0,0,0,0,0,0,0)';$S;BIDI;
    'DDR5_SB_DQS_DN6':'(0,0,0,0,0,0,0,0,0,0,0,0,EJ21,0,0,0,0,0,0,0,0,0,0,0,0,0,0~
,0,0,0,0,0,0,0,0,0,0,0,0,0,0,0)';$S;BIDI;
    'DDR5_SB_DQS_DN5':'(0,0,0,0,0,0,0,0,0,0,0,0,EB30,0,0,0,0,0,0,0,0,0,0,0,0,0,0~
,0,0,0,0,0,0,0,0,0,0,0,0,0,0,0)';$S;BIDI;
    'DDR5_SB_DQS_DN4':'(0,0,0,0,0,0,0,0,0,0,0,0,EJ33,0,0,0,0,0,0,0,0,0,0,0,0,0,0~
,0,0,0,0,0,0,0,0,0,0,0,0,0,0,0)';$S;BIDI;
    'DDR5_SB_DQS_DN3':'(0,0,0,0,0,0,0,0,0,0,0,0,DT18,0,0,0,0,0,0,0,0,0,0,0,0,0,0~
,0,0,0,0,0,0,0,0,0,0,0,0,0,0,0)';$S;BIDI;
    'DDR5_SB_DQS_DN2':'(0,0,0,0,0,0,0,0,0,0,0,0,EM12,0,0,0,0,0,0,0,0,0,0,0,0,0,0~
,0,0,0,0,0,0,0,0,0,0,0,0,0,0,0)';$S;BIDI;
    'DDR5_SB_DQS_DN1':'(0,0,0,0,0,0,0,0,0,0,0,0,EE21,0,0,0,0,0,0,0,0,0,0,0,0,0,0~
,0,0,0,0,0,0,0,0,0,0,0,0,0,0,0)';$S;BIDI;
    'DDR5_SB_DQS_DN0':'(0,0,0,0,0,0,0,0,0,0,0,0,DV30,0,0,0,0,0,0,0,0,0,0,0,0,0,0~
,0,0,0,0,0,0,0,0,0,0,0,0,0,0,0)';$S;BIDI;
    'DDR5_SB_DQS_DP9':'(0,0,0,0,0,0,0,0,0,0,0,0,EC33,0,0,0,0,0,0,0,0,0,0,0,0,0,0~
,0,0,0,0,0,0,0,0,0,0,0,0,0,0,0)';$S;BIDI;
    'DDR5_SB_DQS_DP8':'(0,0,0,0,0,0,0,0,0,0,0,0,EB18,0,0,0,0,0,0,0,0,0,0,0,0,0,0~
,0,0,0,0,0,0,0,0,0,0,0,0,0,0,0)';$S;BIDI;
    'DDR5_SB_DQS_DP7':'(0,0,0,0,0,0,0,0,0,0,0,0,EP12,0,0,0,0,0,0,0,0,0,0,0,0,0,0~
,0,0,0,0,0,0,0,0,0,0,0,0,0,0,0)';$S;BIDI;
    'DDR5_SB_DQS_DP6':'(0,0,0,0,0,0,0,0,0,0,0,0,EG21,0,0,0,0,0,0,0,0,0,0,0,0,0,0~
,0,0,0,0,0,0,0,0,0,0,0,0,0,0,0)';$S;BIDI;
    'DDR5_SB_DQS_DP5':'(0,0,0,0,0,0,0,0,0,0,0,0,DY30,0,0,0,0,0,0,0,0,0,0,0,0,0,0~
,0,0,0,0,0,0,0,0,0,0,0,0,0,0,0)';$S;BIDI;
    'DDR5_SB_DQS_DP4':'(0,0,0,0,0,0,0,0,0,0,0,0,EG33,0,0,0,0,0,0,0,0,0,0,0,0,0,0~
,0,0,0,0,0,0,0,0,0,0,0,0,0,0,0)';$S;BIDI;
    'DDR5_SB_DQS_DP3':'(0,0,0,0,0,0,0,0,0,0,0,0,DV18,0,0,0,0,0,0,0,0,0,0,0,0,0,0~
,0,0,0,0,0,0,0,0,0,0,0,0,0,0,0)';$S;BIDI;
    'DDR5_SB_DQS_DP2':'(0,0,0,0,0,0,0,0,0,0,0,0,EK12,0,0,0,0,0,0,0,0,0,0,0,0,0,0~
,0,0,0,0,0,0,0,0,0,0,0,0,0,0,0)';$S;BIDI;
    'DDR5_SB_DQS_DP1':'(0,0,0,0,0,0,0,0,0,0,0,0,EC21,0,0,0,0,0,0,0,0,0,0,0,0,0,0~
,0,0,0,0,0,0,0,0,0,0,0,0,0,0,0)';$S;BIDI;
    'DDR5_SB_DQS_DP0':'(0,0,0,0,0,0,0,0,0,0,0,0,DT30,0,0,0,0,0,0,0,0,0,0,0,0,0,0~
,0,0,0,0,0,0,0,0,0,0,0,0,0,0,0)';$S;BIDI;
    'DDR5_SB_ECC7':'(0,0,0,0,0,0,0,0,0,0,0,0,EH34,0,0,0,0,0,0,0,0,0,0,0,0,0,0,0,~
0,0,0,0,0,0,0,0,0,0,0,0,0,0)';$S;BIDI;
    'DDR5_SB_ECC6':'(0,0,0,0,0,0,0,0,0,0,0,0,EG35,0,0,0,0,0,0,0,0,0,0,0,0,0,0,0,~
0,0,0,0,0,0,0,0,0,0,0,0,0,0)';$S;BIDI;
    'DDR5_SB_ECC5':'(0,0,0,0,0,0,0,0,0,0,0,0,ED34,0,0,0,0,0,0,0,0,0,0,0,0,0,0,0,~
0,0,0,0,0,0,0,0,0,0,0,0,0,0)';$S;BIDI;
    'DDR5_SB_ECC4':'(0,0,0,0,0,0,0,0,0,0,0,0,EE35,0,0,0,0,0,0,0,0,0,0,0,0,0,0,0,~
0,0,0,0,0,0,0,0,0,0,0,0,0,0)';$S;BIDI;
    'DDR5_SB_ECC3':'(0,0,0,0,0,0,0,0,0,0,0,0,EG31,0,0,0,0,0,0,0,0,0,0,0,0,0,0,0,~
0,0,0,0,0,0,0,0,0,0,0,0,0,0)';$S;BIDI;
    'DDR5_SB_ECC2':'(0,0,0,0,0,0,0,0,0,0,0,0,EH32,0,0,0,0,0,0,0,0,0,0,0,0,0,0,0,~
0,0,0,0,0,0,0,0,0,0,0,0,0,0)';$S;BIDI;
    'DDR5_SB_ECC1':'(0,0,0,0,0,0,0,0,0,0,0,0,EE31,0,0,0,0,0,0,0,0,0,0,0,0,0,0,0,~
0,0,0,0,0,0,0,0,0,0,0,0,0,0)';$S;BIDI;
    'DDR5_SB_ECC0':'(0,0,0,0,0,0,0,0,0,0,0,0,ED32,0,0,0,0,0,0,0,0,0,0,0,0,0,0,0,~
0,0,0,0,0,0,0,0,0,0,0,0,0,0)';$S;BIDI;
    'DDR5_SB_PAR':'(0,0,0,0,0,0,0,0,0,0,0,0,EJ39,0,0,0,0,0,0,0,0,0,0,0,0,0,0,0,0~
,0,0,0,0,0,0,0,0,0,0,0,0,0)';$S;OUT;
    'DDR6_ALERT_N':'(0,0,0,0,0,0,0,0,0,0,0,0,0,CW50,0,0,0,0,0,0,0,0,0,0,0,0,0,0,~
0,0,0,0,0,0,0,0,0,0,0,0,0,0)';$S;IN;
    'DDR6_A_RSP1':'(0,0,0,0,0,0,0,0,0,0,0,0,0,DY47,0,0,0,0,0,0,0,0,0,0,0,0,0,0,0~
,0,0,0,0,0,0,0,0,0,0,0,0,0)';$S;IN;
    'DDR6_A_RSP0':'(0,0,0,0,0,0,0,0,0,0,0,0,0,EA48,0,0,0,0,0,0,0,0,0,0,0,0,0,0,0~
,0,0,0,0,0,0,0,0,0,0,0,0,0)';$S;IN;
    'DDR6_B_RSP1':'(0,0,0,0,0,0,0,0,0,0,0,0,0,DV47,0,0,0,0,0,0,0,0,0,0,0,0,0,0,0~
,0,0,0,0,0,0,0,0,0,0,0,0,0)';$S;IN;
    'DDR6_B_RSP0':'(0,0,0,0,0,0,0,0,0,0,0,0,0,DU48,0,0,0,0,0,0,0,0,0,0,0,0,0,0,0~
,0,0,0,0,0,0,0,0,0,0,0,0,0)';$S;IN;
    'DDR6_CLK_DN1':'(0,0,0,0,0,0,0,0,0,0,0,0,0,DL45,0,0,0,0,0,0,0,0,0,0,0,0,0,0,~
0,0,0,0,0,0,0,0,0,0,0,0,0,0)';$S;OUT;
    'DDR6_CLK_DN0':'(0,0,0,0,0,0,0,0,0,0,0,0,0,DR45,0,0,0,0,0,0,0,0,0,0,0,0,0,0,~
0,0,0,0,0,0,0,0,0,0,0,0,0,0)';$S;OUT;
    'DDR6_CLK_DP1':'(0,0,0,0,0,0,0,0,0,0,0,0,0,DJ45,0,0,0,0,0,0,0,0,0,0,0,0,0,0,~
0,0,0,0,0,0,0,0,0,0,0,0,0,0)';$S;OUT;
    'DDR6_CLK_DP0':'(0,0,0,0,0,0,0,0,0,0,0,0,0,DN45,0,0,0,0,0,0,0,0,0,0,0,0,0,0,~
0,0,0,0,0,0,0,0,0,0,0,0,0,0)';$S;OUT;
    'DDR6_SA_CA6':'(0,0,0,0,0,0,0,0,0,0,0,0,0,DK44,0,0,0,0,0,0,0,0,0,0,0,0,0,0,0~
,0,0,0,0,0,0,0,0,0,0,0,0,0)';$S;OUT;
    'DDR6_SA_CA5':'(0,0,0,0,0,0,0,0,0,0,0,0,0,DN50,0,0,0,0,0,0,0,0,0,0,0,0,0,0,0~
,0,0,0,0,0,0,0,0,0,0,0,0,0)';$S;OUT;
    'DDR6_SA_CA4':'(0,0,0,0,0,0,0,0,0,0,0,0,0,DL50,0,0,0,0,0,0,0,0,0,0,0,0,0,0,0~
,0,0,0,0,0,0,0,0,0,0,0,0,0)';$S;OUT;
    'DDR6_SA_CA3':'(0,0,0,0,0,0,0,0,0,0,0,0,0,DP51,0,0,0,0,0,0,0,0,0,0,0,0,0,0,0~
,0,0,0,0,0,0,0,0,0,0,0,0,0)';$S;OUT;
    'DDR6_SA_CA2':'(0,0,0,0,0,0,0,0,0,0,0,0,0,DK51,0,0,0,0,0,0,0,0,0,0,0,0,0,0,0~
,0,0,0,0,0,0,0,0,0,0,0,0,0)';$S;OUT;
    'DDR6_SA_CA1':'(0,0,0,0,0,0,0,0,0,0,0,0,0,DR52,0,0,0,0,0,0,0,0,0,0,0,0,0,0,0~
,0,0,0,0,0,0,0,0,0,0,0,0,0)';$S;OUT;
    'DDR6_SA_CA0':'(0,0,0,0,0,0,0,0,0,0,0,0,0,DJ52,0,0,0,0,0,0,0,0,0,0,0,0,0,0,0~
,0,0,0,0,0,0,0,0,0,0,0,0,0)';$S;OUT;
    'DDR6_SA_CS_N3':'(0,0,0,0,0,0,0,0,0,0,0,0,0,DK53,0,0,0,0,0,0,0,0,0,0,0,0,0,0~
,0,0,0,0,0,0,0,0,0,0,0,0,0,0)';$S;OUT;
    'DDR6_SA_CS_N2':'(0,0,0,0,0,0,0,0,0,0,0,0,0,DL54,0,0,0,0,0,0,0,0,0,0,0,0,0,0~
,0,0,0,0,0,0,0,0,0,0,0,0,0,0)';$S;OUT;
    'DDR6_SA_CS_N1':'(0,0,0,0,0,0,0,0,0,0,0,0,0,DP53,0,0,0,0,0,0,0,0,0,0,0,0,0,0~
,0,0,0,0,0,0,0,0,0,0,0,0,0,0)';$S;OUT;
    'DDR6_SA_CS_N0':'(0,0,0,0,0,0,0,0,0,0,0,0,0,DN54,0,0,0,0,0,0,0,0,0,0,0,0,0,0~
,0,0,0,0,0,0,0,0,0,0,0,0,0,0)';$S;OUT;
    'DDR6_SA_DQ31':'(0,0,0,0,0,0,0,0,0,0,0,0,0,DN62,0,0,0,0,0,0,0,0,0,0,0,0,0,0,~
0,0,0,0,0,0,0,0,0,0,0,0,0,0)';$S;BIDI;
    'DDR6_SA_DQ30':'(0,0,0,0,0,0,0,0,0,0,0,0,0,DP63,0,0,0,0,0,0,0,0,0,0,0,0,0,0,~
0,0,0,0,0,0,0,0,0,0,0,0,0,0)';$S;BIDI;
    'DDR6_SA_DQ29':'(0,0,0,0,0,0,0,0,0,0,0,0,0,DL62,0,0,0,0,0,0,0,0,0,0,0,0,0,0,~
0,0,0,0,0,0,0,0,0,0,0,0,0,0)';$S;BIDI;
    'DDR6_SA_DQ28':'(0,0,0,0,0,0,0,0,0,0,0,0,0,DK63,0,0,0,0,0,0,0,0,0,0,0,0,0,0,~
0,0,0,0,0,0,0,0,0,0,0,0,0,0)';$S;BIDI;
    'DDR6_SA_DQ27':'(0,0,0,0,0,0,0,0,0,0,0,0,0,DP65,0,0,0,0,0,0,0,0,0,0,0,0,0,0,~
0,0,0,0,0,0,0,0,0,0,0,0,0,0)';$S;BIDI;
    'DDR6_SA_DQ26':'(0,0,0,0,0,0,0,0,0,0,0,0,0,DN66,0,0,0,0,0,0,0,0,0,0,0,0,0,0,~
0,0,0,0,0,0,0,0,0,0,0,0,0,0)';$S;BIDI;
    'DDR6_SA_DQ25':'(0,0,0,0,0,0,0,0,0,0,0,0,0,DK65,0,0,0,0,0,0,0,0,0,0,0,0,0,0,~
0,0,0,0,0,0,0,0,0,0,0,0,0,0)';$S;BIDI;
    'DDR6_SA_DQ24':'(0,0,0,0,0,0,0,0,0,0,0,0,0,DL66,0,0,0,0,0,0,0,0,0,0,0,0,0,0,~
0,0,0,0,0,0,0,0,0,0,0,0,0,0)';$S;BIDI;
    'DDR6_SA_DQ23':'(0,0,0,0,0,0,0,0,0,0,0,0,0,DY59,0,0,0,0,0,0,0,0,0,0,0,0,0,0,~
0,0,0,0,0,0,0,0,0,0,0,0,0,0)';$S;BIDI;
    'DDR6_SA_DQ22':'(0,0,0,0,0,0,0,0,0,0,0,0,0,EA60,0,0,0,0,0,0,0,0,0,0,0,0,0,0,~
0,0,0,0,0,0,0,0,0,0,0,0,0,0)';$S;BIDI;
    'DDR6_SA_DQ21':'(0,0,0,0,0,0,0,0,0,0,0,0,0,DV59,0,0,0,0,0,0,0,0,0,0,0,0,0,0,~
0,0,0,0,0,0,0,0,0,0,0,0,0,0)';$S;BIDI;
    'DDR6_SA_DQ20':'(0,0,0,0,0,0,0,0,0,0,0,0,0,DU60,0,0,0,0,0,0,0,0,0,0,0,0,0,0,~
0,0,0,0,0,0,0,0,0,0,0,0,0,0)';$S;BIDI;
    'DDR6_SA_DQ19':'(0,0,0,0,0,0,0,0,0,0,0,0,0,EA62,0,0,0,0,0,0,0,0,0,0,0,0,0,0,~
0,0,0,0,0,0,0,0,0,0,0,0,0,0)';$S;BIDI;
    'DDR6_SA_DQ18':'(0,0,0,0,0,0,0,0,0,0,0,0,0,DY63,0,0,0,0,0,0,0,0,0,0,0,0,0,0,~
0,0,0,0,0,0,0,0,0,0,0,0,0,0)';$S;BIDI;
    'DDR6_SA_DQ17':'(0,0,0,0,0,0,0,0,0,0,0,0,0,DU62,0,0,0,0,0,0,0,0,0,0,0,0,0,0,~
0,0,0,0,0,0,0,0,0,0,0,0,0,0)';$S;BIDI;
    'DDR6_SA_DQ16':'(0,0,0,0,0,0,0,0,0,0,0,0,0,DV63,0,0,0,0,0,0,0,0,0,0,0,0,0,0,~
0,0,0,0,0,0,0,0,0,0,0,0,0,0)';$S;BIDI;
    'DDR6_SA_DQ15':'(0,0,0,0,0,0,0,0,0,0,0,0,0,DN68,0,0,0,0,0,0,0,0,0,0,0,0,0,0,~
0,0,0,0,0,0,0,0,0,0,0,0,0,0)';$S;BIDI;
    'DDR6_SA_DQ14':'(0,0,0,0,0,0,0,0,0,0,0,0,0,DP69,0,0,0,0,0,0,0,0,0,0,0,0,0,0,~
0,0,0,0,0,0,0,0,0,0,0,0,0,0)';$S;BIDI;
    'DDR6_SA_DQ13':'(0,0,0,0,0,0,0,0,0,0,0,0,0,DL68,0,0,0,0,0,0,0,0,0,0,0,0,0,0,~
0,0,0,0,0,0,0,0,0,0,0,0,0,0)';$S;BIDI;
    'DDR6_SA_DQ12':'(0,0,0,0,0,0,0,0,0,0,0,0,0,DK69,0,0,0,0,0,0,0,0,0,0,0,0,0,0,~
0,0,0,0,0,0,0,0,0,0,0,0,0,0)';$S;BIDI;
    'DDR6_SA_DQ11':'(0,0,0,0,0,0,0,0,0,0,0,0,0,DP71,0,0,0,0,0,0,0,0,0,0,0,0,0,0,~
0,0,0,0,0,0,0,0,0,0,0,0,0,0)';$S;BIDI;
    'DDR6_SA_DQ10':'(0,0,0,0,0,0,0,0,0,0,0,0,0,DN72,0,0,0,0,0,0,0,0,0,0,0,0,0,0,~
0,0,0,0,0,0,0,0,0,0,0,0,0,0)';$S;BIDI;
    'DDR6_SA_DQ9':'(0,0,0,0,0,0,0,0,0,0,0,0,0,DK71,0,0,0,0,0,0,0,0,0,0,0,0,0,0,0~
,0,0,0,0,0,0,0,0,0,0,0,0,0)';$S;BIDI;
    'DDR6_SA_DQ8':'(0,0,0,0,0,0,0,0,0,0,0,0,0,DL72,0,0,0,0,0,0,0,0,0,0,0,0,0,0,0~
,0,0,0,0,0,0,0,0,0,0,0,0,0)';$S;BIDI;
    'DDR6_SA_DQ7':'(0,0,0,0,0,0,0,0,0,0,0,0,0,DY71,0,0,0,0,0,0,0,0,0,0,0,0,0,0,0~
,0,0,0,0,0,0,0,0,0,0,0,0,0)';$S;BIDI;
    'DDR6_SA_DQ6':'(0,0,0,0,0,0,0,0,0,0,0,0,0,EA72,0,0,0,0,0,0,0,0,0,0,0,0,0,0,0~
,0,0,0,0,0,0,0,0,0,0,0,0,0)';$S;BIDI;
    'DDR6_SA_DQ5':'(0,0,0,0,0,0,0,0,0,0,0,0,0,DV71,0,0,0,0,0,0,0,0,0,0,0,0,0,0,0~
,0,0,0,0,0,0,0,0,0,0,0,0,0)';$S;BIDI;
    'DDR6_SA_DQ4':'(0,0,0,0,0,0,0,0,0,0,0,0,0,DU72,0,0,0,0,0,0,0,0,0,0,0,0,0,0,0~
,0,0,0,0,0,0,0,0,0,0,0,0,0)';$S;BIDI;
    'DDR6_SA_DQ3':'(0,0,0,0,0,0,0,0,0,0,0,0,0,EA74,0,0,0,0,0,0,0,0,0,0,0,0,0,0,0~
,0,0,0,0,0,0,0,0,0,0,0,0,0)';$S;BIDI;
    'DDR6_SA_DQ2':'(0,0,0,0,0,0,0,0,0,0,0,0,0,DY75,0,0,0,0,0,0,0,0,0,0,0,0,0,0,0~
,0,0,0,0,0,0,0,0,0,0,0,0,0)';$S;BIDI;
    'DDR6_SA_DQ1':'(0,0,0,0,0,0,0,0,0,0,0,0,0,DU74,0,0,0,0,0,0,0,0,0,0,0,0,0,0,0~
,0,0,0,0,0,0,0,0,0,0,0,0,0)';$S;BIDI;
    'DDR6_SA_DQ0':'(0,0,0,0,0,0,0,0,0,0,0,0,0,DV75,0,0,0,0,0,0,0,0,0,0,0,0,0,0,0~
,0,0,0,0,0,0,0,0,0,0,0,0,0)';$S;BIDI;
    'DDR6_SA_DQS_DN9':'(0,0,0,0,0,0,0,0,0,0,0,0,0,DR58,0,0,0,0,0,0,0,0,0,0,0,0,0~
,0,0,0,0,0,0,0,0,0,0,0,0,0,0,0)';$S;BIDI;
    'DDR6_SA_DQS_DN8':'(0,0,0,0,0,0,0,0,0,0,0,0,0,DR64,0,0,0,0,0,0,0,0,0,0,0,0,0~
,0,0,0,0,0,0,0,0,0,0,0,0,0,0,0)';$S;BIDI;
    'DDR6_SA_DQS_DN7':'(0,0,0,0,0,0,0,0,0,0,0,0,0,EB61,0,0,0,0,0,0,0,0,0,0,0,0,0~
,0,0,0,0,0,0,0,0,0,0,0,0,0,0,0)';$S;BIDI;
    'DDR6_SA_DQS_DN6':'(0,0,0,0,0,0,0,0,0,0,0,0,0,DR70,0,0,0,0,0,0,0,0,0,0,0,0,0~
,0,0,0,0,0,0,0,0,0,0,0,0,0,0,0)';$S;BIDI;
    'DDR6_SA_DQS_DN5':'(0,0,0,0,0,0,0,0,0,0,0,0,0,EB73,0,0,0,0,0,0,0,0,0,0,0,0,0~
,0,0,0,0,0,0,0,0,0,0,0,0,0,0,0)';$S;BIDI;
    'DDR6_SA_DQS_DN4':'(0,0,0,0,0,0,0,0,0,0,0,0,0,DL58,0,0,0,0,0,0,0,0,0,0,0,0,0~
,0,0,0,0,0,0,0,0,0,0,0,0,0,0,0)';$S;BIDI;
    'DDR6_SA_DQS_DN3':'(0,0,0,0,0,0,0,0,0,0,0,0,0,DL64,0,0,0,0,0,0,0,0,0,0,0,0,0~
,0,0,0,0,0,0,0,0,0,0,0,0,0,0,0)';$S;BIDI;
    'DDR6_SA_DQS_DN2':'(0,0,0,0,0,0,0,0,0,0,0,0,0,DT61,0,0,0,0,0,0,0,0,0,0,0,0,0~
,0,0,0,0,0,0,0,0,0,0,0,0,0,0,0)';$S;BIDI;
    'DDR6_SA_DQS_DN1':'(0,0,0,0,0,0,0,0,0,0,0,0,0,DJ70,0,0,0,0,0,0,0,0,0,0,0,0,0~
,0,0,0,0,0,0,0,0,0,0,0,0,0,0,0)';$S;BIDI;
    'DDR6_SA_DQS_DN0':'(0,0,0,0,0,0,0,0,0,0,0,0,0,DV73,0,0,0,0,0,0,0,0,0,0,0,0,0~
,0,0,0,0,0,0,0,0,0,0,0,0,0,0,0)';$S;BIDI;
    'DDR6_SA_DQS_DP9':'(0,0,0,0,0,0,0,0,0,0,0,0,0,DN58,0,0,0,0,0,0,0,0,0,0,0,0,0~
,0,0,0,0,0,0,0,0,0,0,0,0,0,0,0)';$S;BIDI;
    'DDR6_SA_DQS_DP8':'(0,0,0,0,0,0,0,0,0,0,0,0,0,DN64,0,0,0,0,0,0,0,0,0,0,0,0,0~
,0,0,0,0,0,0,0,0,0,0,0,0,0,0,0)';$S;BIDI;
    'DDR6_SA_DQS_DP7':'(0,0,0,0,0,0,0,0,0,0,0,0,0,DY61,0,0,0,0,0,0,0,0,0,0,0,0,0~
,0,0,0,0,0,0,0,0,0,0,0,0,0,0,0)';$S;BIDI;
    'DDR6_SA_DQS_DP6':'(0,0,0,0,0,0,0,0,0,0,0,0,0,DN70,0,0,0,0,0,0,0,0,0,0,0,0,0~
,0,0,0,0,0,0,0,0,0,0,0,0,0,0,0)';$S;BIDI;
    'DDR6_SA_DQS_DP5':'(0,0,0,0,0,0,0,0,0,0,0,0,0,DY73,0,0,0,0,0,0,0,0,0,0,0,0,0~
,0,0,0,0,0,0,0,0,0,0,0,0,0,0,0)';$S;BIDI;
    'DDR6_SA_DQS_DP4':'(0,0,0,0,0,0,0,0,0,0,0,0,0,DJ58,0,0,0,0,0,0,0,0,0,0,0,0,0~
,0,0,0,0,0,0,0,0,0,0,0,0,0,0,0)';$S;BIDI;
    'DDR6_SA_DQS_DP3':'(0,0,0,0,0,0,0,0,0,0,0,0,0,DJ64,0,0,0,0,0,0,0,0,0,0,0,0,0~
,0,0,0,0,0,0,0,0,0,0,0,0,0,0,0)';$S;BIDI;
    'DDR6_SA_DQS_DP2':'(0,0,0,0,0,0,0,0,0,0,0,0,0,DV61,0,0,0,0,0,0,0,0,0,0,0,0,0~
,0,0,0,0,0,0,0,0,0,0,0,0,0,0,0)';$S;BIDI;
    'DDR6_SA_DQS_DP1':'(0,0,0,0,0,0,0,0,0,0,0,0,0,DL70,0,0,0,0,0,0,0,0,0,0,0,0,0~
,0,0,0,0,0,0,0,0,0,0,0,0,0,0,0)';$S;BIDI;
    'DDR6_SA_DQS_DP0':'(0,0,0,0,0,0,0,0,0,0,0,0,0,DT73,0,0,0,0,0,0,0,0,0,0,0,0,0~
,0,0,0,0,0,0,0,0,0,0,0,0,0,0,0)';$S;BIDI;
    'DDR6_SA_ECC7':'(0,0,0,0,0,0,0,0,0,0,0,0,0,DN56,0,0,0,0,0,0,0,0,0,0,0,0,0,0,~
0,0,0,0,0,0,0,0,0,0,0,0,0,0)';$S;BIDI;
    'DDR6_SA_ECC6':'(0,0,0,0,0,0,0,0,0,0,0,0,0,DP57,0,0,0,0,0,0,0,0,0,0,0,0,0,0,~
0,0,0,0,0,0,0,0,0,0,0,0,0,0)';$S;BIDI;
    'DDR6_SA_ECC5':'(0,0,0,0,0,0,0,0,0,0,0,0,0,DL56,0,0,0,0,0,0,0,0,0,0,0,0,0,0,~
0,0,0,0,0,0,0,0,0,0,0,0,0,0)';$S;BIDI;
    'DDR6_SA_ECC4':'(0,0,0,0,0,0,0,0,0,0,0,0,0,DK57,0,0,0,0,0,0,0,0,0,0,0,0,0,0,~
0,0,0,0,0,0,0,0,0,0,0,0,0,0)';$S;BIDI;
    'DDR6_SA_ECC3':'(0,0,0,0,0,0,0,0,0,0,0,0,0,DP59,0,0,0,0,0,0,0,0,0,0,0,0,0,0,~
0,0,0,0,0,0,0,0,0,0,0,0,0,0)';$S;BIDI;
    'DDR6_SA_ECC2':'(0,0,0,0,0,0,0,0,0,0,0,0,0,DN60,0,0,0,0,0,0,0,0,0,0,0,0,0,0,~
0,0,0,0,0,0,0,0,0,0,0,0,0,0)';$S;BIDI;
    'DDR6_SA_ECC1':'(0,0,0,0,0,0,0,0,0,0,0,0,0,DK59,0,0,0,0,0,0,0,0,0,0,0,0,0,0,~
0,0,0,0,0,0,0,0,0,0,0,0,0,0)';$S;BIDI;
    'DDR6_SA_ECC0':'(0,0,0,0,0,0,0,0,0,0,0,0,0,DL60,0,0,0,0,0,0,0,0,0,0,0,0,0,0,~
0,0,0,0,0,0,0,0,0,0,0,0,0,0)';$S;BIDI;
    'DDR6_SA_PAR':'(0,0,0,0,0,0,0,0,0,0,0,0,0,DL43,0,0,0,0,0,0,0,0,0,0,0,0,0,0,0~
,0,0,0,0,0,0,0,0,0,0,0,0,0)';$S;OUT;
    'DDR6_SB_CA6':'(0,0,0,0,0,0,0,0,0,0,0,0,0,DT42,0,0,0,0,0,0,0,0,0,0,0,0,0,0,0~
,0,0,0,0,0,0,0,0,0,0,0,0,0)';$S;OUT;
    'DDR6_SB_CA5':'(0,0,0,0,0,0,0,0,0,0,0,0,0,EA43,0,0,0,0,0,0,0,0,0,0,0,0,0,0,0~
,0,0,0,0,0,0,0,0,0,0,0,0,0)';$S;OUT;
    'DDR6_SB_CA4':'(0,0,0,0,0,0,0,0,0,0,0,0,0,DU43,0,0,0,0,0,0,0,0,0,0,0,0,0,0,0~
,0,0,0,0,0,0,0,0,0,0,0,0,0)';$S;OUT;
    'DDR6_SB_CA3':'(0,0,0,0,0,0,0,0,0,0,0,0,0,DY44,0,0,0,0,0,0,0,0,0,0,0,0,0,0,0~
,0,0,0,0,0,0,0,0,0,0,0,0,0)';$S;OUT;
    'DDR6_SB_CA2':'(0,0,0,0,0,0,0,0,0,0,0,0,0,DV44,0,0,0,0,0,0,0,0,0,0,0,0,0,0,0~
,0,0,0,0,0,0,0,0,0,0,0,0,0)';$S;OUT;
    'DDR6_SB_CA1':'(0,0,0,0,0,0,0,0,0,0,0,0,0,DP44,0,0,0,0,0,0,0,0,0,0,0,0,0,0,0~
,0,0,0,0,0,0,0,0,0,0,0,0,0)';$S;OUT;
    'DDR6_SB_CA0':'(0,0,0,0,0,0,0,0,0,0,0,0,0,DN43,0,0,0,0,0,0,0,0,0,0,0,0,0,0,0~
,0,0,0,0,0,0,0,0,0,0,0,0,0)';$S;OUT;
    'DDR6_SB_CS_N3':'(0,0,0,0,0,0,0,0,0,0,0,0,0,DV40,0,0,0,0,0,0,0,0,0,0,0,0,0,0~
,0,0,0,0,0,0,0,0,0,0,0,0,0,0)';$S;OUT;
    'DDR6_SB_CS_N2':'(0,0,0,0,0,0,0,0,0,0,0,0,0,DU41,0,0,0,0,0,0,0,0,0,0,0,0,0,0~
,0,0,0,0,0,0,0,0,0,0,0,0,0,0)';$S;OUT;
    'DDR6_SB_CS_N1':'(0,0,0,0,0,0,0,0,0,0,0,0,0,DY40,0,0,0,0,0,0,0,0,0,0,0,0,0,0~
,0,0,0,0,0,0,0,0,0,0,0,0,0,0)';$S;OUT;
    'DDR6_SB_CS_N0':'(0,0,0,0,0,0,0,0,0,0,0,0,0,EA41,0,0,0,0,0,0,0,0,0,0,0,0,0,0~
,0,0,0,0,0,0,0,0,0,0,0,0,0,0)';$S;OUT;
    'DDR6_SB_DQ31':'(0,0,0,0,0,0,0,0,0,0,0,0,0,EM4,0,0,0,0,0,0,0,0,0,0,0,0,0,0,0~
,0,0,0,0,0,0,0,0,0,0,0,0,0)';$S;BIDI;
    'DDR6_SB_DQ30':'(0,0,0,0,0,0,0,0,0,0,0,0,0,EP4,0,0,0,0,0,0,0,0,0,0,0,0,0,0,0~
,0,0,0,0,0,0,0,0,0,0,0,0,0)';$S;BIDI;
    'DDR6_SB_DQ29':'(0,0,0,0,0,0,0,0,0,0,0,0,0,EJ5,0,0,0,0,0,0,0,0,0,0,0,0,0,0,0~
,0,0,0,0,0,0,0,0,0,0,0,0,0)';$S;BIDI;
    'DDR6_SB_DQ28':'(0,0,0,0,0,0,0,0,0,0,0,0,0,EK6,0,0,0,0,0,0,0,0,0,0,0,0,0,0,0~
,0,0,0,0,0,0,0,0,0,0,0,0,0)';$S;BIDI;
    'DDR6_SB_DQ27':'(0,0,0,0,0,0,0,0,0,0,0,0,0,ET8,0,0,0,0,0,0,0,0,0,0,0,0,0,0,0~
,0,0,0,0,0,0,0,0,0,0,0,0,0)';$S;BIDI;
    'DDR6_SB_DQ26':'(0,0,0,0,0,0,0,0,0,0,0,0,0,EP8,0,0,0,0,0,0,0,0,0,0,0,0,0,0,0~
,0,0,0,0,0,0,0,0,0,0,0,0,0)';$S;BIDI;
    'DDR6_SB_DQ25':'(0,0,0,0,0,0,0,0,0,0,0,0,0,EH8,0,0,0,0,0,0,0,0,0,0,0,0,0,0,0~
,0,0,0,0,0,0,0,0,0,0,0,0,0)';$S;BIDI;
    'DDR6_SB_DQ24':'(0,0,0,0,0,0,0,0,0,0,0,0,0,EK8,0,0,0,0,0,0,0,0,0,0,0,0,0,0,0~
,0,0,0,0,0,0,0,0,0,0,0,0,0)';$S;BIDI;
    'DDR6_SB_DQ23':'(0,0,0,0,0,0,0,0,0,0,0,0,0,DY22,0,0,0,0,0,0,0,0,0,0,0,0,0,0,~
0,0,0,0,0,0,0,0,0,0,0,0,0,0)';$S;BIDI;
    'DDR6_SB_DQ22':'(0,0,0,0,0,0,0,0,0,0,0,0,0,EA23,0,0,0,0,0,0,0,0,0,0,0,0,0,0,~
0,0,0,0,0,0,0,0,0,0,0,0,0,0)';$S;BIDI;
    'DDR6_SB_DQ21':'(0,0,0,0,0,0,0,0,0,0,0,0,0,DV22,0,0,0,0,0,0,0,0,0,0,0,0,0,0,~
0,0,0,0,0,0,0,0,0,0,0,0,0,0)';$S;BIDI;
    'DDR6_SB_DQ20':'(0,0,0,0,0,0,0,0,0,0,0,0,0,DU23,0,0,0,0,0,0,0,0,0,0,0,0,0,0,~
0,0,0,0,0,0,0,0,0,0,0,0,0,0)';$S;BIDI;
    'DDR6_SB_DQ19':'(0,0,0,0,0,0,0,0,0,0,0,0,0,EA25,0,0,0,0,0,0,0,0,0,0,0,0,0,0,~
0,0,0,0,0,0,0,0,0,0,0,0,0,0)';$S;BIDI;
    'DDR6_SB_DQ18':'(0,0,0,0,0,0,0,0,0,0,0,0,0,DY26,0,0,0,0,0,0,0,0,0,0,0,0,0,0,~
0,0,0,0,0,0,0,0,0,0,0,0,0,0)';$S;BIDI;
    'DDR6_SB_DQ17':'(0,0,0,0,0,0,0,0,0,0,0,0,0,DU25,0,0,0,0,0,0,0,0,0,0,0,0,0,0,~
0,0,0,0,0,0,0,0,0,0,0,0,0,0)';$S;BIDI;
    'DDR6_SB_DQ16':'(0,0,0,0,0,0,0,0,0,0,0,0,0,DV26,0,0,0,0,0,0,0,0,0,0,0,0,0,0,~
0,0,0,0,0,0,0,0,0,0,0,0,0,0)';$S;BIDI;
    'DDR6_SB_DQ15':'(0,0,0,0,0,0,0,0,0,0,0,0,0,DN25,0,0,0,0,0,0,0,0,0,0,0,0,0,0,~
0,0,0,0,0,0,0,0,0,0,0,0,0,0)';$S;BIDI;
    'DDR6_SB_DQ14':'(0,0,0,0,0,0,0,0,0,0,0,0,0,DP26,0,0,0,0,0,0,0,0,0,0,0,0,0,0,~
0,0,0,0,0,0,0,0,0,0,0,0,0,0)';$S;BIDI;
    'DDR6_SB_DQ13':'(0,0,0,0,0,0,0,0,0,0,0,0,0,DL25,0,0,0,0,0,0,0,0,0,0,0,0,0,0,~
0,0,0,0,0,0,0,0,0,0,0,0,0,0)';$S;BIDI;
    'DDR6_SB_DQ12':'(0,0,0,0,0,0,0,0,0,0,0,0,0,DK26,0,0,0,0,0,0,0,0,0,0,0,0,0,0,~
0,0,0,0,0,0,0,0,0,0,0,0,0,0)';$S;BIDI;
    'DDR6_SB_DQ11':'(0,0,0,0,0,0,0,0,0,0,0,0,0,DP28,0,0,0,0,0,0,0,0,0,0,0,0,0,0,~
0,0,0,0,0,0,0,0,0,0,0,0,0,0)';$S;BIDI;
    'DDR6_SB_DQ10':'(0,0,0,0,0,0,0,0,0,0,0,0,0,DL29,0,0,0,0,0,0,0,0,0,0,0,0,0,0,~
0,0,0,0,0,0,0,0,0,0,0,0,0,0)';$S;BIDI;
    'DDR6_SB_DQ9':'(0,0,0,0,0,0,0,0,0,0,0,0,0,DK28,0,0,0,0,0,0,0,0,0,0,0,0,0,0,0~
,0,0,0,0,0,0,0,0,0,0,0,0,0)';$S;BIDI;
    'DDR6_SB_DQ8':'(0,0,0,0,0,0,0,0,0,0,0,0,0,DN29,0,0,0,0,0,0,0,0,0,0,0,0,0,0,0~
,0,0,0,0,0,0,0,0,0,0,0,0,0)';$S;BIDI;
    'DDR6_SB_DQ7':'(0,0,0,0,0,0,0,0,0,0,0,0,0,DN31,0,0,0,0,0,0,0,0,0,0,0,0,0,0,0~
,0,0,0,0,0,0,0,0,0,0,0,0,0)';$S;BIDI;
    'DDR6_SB_DQ6':'(0,0,0,0,0,0,0,0,0,0,0,0,0,DP32,0,0,0,0,0,0,0,0,0,0,0,0,0,0,0~
,0,0,0,0,0,0,0,0,0,0,0,0,0)';$S;BIDI;
    'DDR6_SB_DQ5':'(0,0,0,0,0,0,0,0,0,0,0,0,0,DL31,0,0,0,0,0,0,0,0,0,0,0,0,0,0,0~
,0,0,0,0,0,0,0,0,0,0,0,0,0)';$S;BIDI;
    'DDR6_SB_DQ4':'(0,0,0,0,0,0,0,0,0,0,0,0,0,DK32,0,0,0,0,0,0,0,0,0,0,0,0,0,0,0~
,0,0,0,0,0,0,0,0,0,0,0,0,0)';$S;BIDI;
    'DDR6_SB_DQ3':'(0,0,0,0,0,0,0,0,0,0,0,0,0,DP34,0,0,0,0,0,0,0,0,0,0,0,0,0,0,0~
,0,0,0,0,0,0,0,0,0,0,0,0,0)';$S;BIDI;
    'DDR6_SB_DQ2':'(0,0,0,0,0,0,0,0,0,0,0,0,0,DN35,0,0,0,0,0,0,0,0,0,0,0,0,0,0,0~
,0,0,0,0,0,0,0,0,0,0,0,0,0)';$S;BIDI;
    'DDR6_SB_DQ1':'(0,0,0,0,0,0,0,0,0,0,0,0,0,DK34,0,0,0,0,0,0,0,0,0,0,0,0,0,0,0~
,0,0,0,0,0,0,0,0,0,0,0,0,0)';$S;BIDI;
    'DDR6_SB_DQ0':'(0,0,0,0,0,0,0,0,0,0,0,0,0,DL35,0,0,0,0,0,0,0,0,0,0,0,0,0,0,0~
,0,0,0,0,0,0,0,0,0,0,0,0,0)';$S;BIDI;
    'DDR6_SB_DQS_DN9':'(0,0,0,0,0,0,0,0,0,0,0,0,0,DV36,0,0,0,0,0,0,0,0,0,0,0,0,0~
,0,0,0,0,0,0,0,0,0,0,0,0,0,0,0)';$S;BIDI;
    'DDR6_SB_DQS_DN8':'(0,0,0,0,0,0,0,0,0,0,0,0,0,EM6,0,0,0,0,0,0,0,0,0,0,0,0,0,~
0,0,0,0,0,0,0,0,0,0,0,0,0,0,0)';$S;BIDI;
    'DDR6_SB_DQS_DN7':'(0,0,0,0,0,0,0,0,0,0,0,0,0,EB24,0,0,0,0,0,0,0,0,0,0,0,0,0~
,0,0,0,0,0,0,0,0,0,0,0,0,0,0,0)';$S;BIDI;
    'DDR6_SB_DQS_DN6':'(0,0,0,0,0,0,0,0,0,0,0,0,0,DN27,0,0,0,0,0,0,0,0,0,0,0,0,0~
,0,0,0,0,0,0,0,0,0,0,0,0,0,0,0)';$S;BIDI;
    'DDR6_SB_DQS_DN5':'(0,0,0,0,0,0,0,0,0,0,0,0,0,DR33,0,0,0,0,0,0,0,0,0,0,0,0,0~
,0,0,0,0,0,0,0,0,0,0,0,0,0,0,0)';$S;BIDI;
    'DDR6_SB_DQS_DN4':'(0,0,0,0,0,0,0,0,0,0,0,0,0,EB36,0,0,0,0,0,0,0,0,0,0,0,0,0~
,0,0,0,0,0,0,0,0,0,0,0,0,0,0,0)';$S;BIDI;
    'DDR6_SB_DQS_DN3':'(0,0,0,0,0,0,0,0,0,0,0,0,0,EP6,0,0,0,0,0,0,0,0,0,0,0,0,0,~
0,0,0,0,0,0,0,0,0,0,0,0,0,0,0)';$S;BIDI;
    'DDR6_SB_DQS_DN2':'(0,0,0,0,0,0,0,0,0,0,0,0,0,DV24,0,0,0,0,0,0,0,0,0,0,0,0,0~
,0,0,0,0,0,0,0,0,0,0,0,0,0,0,0)';$S;BIDI;
    'DDR6_SB_DQS_DN1':'(0,0,0,0,0,0,0,0,0,0,0,0,0,DJ27,0,0,0,0,0,0,0,0,0,0,0,0,0~
,0,0,0,0,0,0,0,0,0,0,0,0,0,0,0)';$S;BIDI;
    'DDR6_SB_DQS_DN0':'(0,0,0,0,0,0,0,0,0,0,0,0,0,DJ33,0,0,0,0,0,0,0,0,0,0,0,0,0~
,0,0,0,0,0,0,0,0,0,0,0,0,0,0,0)';$S;BIDI;
    'DDR6_SB_DQS_DP9':'(0,0,0,0,0,0,0,0,0,0,0,0,0,DT36,0,0,0,0,0,0,0,0,0,0,0,0,0~
,0,0,0,0,0,0,0,0,0,0,0,0,0,0,0)';$S;BIDI;
    'DDR6_SB_DQS_DP8':'(0,0,0,0,0,0,0,0,0,0,0,0,0,EN5,0,0,0,0,0,0,0,0,0,0,0,0,0,~
0,0,0,0,0,0,0,0,0,0,0,0,0,0,0)';$S;BIDI;
    'DDR6_SB_DQS_DP7':'(0,0,0,0,0,0,0,0,0,0,0,0,0,DY24,0,0,0,0,0,0,0,0,0,0,0,0,0~
,0,0,0,0,0,0,0,0,0,0,0,0,0,0,0)';$S;BIDI;
    'DDR6_SB_DQS_DP6':'(0,0,0,0,0,0,0,0,0,0,0,0,0,DR27,0,0,0,0,0,0,0,0,0,0,0,0,0~
,0,0,0,0,0,0,0,0,0,0,0,0,0,0,0)';$S;BIDI;
    'DDR6_SB_DQS_DP5':'(0,0,0,0,0,0,0,0,0,0,0,0,0,DN33,0,0,0,0,0,0,0,0,0,0,0,0,0~
,0,0,0,0,0,0,0,0,0,0,0,0,0,0,0)';$S;BIDI;
    'DDR6_SB_DQS_DP4':'(0,0,0,0,0,0,0,0,0,0,0,0,0,DY36,0,0,0,0,0,0,0,0,0,0,0,0,0~
,0,0,0,0,0,0,0,0,0,0,0,0,0,0,0)';$S;BIDI;
    'DDR6_SB_DQS_DP3':'(0,0,0,0,0,0,0,0,0,0,0,0,0,EN7,0,0,0,0,0,0,0,0,0,0,0,0,0,~
0,0,0,0,0,0,0,0,0,0,0,0,0,0,0)';$S;BIDI;
    'DDR6_SB_DQS_DP2':'(0,0,0,0,0,0,0,0,0,0,0,0,0,DT24,0,0,0,0,0,0,0,0,0,0,0,0,0~
,0,0,0,0,0,0,0,0,0,0,0,0,0,0,0)';$S;BIDI;
    'DDR6_SB_DQS_DP1':'(0,0,0,0,0,0,0,0,0,0,0,0,0,DL27,0,0,0,0,0,0,0,0,0,0,0,0,0~
,0,0,0,0,0,0,0,0,0,0,0,0,0,0,0)';$S;BIDI;
    'DDR6_SB_DQS_DP0':'(0,0,0,0,0,0,0,0,0,0,0,0,0,DL33,0,0,0,0,0,0,0,0,0,0,0,0,0~
,0,0,0,0,0,0,0,0,0,0,0,0,0,0,0)';$S;BIDI;
    'DDR6_SB_ECC7':'(0,0,0,0,0,0,0,0,0,0,0,0,0,EA37,0,0,0,0,0,0,0,0,0,0,0,0,0,0,~
0,0,0,0,0,0,0,0,0,0,0,0,0,0)';$S;BIDI;
    'DDR6_SB_ECC6':'(0,0,0,0,0,0,0,0,0,0,0,0,0,DY38,0,0,0,0,0,0,0,0,0,0,0,0,0,0,~
0,0,0,0,0,0,0,0,0,0,0,0,0,0)';$S;BIDI;
    'DDR6_SB_ECC5':'(0,0,0,0,0,0,0,0,0,0,0,0,0,DU37,0,0,0,0,0,0,0,0,0,0,0,0,0,0,~
0,0,0,0,0,0,0,0,0,0,0,0,0,0)';$S;BIDI;
    'DDR6_SB_ECC4':'(0,0,0,0,0,0,0,0,0,0,0,0,0,DV38,0,0,0,0,0,0,0,0,0,0,0,0,0,0,~
0,0,0,0,0,0,0,0,0,0,0,0,0,0)';$S;BIDI;
    'DDR6_SB_ECC3':'(0,0,0,0,0,0,0,0,0,0,0,0,0,DY34,0,0,0,0,0,0,0,0,0,0,0,0,0,0,~
0,0,0,0,0,0,0,0,0,0,0,0,0,0)';$S;BIDI;
    'DDR6_SB_ECC2':'(0,0,0,0,0,0,0,0,0,0,0,0,0,EA35,0,0,0,0,0,0,0,0,0,0,0,0,0,0,~
0,0,0,0,0,0,0,0,0,0,0,0,0,0)';$S;BIDI;
    'DDR6_SB_ECC1':'(0,0,0,0,0,0,0,0,0,0,0,0,0,DV34,0,0,0,0,0,0,0,0,0,0,0,0,0,0,~
0,0,0,0,0,0,0,0,0,0,0,0,0,0)';$S;BIDI;
    'DDR6_SB_ECC0':'(0,0,0,0,0,0,0,0,0,0,0,0,0,DU35,0,0,0,0,0,0,0,0,0,0,0,0,0,0,~
0,0,0,0,0,0,0,0,0,0,0,0,0,0)';$S;BIDI;
    'DDR6_SB_PAR':'(0,0,0,0,0,0,0,0,0,0,0,0,0,EB42,0,0,0,0,0,0,0,0,0,0,0,0,0,0,0~
,0,0,0,0,0,0,0,0,0,0,0,0,0)';$S;OUT;
    'DDR7_ALERT_N':'(0,0,0,0,0,0,0,0,0,0,0,0,0,0,CY51,0,0,0,0,0,0,0,0,0,0,0,0,0,~
0,0,0,0,0,0,0,0,0,0,0,0,0,0)';$S;IN;
    'DDR7_A_RSP1':'(0,0,0,0,0,0,0,0,0,0,0,0,0,0,EH47,0,0,0,0,0,0,0,0,0,0,0,0,0,0~
,0,0,0,0,0,0,0,0,0,0,0,0,0)';$S;IN;
    'DDR7_A_RSP0':'(0,0,0,0,0,0,0,0,0,0,0,0,0,0,EG48,0,0,0,0,0,0,0,0,0,0,0,0,0,0~
,0,0,0,0,0,0,0,0,0,0,0,0,0)';$S;IN;
    'DDR7_B_RSP1':'(0,0,0,0,0,0,0,0,0,0,0,0,0,0,ED47,0,0,0,0,0,0,0,0,0,0,0,0,0,0~
,0,0,0,0,0,0,0,0,0,0,0,0,0)';$S;IN;
    'DDR7_B_RSP0':'(0,0,0,0,0,0,0,0,0,0,0,0,0,0,EE48,0,0,0,0,0,0,0,0,0,0,0,0,0,0~
,0,0,0,0,0,0,0,0,0,0,0,0,0)';$S;IN;
    'DDR7_CLK_DN1':'(0,0,0,0,0,0,0,0,0,0,0,0,0,0,DD42,0,0,0,0,0,0,0,0,0,0,0,0,0,~
0,0,0,0,0,0,0,0,0,0,0,0,0,0)';$S;OUT;
    'DDR7_CLK_DN0':'(0,0,0,0,0,0,0,0,0,0,0,0,0,0,DH42,0,0,0,0,0,0,0,0,0,0,0,0,0,~
0,0,0,0,0,0,0,0,0,0,0,0,0,0)';$S;OUT;
    'DDR7_CLK_DP1':'(0,0,0,0,0,0,0,0,0,0,0,0,0,0,DB42,0,0,0,0,0,0,0,0,0,0,0,0,0,~
0,0,0,0,0,0,0,0,0,0,0,0,0,0)';$S;OUT;
    'DDR7_CLK_DP0':'(0,0,0,0,0,0,0,0,0,0,0,0,0,0,DF42,0,0,0,0,0,0,0,0,0,0,0,0,0,~
0,0,0,0,0,0,0,0,0,0,0,0,0,0)';$S;OUT;
    'DDR7_SA_CA6':'(0,0,0,0,0,0,0,0,0,0,0,0,0,0,DC41,0,0,0,0,0,0,0,0,0,0,0,0,0,0~
,0,0,0,0,0,0,0,0,0,0,0,0,0)';$S;OUT;
    'DDR7_SA_CA5':'(0,0,0,0,0,0,0,0,0,0,0,0,0,0,DF47,0,0,0,0,0,0,0,0,0,0,0,0,0,0~
,0,0,0,0,0,0,0,0,0,0,0,0,0)';$S;OUT;
    'DDR7_SA_CA4':'(0,0,0,0,0,0,0,0,0,0,0,0,0,0,DD47,0,0,0,0,0,0,0,0,0,0,0,0,0,0~
,0,0,0,0,0,0,0,0,0,0,0,0,0)';$S;OUT;
    'DDR7_SA_CA3':'(0,0,0,0,0,0,0,0,0,0,0,0,0,0,DG48,0,0,0,0,0,0,0,0,0,0,0,0,0,0~
,0,0,0,0,0,0,0,0,0,0,0,0,0)';$S;OUT;
    'DDR7_SA_CA2':'(0,0,0,0,0,0,0,0,0,0,0,0,0,0,DC48,0,0,0,0,0,0,0,0,0,0,0,0,0,0~
,0,0,0,0,0,0,0,0,0,0,0,0,0)';$S;OUT;
    'DDR7_SA_CA1':'(0,0,0,0,0,0,0,0,0,0,0,0,0,0,DH49,0,0,0,0,0,0,0,0,0,0,0,0,0,0~
,0,0,0,0,0,0,0,0,0,0,0,0,0)';$S;OUT;
    'DDR7_SA_CA0':'(0,0,0,0,0,0,0,0,0,0,0,0,0,0,DB49,0,0,0,0,0,0,0,0,0,0,0,0,0,0~
,0,0,0,0,0,0,0,0,0,0,0,0,0)';$S;OUT;
    'DDR7_SA_CS_N3':'(0,0,0,0,0,0,0,0,0,0,0,0,0,0,DC50,0,0,0,0,0,0,0,0,0,0,0,0,0~
,0,0,0,0,0,0,0,0,0,0,0,0,0,0)';$S;OUT;
    'DDR7_SA_CS_N2':'(0,0,0,0,0,0,0,0,0,0,0,0,0,0,DD51,0,0,0,0,0,0,0,0,0,0,0,0,0~
,0,0,0,0,0,0,0,0,0,0,0,0,0,0)';$S;OUT;
    'DDR7_SA_CS_N1':'(0,0,0,0,0,0,0,0,0,0,0,0,0,0,DG50,0,0,0,0,0,0,0,0,0,0,0,0,0~
,0,0,0,0,0,0,0,0,0,0,0,0,0,0)';$S;OUT;
    'DDR7_SA_CS_N0':'(0,0,0,0,0,0,0,0,0,0,0,0,0,0,DF51,0,0,0,0,0,0,0,0,0,0,0,0,0~
,0,0,0,0,0,0,0,0,0,0,0,0,0,0)';$S;OUT;
    'DDR7_SA_DQ31':'(0,0,0,0,0,0,0,0,0,0,0,0,0,0,DF59,0,0,0,0,0,0,0,0,0,0,0,0,0,~
0,0,0,0,0,0,0,0,0,0,0,0,0,0)';$S;BIDI;
    'DDR7_SA_DQ30':'(0,0,0,0,0,0,0,0,0,0,0,0,0,0,DG60,0,0,0,0,0,0,0,0,0,0,0,0,0,~
0,0,0,0,0,0,0,0,0,0,0,0,0,0)';$S;BIDI;
    'DDR7_SA_DQ29':'(0,0,0,0,0,0,0,0,0,0,0,0,0,0,DD59,0,0,0,0,0,0,0,0,0,0,0,0,0,~
0,0,0,0,0,0,0,0,0,0,0,0,0,0)';$S;BIDI;
    'DDR7_SA_DQ28':'(0,0,0,0,0,0,0,0,0,0,0,0,0,0,DC60,0,0,0,0,0,0,0,0,0,0,0,0,0,~
0,0,0,0,0,0,0,0,0,0,0,0,0,0)';$S;BIDI;
    'DDR7_SA_DQ27':'(0,0,0,0,0,0,0,0,0,0,0,0,0,0,DG62,0,0,0,0,0,0,0,0,0,0,0,0,0,~
0,0,0,0,0,0,0,0,0,0,0,0,0,0)';$S;BIDI;
    'DDR7_SA_DQ26':'(0,0,0,0,0,0,0,0,0,0,0,0,0,0,DF63,0,0,0,0,0,0,0,0,0,0,0,0,0,~
0,0,0,0,0,0,0,0,0,0,0,0,0,0)';$S;BIDI;
    'DDR7_SA_DQ25':'(0,0,0,0,0,0,0,0,0,0,0,0,0,0,DC62,0,0,0,0,0,0,0,0,0,0,0,0,0,~
0,0,0,0,0,0,0,0,0,0,0,0,0,0)';$S;BIDI;
    'DDR7_SA_DQ24':'(0,0,0,0,0,0,0,0,0,0,0,0,0,0,DD63,0,0,0,0,0,0,0,0,0,0,0,0,0,~
0,0,0,0,0,0,0,0,0,0,0,0,0,0)';$S;BIDI;
    'DDR7_SA_DQ23':'(0,0,0,0,0,0,0,0,0,0,0,0,0,0,DF65,0,0,0,0,0,0,0,0,0,0,0,0,0,~
0,0,0,0,0,0,0,0,0,0,0,0,0,0)';$S;BIDI;
    'DDR7_SA_DQ22':'(0,0,0,0,0,0,0,0,0,0,0,0,0,0,DG66,0,0,0,0,0,0,0,0,0,0,0,0,0,~
0,0,0,0,0,0,0,0,0,0,0,0,0,0)';$S;BIDI;
    'DDR7_SA_DQ21':'(0,0,0,0,0,0,0,0,0,0,0,0,0,0,DD65,0,0,0,0,0,0,0,0,0,0,0,0,0,~
0,0,0,0,0,0,0,0,0,0,0,0,0,0)';$S;BIDI;
    'DDR7_SA_DQ20':'(0,0,0,0,0,0,0,0,0,0,0,0,0,0,DC66,0,0,0,0,0,0,0,0,0,0,0,0,0,~
0,0,0,0,0,0,0,0,0,0,0,0,0,0)';$S;BIDI;
    'DDR7_SA_DQ19':'(0,0,0,0,0,0,0,0,0,0,0,0,0,0,DG68,0,0,0,0,0,0,0,0,0,0,0,0,0,~
0,0,0,0,0,0,0,0,0,0,0,0,0,0)';$S;BIDI;
    'DDR7_SA_DQ18':'(0,0,0,0,0,0,0,0,0,0,0,0,0,0,DF69,0,0,0,0,0,0,0,0,0,0,0,0,0,~
0,0,0,0,0,0,0,0,0,0,0,0,0,0)';$S;BIDI;
    'DDR7_SA_DQ17':'(0,0,0,0,0,0,0,0,0,0,0,0,0,0,DC68,0,0,0,0,0,0,0,0,0,0,0,0,0,~
0,0,0,0,0,0,0,0,0,0,0,0,0,0)';$S;BIDI;
    'DDR7_SA_DQ16':'(0,0,0,0,0,0,0,0,0,0,0,0,0,0,DD69,0,0,0,0,0,0,0,0,0,0,0,0,0,~
0,0,0,0,0,0,0,0,0,0,0,0,0,0)';$S;BIDI;
    'DDR7_SA_DQ15':'(0,0,0,0,0,0,0,0,0,0,0,0,0,0,DF71,0,0,0,0,0,0,0,0,0,0,0,0,0,~
0,0,0,0,0,0,0,0,0,0,0,0,0,0)';$S;BIDI;
    'DDR7_SA_DQ14':'(0,0,0,0,0,0,0,0,0,0,0,0,0,0,DG72,0,0,0,0,0,0,0,0,0,0,0,0,0,~
0,0,0,0,0,0,0,0,0,0,0,0,0,0)';$S;BIDI;
    'DDR7_SA_DQ13':'(0,0,0,0,0,0,0,0,0,0,0,0,0,0,DD71,0,0,0,0,0,0,0,0,0,0,0,0,0,~
0,0,0,0,0,0,0,0,0,0,0,0,0,0)';$S;BIDI;
    'DDR7_SA_DQ12':'(0,0,0,0,0,0,0,0,0,0,0,0,0,0,DC72,0,0,0,0,0,0,0,0,0,0,0,0,0,~
0,0,0,0,0,0,0,0,0,0,0,0,0,0)';$S;BIDI;
    'DDR7_SA_DQ11':'(0,0,0,0,0,0,0,0,0,0,0,0,0,0,DG74,0,0,0,0,0,0,0,0,0,0,0,0,0,~
0,0,0,0,0,0,0,0,0,0,0,0,0,0)';$S;BIDI;
    'DDR7_SA_DQ10':'(0,0,0,0,0,0,0,0,0,0,0,0,0,0,DF75,0,0,0,0,0,0,0,0,0,0,0,0,0,~
0,0,0,0,0,0,0,0,0,0,0,0,0,0)';$S;BIDI;
    'DDR7_SA_DQ9':'(0,0,0,0,0,0,0,0,0,0,0,0,0,0,DC74,0,0,0,0,0,0,0,0,0,0,0,0,0,0~
,0,0,0,0,0,0,0,0,0,0,0,0,0)';$S;BIDI;
    'DDR7_SA_DQ8':'(0,0,0,0,0,0,0,0,0,0,0,0,0,0,DD75,0,0,0,0,0,0,0,0,0,0,0,0,0,0~
,0,0,0,0,0,0,0,0,0,0,0,0,0)';$S;BIDI;
    'DDR7_SA_DQ7':'(0,0,0,0,0,0,0,0,0,0,0,0,0,0,DN74,0,0,0,0,0,0,0,0,0,0,0,0,0,0~
,0,0,0,0,0,0,0,0,0,0,0,0,0)';$S;BIDI;
    'DDR7_SA_DQ6':'(0,0,0,0,0,0,0,0,0,0,0,0,0,0,DP75,0,0,0,0,0,0,0,0,0,0,0,0,0,0~
,0,0,0,0,0,0,0,0,0,0,0,0,0)';$S;BIDI;
    'DDR7_SA_DQ5':'(0,0,0,0,0,0,0,0,0,0,0,0,0,0,DL74,0,0,0,0,0,0,0,0,0,0,0,0,0,0~
,0,0,0,0,0,0,0,0,0,0,0,0,0)';$S;BIDI;
    'DDR7_SA_DQ4':'(0,0,0,0,0,0,0,0,0,0,0,0,0,0,DK75,0,0,0,0,0,0,0,0,0,0,0,0,0,0~
,0,0,0,0,0,0,0,0,0,0,0,0,0)';$S;BIDI;
    'DDR7_SA_DQ3':'(0,0,0,0,0,0,0,0,0,0,0,0,0,0,DP77,0,0,0,0,0,0,0,0,0,0,0,0,0,0~
,0,0,0,0,0,0,0,0,0,0,0,0,0)';$S;BIDI;
    'DDR7_SA_DQ2':'(0,0,0,0,0,0,0,0,0,0,0,0,0,0,DW78,0,0,0,0,0,0,0,0,0,0,0,0,0,0~
,0,0,0,0,0,0,0,0,0,0,0,0,0)';$S;BIDI;
    'DDR7_SA_DQ1':'(0,0,0,0,0,0,0,0,0,0,0,0,0,0,DT77,0,0,0,0,0,0,0,0,0,0,0,0,0,0~
,0,0,0,0,0,0,0,0,0,0,0,0,0)';$S;BIDI;
    'DDR7_SA_DQ0':'(0,0,0,0,0,0,0,0,0,0,0,0,0,0,DY79,0,0,0,0,0,0,0,0,0,0,0,0,0,0~
,0,0,0,0,0,0,0,0,0,0,0,0,0)';$S;BIDI;
    'DDR7_SA_DQS_DN9':'(0,0,0,0,0,0,0,0,0,0,0,0,0,0,DH55,0,0,0,0,0,0,0,0,0,0,0,0~
,0,0,0,0,0,0,0,0,0,0,0,0,0,0,0)';$S;BIDI;
    'DDR7_SA_DQS_DN8':'(0,0,0,0,0,0,0,0,0,0,0,0,0,0,DH61,0,0,0,0,0,0,0,0,0,0,0,0~
,0,0,0,0,0,0,0,0,0,0,0,0,0,0,0)';$S;BIDI;
    'DDR7_SA_DQS_DN7':'(0,0,0,0,0,0,0,0,0,0,0,0,0,0,DH67,0,0,0,0,0,0,0,0,0,0,0,0~
,0,0,0,0,0,0,0,0,0,0,0,0,0,0,0)';$S;BIDI;
    'DDR7_SA_DQS_DN6':'(0,0,0,0,0,0,0,0,0,0,0,0,0,0,DH73,0,0,0,0,0,0,0,0,0,0,0,0~
,0,0,0,0,0,0,0,0,0,0,0,0,0,0,0)';$S;BIDI;
    'DDR7_SA_DQS_DN5':'(0,0,0,0,0,0,0,0,0,0,0,0,0,0,DR76,0,0,0,0,0,0,0,0,0,0,0,0~
,0,0,0,0,0,0,0,0,0,0,0,0,0,0,0)';$S;BIDI;
    'DDR7_SA_DQS_DN4':'(0,0,0,0,0,0,0,0,0,0,0,0,0,0,DD55,0,0,0,0,0,0,0,0,0,0,0,0~
,0,0,0,0,0,0,0,0,0,0,0,0,0,0,0)';$S;BIDI;
    'DDR7_SA_DQS_DN3':'(0,0,0,0,0,0,0,0,0,0,0,0,0,0,DD61,0,0,0,0,0,0,0,0,0,0,0,0~
,0,0,0,0,0,0,0,0,0,0,0,0,0,0,0)';$S;BIDI;
    'DDR7_SA_DQS_DN2':'(0,0,0,0,0,0,0,0,0,0,0,0,0,0,DD67,0,0,0,0,0,0,0,0,0,0,0,0~
,0,0,0,0,0,0,0,0,0,0,0,0,0,0,0)';$S;BIDI;
    'DDR7_SA_DQS_DN1':'(0,0,0,0,0,0,0,0,0,0,0,0,0,0,DB73,0,0,0,0,0,0,0,0,0,0,0,0~
,0,0,0,0,0,0,0,0,0,0,0,0,0,0,0)';$S;BIDI;
    'DDR7_SA_DQS_DN0':'(0,0,0,0,0,0,0,0,0,0,0,0,0,0,DJ76,0,0,0,0,0,0,0,0,0,0,0,0~
,0,0,0,0,0,0,0,0,0,0,0,0,0,0,0)';$S;BIDI;
    'DDR7_SA_DQS_DP9':'(0,0,0,0,0,0,0,0,0,0,0,0,0,0,DF55,0,0,0,0,0,0,0,0,0,0,0,0~
,0,0,0,0,0,0,0,0,0,0,0,0,0,0,0)';$S;BIDI;
    'DDR7_SA_DQS_DP8':'(0,0,0,0,0,0,0,0,0,0,0,0,0,0,DF61,0,0,0,0,0,0,0,0,0,0,0,0~
,0,0,0,0,0,0,0,0,0,0,0,0,0,0,0)';$S;BIDI;
    'DDR7_SA_DQS_DP7':'(0,0,0,0,0,0,0,0,0,0,0,0,0,0,DF67,0,0,0,0,0,0,0,0,0,0,0,0~
,0,0,0,0,0,0,0,0,0,0,0,0,0,0,0)';$S;BIDI;
    'DDR7_SA_DQS_DP6':'(0,0,0,0,0,0,0,0,0,0,0,0,0,0,DF73,0,0,0,0,0,0,0,0,0,0,0,0~
,0,0,0,0,0,0,0,0,0,0,0,0,0,0,0)';$S;BIDI;
    'DDR7_SA_DQS_DP5':'(0,0,0,0,0,0,0,0,0,0,0,0,0,0,DN76,0,0,0,0,0,0,0,0,0,0,0,0~
,0,0,0,0,0,0,0,0,0,0,0,0,0,0,0)';$S;BIDI;
    'DDR7_SA_DQS_DP4':'(0,0,0,0,0,0,0,0,0,0,0,0,0,0,DB55,0,0,0,0,0,0,0,0,0,0,0,0~
,0,0,0,0,0,0,0,0,0,0,0,0,0,0,0)';$S;BIDI;
    'DDR7_SA_DQS_DP3':'(0,0,0,0,0,0,0,0,0,0,0,0,0,0,DB61,0,0,0,0,0,0,0,0,0,0,0,0~
,0,0,0,0,0,0,0,0,0,0,0,0,0,0,0)';$S;BIDI;
    'DDR7_SA_DQS_DP2':'(0,0,0,0,0,0,0,0,0,0,0,0,0,0,DB67,0,0,0,0,0,0,0,0,0,0,0,0~
,0,0,0,0,0,0,0,0,0,0,0,0,0,0,0)';$S;BIDI;
    'DDR7_SA_DQS_DP1':'(0,0,0,0,0,0,0,0,0,0,0,0,0,0,DD73,0,0,0,0,0,0,0,0,0,0,0,0~
,0,0,0,0,0,0,0,0,0,0,0,0,0,0,0)';$S;BIDI;
    'DDR7_SA_DQS_DP0':'(0,0,0,0,0,0,0,0,0,0,0,0,0,0,DL76,0,0,0,0,0,0,0,0,0,0,0,0~
,0,0,0,0,0,0,0,0,0,0,0,0,0,0,0)';$S;BIDI;
    'DDR7_SA_ECC7':'(0,0,0,0,0,0,0,0,0,0,0,0,0,0,DF53,0,0,0,0,0,0,0,0,0,0,0,0,0,~
0,0,0,0,0,0,0,0,0,0,0,0,0,0)';$S;BIDI;
    'DDR7_SA_ECC6':'(0,0,0,0,0,0,0,0,0,0,0,0,0,0,DG54,0,0,0,0,0,0,0,0,0,0,0,0,0,~
0,0,0,0,0,0,0,0,0,0,0,0,0,0)';$S;BIDI;
    'DDR7_SA_ECC5':'(0,0,0,0,0,0,0,0,0,0,0,0,0,0,DD53,0,0,0,0,0,0,0,0,0,0,0,0,0,~
0,0,0,0,0,0,0,0,0,0,0,0,0,0)';$S;BIDI;
    'DDR7_SA_ECC4':'(0,0,0,0,0,0,0,0,0,0,0,0,0,0,DC54,0,0,0,0,0,0,0,0,0,0,0,0,0,~
0,0,0,0,0,0,0,0,0,0,0,0,0,0)';$S;BIDI;
    'DDR7_SA_ECC3':'(0,0,0,0,0,0,0,0,0,0,0,0,0,0,DG56,0,0,0,0,0,0,0,0,0,0,0,0,0,~
0,0,0,0,0,0,0,0,0,0,0,0,0,0)';$S;BIDI;
    'DDR7_SA_ECC2':'(0,0,0,0,0,0,0,0,0,0,0,0,0,0,DF57,0,0,0,0,0,0,0,0,0,0,0,0,0,~
0,0,0,0,0,0,0,0,0,0,0,0,0,0)';$S;BIDI;
    'DDR7_SA_ECC1':'(0,0,0,0,0,0,0,0,0,0,0,0,0,0,DC56,0,0,0,0,0,0,0,0,0,0,0,0,0,~
0,0,0,0,0,0,0,0,0,0,0,0,0,0)';$S;BIDI;
    'DDR7_SA_ECC0':'(0,0,0,0,0,0,0,0,0,0,0,0,0,0,DD57,0,0,0,0,0,0,0,0,0,0,0,0,0,~
0,0,0,0,0,0,0,0,0,0,0,0,0,0)';$S;BIDI;
    'DDR7_SA_PAR':'(0,0,0,0,0,0,0,0,0,0,0,0,0,0,DD40,0,0,0,0,0,0,0,0,0,0,0,0,0,0~
,0,0,0,0,0,0,0,0,0,0,0,0,0)';$S;OUT;
    'DDR7_SB_CA6':'(0,0,0,0,0,0,0,0,0,0,0,0,0,0,DJ39,0,0,0,0,0,0,0,0,0,0,0,0,0,0~
,0,0,0,0,0,0,0,0,0,0,0,0,0)';$S;OUT;
    'DDR7_SB_CA5':'(0,0,0,0,0,0,0,0,0,0,0,0,0,0,DP40,0,0,0,0,0,0,0,0,0,0,0,0,0,0~
,0,0,0,0,0,0,0,0,0,0,0,0,0)';$S;OUT;
    'DDR7_SB_CA4':'(0,0,0,0,0,0,0,0,0,0,0,0,0,0,DK40,0,0,0,0,0,0,0,0,0,0,0,0,0,0~
,0,0,0,0,0,0,0,0,0,0,0,0,0)';$S;OUT;
    'DDR7_SB_CA3':'(0,0,0,0,0,0,0,0,0,0,0,0,0,0,DN41,0,0,0,0,0,0,0,0,0,0,0,0,0,0~
,0,0,0,0,0,0,0,0,0,0,0,0,0)';$S;OUT;
    'DDR7_SB_CA2':'(0,0,0,0,0,0,0,0,0,0,0,0,0,0,DL41,0,0,0,0,0,0,0,0,0,0,0,0,0,0~
,0,0,0,0,0,0,0,0,0,0,0,0,0)';$S;OUT;
    'DDR7_SB_CA1':'(0,0,0,0,0,0,0,0,0,0,0,0,0,0,DG41,0,0,0,0,0,0,0,0,0,0,0,0,0,0~
,0,0,0,0,0,0,0,0,0,0,0,0,0)';$S;OUT;
    'DDR7_SB_CA0':'(0,0,0,0,0,0,0,0,0,0,0,0,0,0,DF40,0,0,0,0,0,0,0,0,0,0,0,0,0,0~
,0,0,0,0,0,0,0,0,0,0,0,0,0)';$S;OUT;
    'DDR7_SB_CS_N3':'(0,0,0,0,0,0,0,0,0,0,0,0,0,0,DP38,0,0,0,0,0,0,0,0,0,0,0,0,0~
,0,0,0,0,0,0,0,0,0,0,0,0,0,0)';$S;OUT;
    'DDR7_SB_CS_N2':'(0,0,0,0,0,0,0,0,0,0,0,0,0,0,DK38,0,0,0,0,0,0,0,0,0,0,0,0,0~
,0,0,0,0,0,0,0,0,0,0,0,0,0,0)';$S;OUT;
    'DDR7_SB_CS_N1':'(0,0,0,0,0,0,0,0,0,0,0,0,0,0,DN37,0,0,0,0,0,0,0,0,0,0,0,0,0~
,0,0,0,0,0,0,0,0,0,0,0,0,0,0)';$S;OUT;
    'DDR7_SB_CS_N0':'(0,0,0,0,0,0,0,0,0,0,0,0,0,0,DL37,0,0,0,0,0,0,0,0,0,0,0,0,0~
,0,0,0,0,0,0,0,0,0,0,0,0,0,0)';$S;OUT;
    'DDR7_SB_DQ31':'(0,0,0,0,0,0,0,0,0,0,0,0,0,0,DC17,0,0,0,0,0,0,0,0,0,0,0,0,0,~
0,0,0,0,0,0,0,0,0,0,0,0,0,0)';$S;BIDI;
    'DDR7_SB_DQ30':'(0,0,0,0,0,0,0,0,0,0,0,0,0,0,DJ17,0,0,0,0,0,0,0,0,0,0,0,0,0,~
0,0,0,0,0,0,0,0,0,0,0,0,0,0)';$S;BIDI;
    'DDR7_SB_DQ29':'(0,0,0,0,0,0,0,0,0,0,0,0,0,0,DA17,0,0,0,0,0,0,0,0,0,0,0,0,0,~
0,0,0,0,0,0,0,0,0,0,0,0,0,0)';$S;BIDI;
    'DDR7_SB_DQ28':'(0,0,0,0,0,0,0,0,0,0,0,0,0,0,DG17,0,0,0,0,0,0,0,0,0,0,0,0,0,~
0,0,0,0,0,0,0,0,0,0,0,0,0,0)';$S;BIDI;
    'DDR7_SB_DQ27':'(0,0,0,0,0,0,0,0,0,0,0,0,0,0,DG19,0,0,0,0,0,0,0,0,0,0,0,0,0,~
0,0,0,0,0,0,0,0,0,0,0,0,0,0)';$S;BIDI;
    'DDR7_SB_DQ26':'(0,0,0,0,0,0,0,0,0,0,0,0,0,0,DF20,0,0,0,0,0,0,0,0,0,0,0,0,0,~
0,0,0,0,0,0,0,0,0,0,0,0,0,0)';$S;BIDI;
    'DDR7_SB_DQ25':'(0,0,0,0,0,0,0,0,0,0,0,0,0,0,DC19,0,0,0,0,0,0,0,0,0,0,0,0,0,~
0,0,0,0,0,0,0,0,0,0,0,0,0,0)';$S;BIDI;
    'DDR7_SB_DQ24':'(0,0,0,0,0,0,0,0,0,0,0,0,0,0,DD20,0,0,0,0,0,0,0,0,0,0,0,0,0,~
0,0,0,0,0,0,0,0,0,0,0,0,0,0)';$S;BIDI;
    'DDR7_SB_DQ23':'(0,0,0,0,0,0,0,0,0,0,0,0,0,0,DN19,0,0,0,0,0,0,0,0,0,0,0,0,0,~
0,0,0,0,0,0,0,0,0,0,0,0,0,0)';$S;BIDI;
    'DDR7_SB_DQ22':'(0,0,0,0,0,0,0,0,0,0,0,0,0,0,DP20,0,0,0,0,0,0,0,0,0,0,0,0,0,~
0,0,0,0,0,0,0,0,0,0,0,0,0,0)';$S;BIDI;
    'DDR7_SB_DQ21':'(0,0,0,0,0,0,0,0,0,0,0,0,0,0,DL19,0,0,0,0,0,0,0,0,0,0,0,0,0,~
0,0,0,0,0,0,0,0,0,0,0,0,0,0)';$S;BIDI;
    'DDR7_SB_DQ20':'(0,0,0,0,0,0,0,0,0,0,0,0,0,0,DK20,0,0,0,0,0,0,0,0,0,0,0,0,0,~
0,0,0,0,0,0,0,0,0,0,0,0,0,0)';$S;BIDI;
    'DDR7_SB_DQ19':'(0,0,0,0,0,0,0,0,0,0,0,0,0,0,DP22,0,0,0,0,0,0,0,0,0,0,0,0,0,~
0,0,0,0,0,0,0,0,0,0,0,0,0,0)';$S;BIDI;
    'DDR7_SB_DQ18':'(0,0,0,0,0,0,0,0,0,0,0,0,0,0,DN23,0,0,0,0,0,0,0,0,0,0,0,0,0,~
0,0,0,0,0,0,0,0,0,0,0,0,0,0)';$S;BIDI;
    'DDR7_SB_DQ17':'(0,0,0,0,0,0,0,0,0,0,0,0,0,0,DK22,0,0,0,0,0,0,0,0,0,0,0,0,0,~
0,0,0,0,0,0,0,0,0,0,0,0,0,0)';$S;BIDI;
    'DDR7_SB_DQ16':'(0,0,0,0,0,0,0,0,0,0,0,0,0,0,DL23,0,0,0,0,0,0,0,0,0,0,0,0,0,~
0,0,0,0,0,0,0,0,0,0,0,0,0,0)';$S;BIDI;
    'DDR7_SB_DQ15':'(0,0,0,0,0,0,0,0,0,0,0,0,0,0,DF22,0,0,0,0,0,0,0,0,0,0,0,0,0,~
0,0,0,0,0,0,0,0,0,0,0,0,0,0)';$S;BIDI;
    'DDR7_SB_DQ14':'(0,0,0,0,0,0,0,0,0,0,0,0,0,0,DG23,0,0,0,0,0,0,0,0,0,0,0,0,0,~
0,0,0,0,0,0,0,0,0,0,0,0,0,0)';$S;BIDI;
    'DDR7_SB_DQ13':'(0,0,0,0,0,0,0,0,0,0,0,0,0,0,DD22,0,0,0,0,0,0,0,0,0,0,0,0,0,~
0,0,0,0,0,0,0,0,0,0,0,0,0,0)';$S;BIDI;
    'DDR7_SB_DQ12':'(0,0,0,0,0,0,0,0,0,0,0,0,0,0,DC23,0,0,0,0,0,0,0,0,0,0,0,0,0,~
0,0,0,0,0,0,0,0,0,0,0,0,0,0)';$S;BIDI;
    'DDR7_SB_DQ11':'(0,0,0,0,0,0,0,0,0,0,0,0,0,0,DG25,0,0,0,0,0,0,0,0,0,0,0,0,0,~
0,0,0,0,0,0,0,0,0,0,0,0,0,0)';$S;BIDI;
    'DDR7_SB_DQ10':'(0,0,0,0,0,0,0,0,0,0,0,0,0,0,DF26,0,0,0,0,0,0,0,0,0,0,0,0,0,~
0,0,0,0,0,0,0,0,0,0,0,0,0,0)';$S;BIDI;
    'DDR7_SB_DQ9':'(0,0,0,0,0,0,0,0,0,0,0,0,0,0,DC25,0,0,0,0,0,0,0,0,0,0,0,0,0,0~
,0,0,0,0,0,0,0,0,0,0,0,0,0)';$S;BIDI;
    'DDR7_SB_DQ8':'(0,0,0,0,0,0,0,0,0,0,0,0,0,0,DD26,0,0,0,0,0,0,0,0,0,0,0,0,0,0~
,0,0,0,0,0,0,0,0,0,0,0,0,0)';$S;BIDI;
    'DDR7_SB_DQ7':'(0,0,0,0,0,0,0,0,0,0,0,0,0,0,DD28,0,0,0,0,0,0,0,0,0,0,0,0,0,0~
,0,0,0,0,0,0,0,0,0,0,0,0,0)';$S;BIDI;
    'DDR7_SB_DQ6':'(0,0,0,0,0,0,0,0,0,0,0,0,0,0,DG29,0,0,0,0,0,0,0,0,0,0,0,0,0,0~
,0,0,0,0,0,0,0,0,0,0,0,0,0)';$S;BIDI;
    'DDR7_SB_DQ5':'(0,0,0,0,0,0,0,0,0,0,0,0,0,0,DF28,0,0,0,0,0,0,0,0,0,0,0,0,0,0~
,0,0,0,0,0,0,0,0,0,0,0,0,0)';$S;BIDI;
    'DDR7_SB_DQ4':'(0,0,0,0,0,0,0,0,0,0,0,0,0,0,DC29,0,0,0,0,0,0,0,0,0,0,0,0,0,0~
,0,0,0,0,0,0,0,0,0,0,0,0,0)';$S;BIDI;
    'DDR7_SB_DQ3':'(0,0,0,0,0,0,0,0,0,0,0,0,0,0,DG31,0,0,0,0,0,0,0,0,0,0,0,0,0,0~
,0,0,0,0,0,0,0,0,0,0,0,0,0)';$S;BIDI;
    'DDR7_SB_DQ2':'(0,0,0,0,0,0,0,0,0,0,0,0,0,0,DF32,0,0,0,0,0,0,0,0,0,0,0,0,0,0~
,0,0,0,0,0,0,0,0,0,0,0,0,0)';$S;BIDI;
    'DDR7_SB_DQ1':'(0,0,0,0,0,0,0,0,0,0,0,0,0,0,DC31,0,0,0,0,0,0,0,0,0,0,0,0,0,0~
,0,0,0,0,0,0,0,0,0,0,0,0,0)';$S;BIDI;
    'DDR7_SB_DQ0':'(0,0,0,0,0,0,0,0,0,0,0,0,0,0,DD32,0,0,0,0,0,0,0,0,0,0,0,0,0,0~
,0,0,0,0,0,0,0,0,0,0,0,0,0)';$S;BIDI;
    'DDR7_SB_DQS_DN9':'(0,0,0,0,0,0,0,0,0,0,0,0,0,0,DD36,0,0,0,0,0,0,0,0,0,0,0,0~
,0,0,0,0,0,0,0,0,0,0,0,0,0,0,0)';$S;BIDI;
    'DDR7_SB_DQS_DN8':'(0,0,0,0,0,0,0,0,0,0,0,0,0,0,DF18,0,0,0,0,0,0,0,0,0,0,0,0~
,0,0,0,0,0,0,0,0,0,0,0,0,0,0,0)';$S;BIDI;
    'DDR7_SB_DQS_DN7':'(0,0,0,0,0,0,0,0,0,0,0,0,0,0,DR21,0,0,0,0,0,0,0,0,0,0,0,0~
,0,0,0,0,0,0,0,0,0,0,0,0,0,0,0)';$S;BIDI;
    'DDR7_SB_DQS_DN6':'(0,0,0,0,0,0,0,0,0,0,0,0,0,0,DH24,0,0,0,0,0,0,0,0,0,0,0,0~
,0,0,0,0,0,0,0,0,0,0,0,0,0,0,0)';$S;BIDI;
    'DDR7_SB_DQS_DN5':'(0,0,0,0,0,0,0,0,0,0,0,0,0,0,DH30,0,0,0,0,0,0,0,0,0,0,0,0~
,0,0,0,0,0,0,0,0,0,0,0,0,0,0,0)';$S;BIDI;
    'DDR7_SB_DQS_DN4':'(0,0,0,0,0,0,0,0,0,0,0,0,0,0,DH36,0,0,0,0,0,0,0,0,0,0,0,0~
,0,0,0,0,0,0,0,0,0,0,0,0,0,0,0)';$S;BIDI;
    'DDR7_SB_DQS_DN3':'(0,0,0,0,0,0,0,0,0,0,0,0,0,0,DB18,0,0,0,0,0,0,0,0,0,0,0,0~
,0,0,0,0,0,0,0,0,0,0,0,0,0,0,0)';$S;BIDI;
    'DDR7_SB_DQS_DN2':'(0,0,0,0,0,0,0,0,0,0,0,0,0,0,DL21,0,0,0,0,0,0,0,0,0,0,0,0~
,0,0,0,0,0,0,0,0,0,0,0,0,0,0,0)';$S;BIDI;
    'DDR7_SB_DQS_DN1':'(0,0,0,0,0,0,0,0,0,0,0,0,0,0,DD24,0,0,0,0,0,0,0,0,0,0,0,0~
,0,0,0,0,0,0,0,0,0,0,0,0,0,0,0)';$S;BIDI;
    'DDR7_SB_DQS_DN0':'(0,0,0,0,0,0,0,0,0,0,0,0,0,0,DD30,0,0,0,0,0,0,0,0,0,0,0,0~
,0,0,0,0,0,0,0,0,0,0,0,0,0,0,0)';$S;BIDI;
    'DDR7_SB_DQS_DP9':'(0,0,0,0,0,0,0,0,0,0,0,0,0,0,DB36,0,0,0,0,0,0,0,0,0,0,0,0~
,0,0,0,0,0,0,0,0,0,0,0,0,0,0,0)';$S;BIDI;
    'DDR7_SB_DQS_DP8':'(0,0,0,0,0,0,0,0,0,0,0,0,0,0,DH18,0,0,0,0,0,0,0,0,0,0,0,0~
,0,0,0,0,0,0,0,0,0,0,0,0,0,0,0)';$S;BIDI;
    'DDR7_SB_DQS_DP7':'(0,0,0,0,0,0,0,0,0,0,0,0,0,0,DN21,0,0,0,0,0,0,0,0,0,0,0,0~
,0,0,0,0,0,0,0,0,0,0,0,0,0,0,0)';$S;BIDI;
    'DDR7_SB_DQS_DP6':'(0,0,0,0,0,0,0,0,0,0,0,0,0,0,DF24,0,0,0,0,0,0,0,0,0,0,0,0~
,0,0,0,0,0,0,0,0,0,0,0,0,0,0,0)';$S;BIDI;
    'DDR7_SB_DQS_DP5':'(0,0,0,0,0,0,0,0,0,0,0,0,0,0,DF30,0,0,0,0,0,0,0,0,0,0,0,0~
,0,0,0,0,0,0,0,0,0,0,0,0,0,0,0)';$S;BIDI;
    'DDR7_SB_DQS_DP4':'(0,0,0,0,0,0,0,0,0,0,0,0,0,0,DF36,0,0,0,0,0,0,0,0,0,0,0,0~
,0,0,0,0,0,0,0,0,0,0,0,0,0,0,0)';$S;BIDI;
    'DDR7_SB_DQS_DP3':'(0,0,0,0,0,0,0,0,0,0,0,0,0,0,DD18,0,0,0,0,0,0,0,0,0,0,0,0~
,0,0,0,0,0,0,0,0,0,0,0,0,0,0,0)';$S;BIDI;
    'DDR7_SB_DQS_DP2':'(0,0,0,0,0,0,0,0,0,0,0,0,0,0,DJ21,0,0,0,0,0,0,0,0,0,0,0,0~
,0,0,0,0,0,0,0,0,0,0,0,0,0,0,0)';$S;BIDI;
    'DDR7_SB_DQS_DP1':'(0,0,0,0,0,0,0,0,0,0,0,0,0,0,DB24,0,0,0,0,0,0,0,0,0,0,0,0~
,0,0,0,0,0,0,0,0,0,0,0,0,0,0,0)';$S;BIDI;
    'DDR7_SB_DQS_DP0':'(0,0,0,0,0,0,0,0,0,0,0,0,0,0,DB30,0,0,0,0,0,0,0,0,0,0,0,0~
,0,0,0,0,0,0,0,0,0,0,0,0,0,0,0)';$S;BIDI;
    'DDR7_SB_ECC7':'(0,0,0,0,0,0,0,0,0,0,0,0,0,0,DC37,0,0,0,0,0,0,0,0,0,0,0,0,0,~
0,0,0,0,0,0,0,0,0,0,0,0,0,0)';$S;BIDI;
    'DDR7_SB_ECC6':'(0,0,0,0,0,0,0,0,0,0,0,0,0,0,DD38,0,0,0,0,0,0,0,0,0,0,0,0,0,~
0,0,0,0,0,0,0,0,0,0,0,0,0,0)';$S;BIDI;
    'DDR7_SB_ECC5':'(0,0,0,0,0,0,0,0,0,0,0,0,0,0,DG37,0,0,0,0,0,0,0,0,0,0,0,0,0,~
0,0,0,0,0,0,0,0,0,0,0,0,0,0)';$S;BIDI;
    'DDR7_SB_ECC4':'(0,0,0,0,0,0,0,0,0,0,0,0,0,0,DF38,0,0,0,0,0,0,0,0,0,0,0,0,0,~
0,0,0,0,0,0,0,0,0,0,0,0,0,0)';$S;BIDI;
    'DDR7_SB_ECC3':'(0,0,0,0,0,0,0,0,0,0,0,0,0,0,DF34,0,0,0,0,0,0,0,0,0,0,0,0,0,~
0,0,0,0,0,0,0,0,0,0,0,0,0,0)';$S;BIDI;
    'DDR7_SB_ECC2':'(0,0,0,0,0,0,0,0,0,0,0,0,0,0,DG35,0,0,0,0,0,0,0,0,0,0,0,0,0,~
0,0,0,0,0,0,0,0,0,0,0,0,0,0)';$S;BIDI;
    'DDR7_SB_ECC1':'(0,0,0,0,0,0,0,0,0,0,0,0,0,0,DD34,0,0,0,0,0,0,0,0,0,0,0,0,0,~
0,0,0,0,0,0,0,0,0,0,0,0,0,0)';$S;BIDI;
    'DDR7_SB_ECC0':'(0,0,0,0,0,0,0,0,0,0,0,0,0,0,DC35,0,0,0,0,0,0,0,0,0,0,0,0,0,~
0,0,0,0,0,0,0,0,0,0,0,0,0,0)';$S;BIDI;
    'DDR7_SB_PAR':'(0,0,0,0,0,0,0,0,0,0,0,0,0,0,DR39,0,0,0,0,0,0,0,0,0,0,0,0,0,0~
,0,0,0,0,0,0,0,0,0,0,0,0,0)';$S;OUT;
    'DMI_RX_DN7':'(0,0,0,0,0,0,0,0,0,0,0,0,0,0,0,BU17,0,0,0,0,0,0,0,0,0,0,0,0,0,~
0,0,0,0,0,0,0,0,0,0,0,0,0)';$S;IN;
    'DMI_RX_DN6':'(0,0,0,0,0,0,0,0,0,0,0,0,0,0,0,BP18,0,0,0,0,0,0,0,0,0,0,0,0,0,~
0,0,0,0,0,0,0,0,0,0,0,0,0)';$S;IN;
    'DMI_RX_DN5':'(0,0,0,0,0,0,0,0,0,0,0,0,0,0,0,BN17,0,0,0,0,0,0,0,0,0,0,0,0,0,~
0,0,0,0,0,0,0,0,0,0,0,0,0)';$S;IN;
    'DMI_RX_DN4':'(0,0,0,0,0,0,0,0,0,0,0,0,0,0,0,BK18,0,0,0,0,0,0,0,0,0,0,0,0,0,~
0,0,0,0,0,0,0,0,0,0,0,0,0)';$S;IN;
    'DMI_RX_DN3':'(0,0,0,0,0,0,0,0,0,0,0,0,0,0,0,BJ17,0,0,0,0,0,0,0,0,0,0,0,0,0,~
0,0,0,0,0,0,0,0,0,0,0,0,0)';$S;IN;
    'DMI_RX_DN2':'(0,0,0,0,0,0,0,0,0,0,0,0,0,0,0,BF18,0,0,0,0,0,0,0,0,0,0,0,0,0,~
0,0,0,0,0,0,0,0,0,0,0,0,0)';$S;IN;
    'DMI_RX_DN1':'(0,0,0,0,0,0,0,0,0,0,0,0,0,0,0,BE17,0,0,0,0,0,0,0,0,0,0,0,0,0,~
0,0,0,0,0,0,0,0,0,0,0,0,0)';$S;IN;
    'DMI_RX_DN0':'(0,0,0,0,0,0,0,0,0,0,0,0,0,0,0,BB18,0,0,0,0,0,0,0,0,0,0,0,0,0,~
0,0,0,0,0,0,0,0,0,0,0,0,0)';$S;IN;
    'DMI_RX_DP7':'(0,0,0,0,0,0,0,0,0,0,0,0,0,0,0,BT18,0,0,0,0,0,0,0,0,0,0,0,0,0,~
0,0,0,0,0,0,0,0,0,0,0,0,0)';$S;IN;
    'DMI_RX_DP6':'(0,0,0,0,0,0,0,0,0,0,0,0,0,0,0,BR19,0,0,0,0,0,0,0,0,0,0,0,0,0,~
0,0,0,0,0,0,0,0,0,0,0,0,0)';$S;IN;
    'DMI_RX_DP5':'(0,0,0,0,0,0,0,0,0,0,0,0,0,0,0,BM18,0,0,0,0,0,0,0,0,0,0,0,0,0,~
0,0,0,0,0,0,0,0,0,0,0,0,0)';$S;IN;
    'DMI_RX_DP4':'(0,0,0,0,0,0,0,0,0,0,0,0,0,0,0,BL19,0,0,0,0,0,0,0,0,0,0,0,0,0,~
0,0,0,0,0,0,0,0,0,0,0,0,0)';$S;IN;
    'DMI_RX_DP3':'(0,0,0,0,0,0,0,0,0,0,0,0,0,0,0,BH18,0,0,0,0,0,0,0,0,0,0,0,0,0,~
0,0,0,0,0,0,0,0,0,0,0,0,0)';$S;IN;
    'DMI_RX_DP2':'(0,0,0,0,0,0,0,0,0,0,0,0,0,0,0,BG19,0,0,0,0,0,0,0,0,0,0,0,0,0,~
0,0,0,0,0,0,0,0,0,0,0,0,0)';$S;IN;
    'DMI_RX_DP1':'(0,0,0,0,0,0,0,0,0,0,0,0,0,0,0,BD18,0,0,0,0,0,0,0,0,0,0,0,0,0,~
0,0,0,0,0,0,0,0,0,0,0,0,0)';$S;IN;
    'DMI_RX_DP0':'(0,0,0,0,0,0,0,0,0,0,0,0,0,0,0,BC19,0,0,0,0,0,0,0,0,0,0,0,0,0,~
0,0,0,0,0,0,0,0,0,0,0,0,0)';$S;IN;
    'DMI_TX_DN7':'(0,0,0,0,0,0,0,0,0,0,0,0,0,0,0,CN17,0,0,0,0,0,0,0,0,0,0,0,0,0,~
0,0,0,0,0,0,0,0,0,0,0,0,0)';$S;OUT;
    'DMI_TX_DN6':'(0,0,0,0,0,0,0,0,0,0,0,0,0,0,0,CK18,0,0,0,0,0,0,0,0,0,0,0,0,0,~
0,0,0,0,0,0,0,0,0,0,0,0,0)';$S;OUT;
    'DMI_TX_DN5':'(0,0,0,0,0,0,0,0,0,0,0,0,0,0,0,CJ17,0,0,0,0,0,0,0,0,0,0,0,0,0,~
0,0,0,0,0,0,0,0,0,0,0,0,0)';$S;OUT;
    'DMI_TX_DN4':'(0,0,0,0,0,0,0,0,0,0,0,0,0,0,0,CF18,0,0,0,0,0,0,0,0,0,0,0,0,0,~
0,0,0,0,0,0,0,0,0,0,0,0,0)';$S;OUT;
    'DMI_TX_DN3':'(0,0,0,0,0,0,0,0,0,0,0,0,0,0,0,CE17,0,0,0,0,0,0,0,0,0,0,0,0,0,~
0,0,0,0,0,0,0,0,0,0,0,0,0)';$S;OUT;
    'DMI_TX_DN2':'(0,0,0,0,0,0,0,0,0,0,0,0,0,0,0,CB18,0,0,0,0,0,0,0,0,0,0,0,0,0,~
0,0,0,0,0,0,0,0,0,0,0,0,0)';$S;OUT;
    'DMI_TX_DN1':'(0,0,0,0,0,0,0,0,0,0,0,0,0,0,0,CA17,0,0,0,0,0,0,0,0,0,0,0,0,0,~
0,0,0,0,0,0,0,0,0,0,0,0,0)';$S;OUT;
    'DMI_TX_DN0':'(0,0,0,0,0,0,0,0,0,0,0,0,0,0,0,BW19,0,0,0,0,0,0,0,0,0,0,0,0,0,~
0,0,0,0,0,0,0,0,0,0,0,0,0)';$S;OUT;
    'DMI_TX_DP7':'(0,0,0,0,0,0,0,0,0,0,0,0,0,0,0,CM18,0,0,0,0,0,0,0,0,0,0,0,0,0,~
0,0,0,0,0,0,0,0,0,0,0,0,0)';$S;OUT;
    'DMI_TX_DP6':'(0,0,0,0,0,0,0,0,0,0,0,0,0,0,0,CL19,0,0,0,0,0,0,0,0,0,0,0,0,0,~
0,0,0,0,0,0,0,0,0,0,0,0,0)';$S;OUT;
    'DMI_TX_DP5':'(0,0,0,0,0,0,0,0,0,0,0,0,0,0,0,CH18,0,0,0,0,0,0,0,0,0,0,0,0,0,~
0,0,0,0,0,0,0,0,0,0,0,0,0)';$S;OUT;
    'DMI_TX_DP4':'(0,0,0,0,0,0,0,0,0,0,0,0,0,0,0,CG19,0,0,0,0,0,0,0,0,0,0,0,0,0,~
0,0,0,0,0,0,0,0,0,0,0,0,0)';$S;OUT;
    'DMI_TX_DP3':'(0,0,0,0,0,0,0,0,0,0,0,0,0,0,0,CD18,0,0,0,0,0,0,0,0,0,0,0,0,0,~
0,0,0,0,0,0,0,0,0,0,0,0,0)';$S;OUT;
    'DMI_TX_DP2':'(0,0,0,0,0,0,0,0,0,0,0,0,0,0,0,CC19,0,0,0,0,0,0,0,0,0,0,0,0,0,~
0,0,0,0,0,0,0,0,0,0,0,0,0)';$S;OUT;
    'DMI_TX_DP1':'(0,0,0,0,0,0,0,0,0,0,0,0,0,0,0,BY18,0,0,0,0,0,0,0,0,0,0,0,0,0,~
0,0,0,0,0,0,0,0,0,0,0,0,0)';$S;OUT;
    'DMI_TX_DP0':'(0,0,0,0,0,0,0,0,0,0,0,0,0,0,0,CA19,0,0,0,0,0,0,0,0,0,0,0,0,0,~
0,0,0,0,0,0,0,0,0,0,0,0,0)';$S;OUT;
    'PE0_RX_DN15':'(0,0,0,0,0,0,0,0,0,0,0,0,0,0,0,0,BA9,0,0,0,0,0,0,0,0,0,0,0,0,~
0,0,0,0,0,0,0,0,0,0,0,0,0)';$S;IN;
    'PE0_RX_DN14':'(0,0,0,0,0,0,0,0,0,0,0,0,0,0,0,0,AV10,0,0,0,0,0,0,0,0,0,0,0,0~
,0,0,0,0,0,0,0,0,0,0,0,0,0)';$S;IN;
    'PE0_RX_DN13':'(0,0,0,0,0,0,0,0,0,0,0,0,0,0,0,0,AU9,0,0,0,0,0,0,0,0,0,0,0,0,~
0,0,0,0,0,0,0,0,0,0,0,0,0)';$S;IN;
    'PE0_RX_DN12':'(0,0,0,0,0,0,0,0,0,0,0,0,0,0,0,0,AP10,0,0,0,0,0,0,0,0,0,0,0,0~
,0,0,0,0,0,0,0,0,0,0,0,0,0)';$S;IN;
    'PE0_RX_DN11':'(0,0,0,0,0,0,0,0,0,0,0,0,0,0,0,0,AM10,0,0,0,0,0,0,0,0,0,0,0,0~
,0,0,0,0,0,0,0,0,0,0,0,0,0)';$S;IN;
    'PE0_RX_DN10':'(0,0,0,0,0,0,0,0,0,0,0,0,0,0,0,0,AK10,0,0,0,0,0,0,0,0,0,0,0,0~
,0,0,0,0,0,0,0,0,0,0,0,0,0)';$S;IN;
    'PE0_RX_DN9':'(0,0,0,0,0,0,0,0,0,0,0,0,0,0,0,0,AJ9,0,0,0,0,0,0,0,0,0,0,0,0,0~
,0,0,0,0,0,0,0,0,0,0,0,0)';$S;IN;
    'PE0_RX_DN8':'(0,0,0,0,0,0,0,0,0,0,0,0,0,0,0,0,AF10,0,0,0,0,0,0,0,0,0,0,0,0,~
0,0,0,0,0,0,0,0,0,0,0,0,0)';$S;IN;
    'PE0_RX_DN7':'(0,0,0,0,0,0,0,0,0,0,0,0,0,0,0,0,AE9,0,0,0,0,0,0,0,0,0,0,0,0,0~
,0,0,0,0,0,0,0,0,0,0,0,0)';$S;IN;
    'PE0_RX_DN6':'(0,0,0,0,0,0,0,0,0,0,0,0,0,0,0,0,AB10,0,0,0,0,0,0,0,0,0,0,0,0,~
0,0,0,0,0,0,0,0,0,0,0,0,0)';$S;IN;
    'PE0_RX_DN5':'(0,0,0,0,0,0,0,0,0,0,0,0,0,0,0,0,AA9,0,0,0,0,0,0,0,0,0,0,0,0,0~
,0,0,0,0,0,0,0,0,0,0,0,0)';$S;IN;
    'PE0_RX_DN4':'(0,0,0,0,0,0,0,0,0,0,0,0,0,0,0,0,V10,0,0,0,0,0,0,0,0,0,0,0,0,0~
,0,0,0,0,0,0,0,0,0,0,0,0)';$S;IN;
    'PE0_RX_DN3':'(0,0,0,0,0,0,0,0,0,0,0,0,0,0,0,0,T10,0,0,0,0,0,0,0,0,0,0,0,0,0~
,0,0,0,0,0,0,0,0,0,0,0,0)';$S;IN;
    'PE0_RX_DN2':'(0,0,0,0,0,0,0,0,0,0,0,0,0,0,0,0,P10,0,0,0,0,0,0,0,0,0,0,0,0,0~
,0,0,0,0,0,0,0,0,0,0,0,0)';$S;IN;
    'PE0_RX_DN1':'(0,0,0,0,0,0,0,0,0,0,0,0,0,0,0,0,M10,0,0,0,0,0,0,0,0,0,0,0,0,0~
,0,0,0,0,0,0,0,0,0,0,0,0)';$S;IN;
    'PE0_RX_DN0':'(0,0,0,0,0,0,0,0,0,0,0,0,0,0,0,0,K10,0,0,0,0,0,0,0,0,0,0,0,0,0~
,0,0,0,0,0,0,0,0,0,0,0,0)';$S;IN;
    'PE0_RX_DP15':'(0,0,0,0,0,0,0,0,0,0,0,0,0,0,0,0,AY10,0,0,0,0,0,0,0,0,0,0,0,0~
,0,0,0,0,0,0,0,0,0,0,0,0,0)';$S;IN;
    'PE0_RX_DP14':'(0,0,0,0,0,0,0,0,0,0,0,0,0,0,0,0,AW11,0,0,0,0,0,0,0,0,0,0,0,0~
,0,0,0,0,0,0,0,0,0,0,0,0,0)';$S;IN;
    'PE0_RX_DP13':'(0,0,0,0,0,0,0,0,0,0,0,0,0,0,0,0,AT10,0,0,0,0,0,0,0,0,0,0,0,0~
,0,0,0,0,0,0,0,0,0,0,0,0,0)';$S;IN;
    'PE0_RX_DP12':'(0,0,0,0,0,0,0,0,0,0,0,0,0,0,0,0,AR11,0,0,0,0,0,0,0,0,0,0,0,0~
,0,0,0,0,0,0,0,0,0,0,0,0,0)';$S;IN;
    'PE0_RX_DP11':'(0,0,0,0,0,0,0,0,0,0,0,0,0,0,0,0,AN9,0,0,0,0,0,0,0,0,0,0,0,0,~
0,0,0,0,0,0,0,0,0,0,0,0,0)';$S;IN;
    'PE0_RX_DP10':'(0,0,0,0,0,0,0,0,0,0,0,0,0,0,0,0,AL11,0,0,0,0,0,0,0,0,0,0,0,0~
,0,0,0,0,0,0,0,0,0,0,0,0,0)';$S;IN;
    'PE0_RX_DP9':'(0,0,0,0,0,0,0,0,0,0,0,0,0,0,0,0,AH10,0,0,0,0,0,0,0,0,0,0,0,0,~
0,0,0,0,0,0,0,0,0,0,0,0,0)';$S;IN;
    'PE0_RX_DP8':'(0,0,0,0,0,0,0,0,0,0,0,0,0,0,0,0,AG11,0,0,0,0,0,0,0,0,0,0,0,0,~
0,0,0,0,0,0,0,0,0,0,0,0,0)';$S;IN;
    'PE0_RX_DP7':'(0,0,0,0,0,0,0,0,0,0,0,0,0,0,0,0,AD10,0,0,0,0,0,0,0,0,0,0,0,0,~
0,0,0,0,0,0,0,0,0,0,0,0,0)';$S;IN;
    'PE0_RX_DP6':'(0,0,0,0,0,0,0,0,0,0,0,0,0,0,0,0,AC11,0,0,0,0,0,0,0,0,0,0,0,0,~
0,0,0,0,0,0,0,0,0,0,0,0,0)';$S;IN;
    'PE0_RX_DP5':'(0,0,0,0,0,0,0,0,0,0,0,0,0,0,0,0,Y10,0,0,0,0,0,0,0,0,0,0,0,0,0~
,0,0,0,0,0,0,0,0,0,0,0,0)';$S;IN;
    'PE0_RX_DP4':'(0,0,0,0,0,0,0,0,0,0,0,0,0,0,0,0,W11,0,0,0,0,0,0,0,0,0,0,0,0,0~
,0,0,0,0,0,0,0,0,0,0,0,0)';$S;IN;
    'PE0_RX_DP3':'(0,0,0,0,0,0,0,0,0,0,0,0,0,0,0,0,U9,0,0,0,0,0,0,0,0,0,0,0,0,0,~
0,0,0,0,0,0,0,0,0,0,0,0)';$S;IN;
    'PE0_RX_DP2':'(0,0,0,0,0,0,0,0,0,0,0,0,0,0,0,0,R11,0,0,0,0,0,0,0,0,0,0,0,0,0~
,0,0,0,0,0,0,0,0,0,0,0,0)';$S;IN;
    'PE0_RX_DP1':'(0,0,0,0,0,0,0,0,0,0,0,0,0,0,0,0,N9,0,0,0,0,0,0,0,0,0,0,0,0,0,~
0,0,0,0,0,0,0,0,0,0,0,0)';$S;IN;
    'PE0_RX_DP0':'(0,0,0,0,0,0,0,0,0,0,0,0,0,0,0,0,L11,0,0,0,0,0,0,0,0,0,0,0,0,0~
,0,0,0,0,0,0,0,0,0,0,0,0)';$S;IN;
    'PE0_TX_DN15':'(0,0,0,0,0,0,0,0,0,0,0,0,0,0,0,0,BB14,0,0,0,0,0,0,0,0,0,0,0,0~
,0,0,0,0,0,0,0,0,0,0,0,0,0)';$S;OUT;
    'PE0_TX_DN14':'(0,0,0,0,0,0,0,0,0,0,0,0,0,0,0,0,BA13,0,0,0,0,0,0,0,0,0,0,0,0~
,0,0,0,0,0,0,0,0,0,0,0,0,0)';$S;OUT;
    'PE0_TX_DN13':'(0,0,0,0,0,0,0,0,0,0,0,0,0,0,0,0,AV14,0,0,0,0,0,0,0,0,0,0,0,0~
,0,0,0,0,0,0,0,0,0,0,0,0,0)';$S;OUT;
    'PE0_TX_DN12':'(0,0,0,0,0,0,0,0,0,0,0,0,0,0,0,0,AU13,0,0,0,0,0,0,0,0,0,0,0,0~
,0,0,0,0,0,0,0,0,0,0,0,0,0)';$S;OUT;
    'PE0_TX_DN11':'(0,0,0,0,0,0,0,0,0,0,0,0,0,0,0,0,AP14,0,0,0,0,0,0,0,0,0,0,0,0~
,0,0,0,0,0,0,0,0,0,0,0,0,0)';$S;OUT;
    'PE0_TX_DN10':'(0,0,0,0,0,0,0,0,0,0,0,0,0,0,0,0,AN13,0,0,0,0,0,0,0,0,0,0,0,0~
,0,0,0,0,0,0,0,0,0,0,0,0,0)';$S;OUT;
    'PE0_TX_DN9':'(0,0,0,0,0,0,0,0,0,0,0,0,0,0,0,0,AK14,0,0,0,0,0,0,0,0,0,0,0,0,~
0,0,0,0,0,0,0,0,0,0,0,0,0)';$S;OUT;
    'PE0_TX_DN8':'(0,0,0,0,0,0,0,0,0,0,0,0,0,0,0,0,AJ13,0,0,0,0,0,0,0,0,0,0,0,0,~
0,0,0,0,0,0,0,0,0,0,0,0,0)';$S;OUT;
    'PE0_TX_DN7':'(0,0,0,0,0,0,0,0,0,0,0,0,0,0,0,0,AF14,0,0,0,0,0,0,0,0,0,0,0,0,~
0,0,0,0,0,0,0,0,0,0,0,0,0)';$S;OUT;
    'PE0_TX_DN6':'(0,0,0,0,0,0,0,0,0,0,0,0,0,0,0,0,AE13,0,0,0,0,0,0,0,0,0,0,0,0,~
0,0,0,0,0,0,0,0,0,0,0,0,0)';$S;OUT;
    'PE0_TX_DN5':'(0,0,0,0,0,0,0,0,0,0,0,0,0,0,0,0,AB14,0,0,0,0,0,0,0,0,0,0,0,0,~
0,0,0,0,0,0,0,0,0,0,0,0,0)';$S;OUT;
    'PE0_TX_DN4':'(0,0,0,0,0,0,0,0,0,0,0,0,0,0,0,0,AA13,0,0,0,0,0,0,0,0,0,0,0,0,~
0,0,0,0,0,0,0,0,0,0,0,0,0)';$S;OUT;
    'PE0_TX_DN3':'(0,0,0,0,0,0,0,0,0,0,0,0,0,0,0,0,V14,0,0,0,0,0,0,0,0,0,0,0,0,0~
,0,0,0,0,0,0,0,0,0,0,0,0)';$S;OUT;
    'PE0_TX_DN2':'(0,0,0,0,0,0,0,0,0,0,0,0,0,0,0,0,U13,0,0,0,0,0,0,0,0,0,0,0,0,0~
,0,0,0,0,0,0,0,0,0,0,0,0)';$S;OUT;
    'PE0_TX_DN1':'(0,0,0,0,0,0,0,0,0,0,0,0,0,0,0,0,P14,0,0,0,0,0,0,0,0,0,0,0,0,0~
,0,0,0,0,0,0,0,0,0,0,0,0)';$S;OUT;
    'PE0_TX_DN0':'(0,0,0,0,0,0,0,0,0,0,0,0,0,0,0,0,N13,0,0,0,0,0,0,0,0,0,0,0,0,0~
,0,0,0,0,0,0,0,0,0,0,0,0)';$S;OUT;
    'PE0_TX_DP15':'(0,0,0,0,0,0,0,0,0,0,0,0,0,0,0,0,BC15,0,0,0,0,0,0,0,0,0,0,0,0~
,0,0,0,0,0,0,0,0,0,0,0,0,0)';$S;OUT;
    'PE0_TX_DP14':'(0,0,0,0,0,0,0,0,0,0,0,0,0,0,0,0,AY14,0,0,0,0,0,0,0,0,0,0,0,0~
,0,0,0,0,0,0,0,0,0,0,0,0,0)';$S;OUT;
    'PE0_TX_DP13':'(0,0,0,0,0,0,0,0,0,0,0,0,0,0,0,0,AW15,0,0,0,0,0,0,0,0,0,0,0,0~
,0,0,0,0,0,0,0,0,0,0,0,0,0)';$S;OUT;
    'PE0_TX_DP12':'(0,0,0,0,0,0,0,0,0,0,0,0,0,0,0,0,AT14,0,0,0,0,0,0,0,0,0,0,0,0~
,0,0,0,0,0,0,0,0,0,0,0,0,0)';$S;OUT;
    'PE0_TX_DP11':'(0,0,0,0,0,0,0,0,0,0,0,0,0,0,0,0,AR15,0,0,0,0,0,0,0,0,0,0,0,0~
,0,0,0,0,0,0,0,0,0,0,0,0,0)';$S;OUT;
    'PE0_TX_DP10':'(0,0,0,0,0,0,0,0,0,0,0,0,0,0,0,0,AM14,0,0,0,0,0,0,0,0,0,0,0,0~
,0,0,0,0,0,0,0,0,0,0,0,0,0)';$S;OUT;
    'PE0_TX_DP9':'(0,0,0,0,0,0,0,0,0,0,0,0,0,0,0,0,AL15,0,0,0,0,0,0,0,0,0,0,0,0,~
0,0,0,0,0,0,0,0,0,0,0,0,0)';$S;OUT;
    'PE0_TX_DP8':'(0,0,0,0,0,0,0,0,0,0,0,0,0,0,0,0,AH14,0,0,0,0,0,0,0,0,0,0,0,0,~
0,0,0,0,0,0,0,0,0,0,0,0,0)';$S;OUT;
    'PE0_TX_DP7':'(0,0,0,0,0,0,0,0,0,0,0,0,0,0,0,0,AG15,0,0,0,0,0,0,0,0,0,0,0,0,~
0,0,0,0,0,0,0,0,0,0,0,0,0)';$S;OUT;
    'PE0_TX_DP6':'(0,0,0,0,0,0,0,0,0,0,0,0,0,0,0,0,AD14,0,0,0,0,0,0,0,0,0,0,0,0,~
0,0,0,0,0,0,0,0,0,0,0,0,0)';$S;OUT;
    'PE0_TX_DP5':'(0,0,0,0,0,0,0,0,0,0,0,0,0,0,0,0,AC15,0,0,0,0,0,0,0,0,0,0,0,0,~
0,0,0,0,0,0,0,0,0,0,0,0,0)';$S;OUT;
    'PE0_TX_DP4':'(0,0,0,0,0,0,0,0,0,0,0,0,0,0,0,0,Y14,0,0,0,0,0,0,0,0,0,0,0,0,0~
,0,0,0,0,0,0,0,0,0,0,0,0)';$S;OUT;
    'PE0_TX_DP3':'(0,0,0,0,0,0,0,0,0,0,0,0,0,0,0,0,W15,0,0,0,0,0,0,0,0,0,0,0,0,0~
,0,0,0,0,0,0,0,0,0,0,0,0)';$S;OUT;
    'PE0_TX_DP2':'(0,0,0,0,0,0,0,0,0,0,0,0,0,0,0,0,T14,0,0,0,0,0,0,0,0,0,0,0,0,0~
,0,0,0,0,0,0,0,0,0,0,0,0)';$S;OUT;
    'PE0_TX_DP1':'(0,0,0,0,0,0,0,0,0,0,0,0,0,0,0,0,R15,0,0,0,0,0,0,0,0,0,0,0,0,0~
,0,0,0,0,0,0,0,0,0,0,0,0)';$S;OUT;
    'PE0_TX_DP0':'(0,0,0,0,0,0,0,0,0,0,0,0,0,0,0,0,M14,0,0,0,0,0,0,0,0,0,0,0,0,0~
,0,0,0,0,0,0,0,0,0,0,0,0)';$S;OUT;
    'PE1_RX_DN15':'(0,0,0,0,0,0,0,0,0,0,0,0,0,0,0,0,0,BC11,0,0,0,0,0,0,0,0,0,0,0~
,0,0,0,0,0,0,0,0,0,0,0,0,0)';$S;IN;
    'PE1_RX_DN14':'(0,0,0,0,0,0,0,0,0,0,0,0,0,0,0,0,0,BF10,0,0,0,0,0,0,0,0,0,0,0~
,0,0,0,0,0,0,0,0,0,0,0,0,0)';$S;IN;
    'PE1_RX_DN13':'(0,0,0,0,0,0,0,0,0,0,0,0,0,0,0,0,0,BG11,0,0,0,0,0,0,0,0,0,0,0~
,0,0,0,0,0,0,0,0,0,0,0,0,0)';$S;IN;
    'PE1_RX_DN12':'(0,0,0,0,0,0,0,0,0,0,0,0,0,0,0,0,0,BK10,0,0,0,0,0,0,0,0,0,0,0~
,0,0,0,0,0,0,0,0,0,0,0,0,0)';$S;IN;
    'PE1_RX_DN11':'(0,0,0,0,0,0,0,0,0,0,0,0,0,0,0,0,0,BL11,0,0,0,0,0,0,0,0,0,0,0~
,0,0,0,0,0,0,0,0,0,0,0,0,0)';$S;IN;
    'PE1_RX_DN10':'(0,0,0,0,0,0,0,0,0,0,0,0,0,0,0,0,0,BP10,0,0,0,0,0,0,0,0,0,0,0~
,0,0,0,0,0,0,0,0,0,0,0,0,0)';$S;IN;
    'PE1_RX_DN9':'(0,0,0,0,0,0,0,0,0,0,0,0,0,0,0,0,0,BR11,0,0,0,0,0,0,0,0,0,0,0,~
0,0,0,0,0,0,0,0,0,0,0,0,0)';$S;IN;
    'PE1_RX_DN8':'(0,0,0,0,0,0,0,0,0,0,0,0,0,0,0,0,0,BV10,0,0,0,0,0,0,0,0,0,0,0,~
0,0,0,0,0,0,0,0,0,0,0,0,0)';$S;IN;
    'PE1_RX_DN7':'(0,0,0,0,0,0,0,0,0,0,0,0,0,0,0,0,0,BW11,0,0,0,0,0,0,0,0,0,0,0,~
0,0,0,0,0,0,0,0,0,0,0,0,0)';$S;IN;
    'PE1_RX_DN6':'(0,0,0,0,0,0,0,0,0,0,0,0,0,0,0,0,0,CB10,0,0,0,0,0,0,0,0,0,0,0,~
0,0,0,0,0,0,0,0,0,0,0,0,0)';$S;IN;
    'PE1_RX_DN5':'(0,0,0,0,0,0,0,0,0,0,0,0,0,0,0,0,0,CC11,0,0,0,0,0,0,0,0,0,0,0,~
0,0,0,0,0,0,0,0,0,0,0,0,0)';$S;IN;
    'PE1_RX_DN4':'(0,0,0,0,0,0,0,0,0,0,0,0,0,0,0,0,0,CF10,0,0,0,0,0,0,0,0,0,0,0,~
0,0,0,0,0,0,0,0,0,0,0,0,0)';$S;IN;
    'PE1_RX_DN3':'(0,0,0,0,0,0,0,0,0,0,0,0,0,0,0,0,0,CG11,0,0,0,0,0,0,0,0,0,0,0,~
0,0,0,0,0,0,0,0,0,0,0,0,0)';$S;IN;
    'PE1_RX_DN2':'(0,0,0,0,0,0,0,0,0,0,0,0,0,0,0,0,0,CK10,0,0,0,0,0,0,0,0,0,0,0,~
0,0,0,0,0,0,0,0,0,0,0,0,0)';$S;IN;
    'PE1_RX_DN1':'(0,0,0,0,0,0,0,0,0,0,0,0,0,0,0,0,0,CL11,0,0,0,0,0,0,0,0,0,0,0,~
0,0,0,0,0,0,0,0,0,0,0,0,0)';$S;IN;
    'PE1_RX_DN0':'(0,0,0,0,0,0,0,0,0,0,0,0,0,0,0,0,0,CP10,0,0,0,0,0,0,0,0,0,0,0,~
0,0,0,0,0,0,0,0,0,0,0,0,0)';$S;IN;
    'PE1_RX_DP15':'(0,0,0,0,0,0,0,0,0,0,0,0,0,0,0,0,0,BD10,0,0,0,0,0,0,0,0,0,0,0~
,0,0,0,0,0,0,0,0,0,0,0,0,0)';$S;IN;
    'PE1_RX_DP14':'(0,0,0,0,0,0,0,0,0,0,0,0,0,0,0,0,0,BE9,0,0,0,0,0,0,0,0,0,0,0,~
0,0,0,0,0,0,0,0,0,0,0,0,0)';$S;IN;
    'PE1_RX_DP13':'(0,0,0,0,0,0,0,0,0,0,0,0,0,0,0,0,0,BH10,0,0,0,0,0,0,0,0,0,0,0~
,0,0,0,0,0,0,0,0,0,0,0,0,0)';$S;IN;
    'PE1_RX_DP12':'(0,0,0,0,0,0,0,0,0,0,0,0,0,0,0,0,0,BJ9,0,0,0,0,0,0,0,0,0,0,0,~
0,0,0,0,0,0,0,0,0,0,0,0,0)';$S;IN;
    'PE1_RX_DP11':'(0,0,0,0,0,0,0,0,0,0,0,0,0,0,0,0,0,BM10,0,0,0,0,0,0,0,0,0,0,0~
,0,0,0,0,0,0,0,0,0,0,0,0,0)';$S;IN;
    'PE1_RX_DP10':'(0,0,0,0,0,0,0,0,0,0,0,0,0,0,0,0,0,BN9,0,0,0,0,0,0,0,0,0,0,0,~
0,0,0,0,0,0,0,0,0,0,0,0,0)';$S;IN;
    'PE1_RX_DP9':'(0,0,0,0,0,0,0,0,0,0,0,0,0,0,0,0,0,BT10,0,0,0,0,0,0,0,0,0,0,0,~
0,0,0,0,0,0,0,0,0,0,0,0,0)';$S;IN;
    'PE1_RX_DP8':'(0,0,0,0,0,0,0,0,0,0,0,0,0,0,0,0,0,BU9,0,0,0,0,0,0,0,0,0,0,0,0~
,0,0,0,0,0,0,0,0,0,0,0,0)';$S;IN;
    'PE1_RX_DP7':'(0,0,0,0,0,0,0,0,0,0,0,0,0,0,0,0,0,BY10,0,0,0,0,0,0,0,0,0,0,0,~
0,0,0,0,0,0,0,0,0,0,0,0,0)';$S;IN;
    'PE1_RX_DP6':'(0,0,0,0,0,0,0,0,0,0,0,0,0,0,0,0,0,CA9,0,0,0,0,0,0,0,0,0,0,0,0~
,0,0,0,0,0,0,0,0,0,0,0,0)';$S;IN;
    'PE1_RX_DP5':'(0,0,0,0,0,0,0,0,0,0,0,0,0,0,0,0,0,CD10,0,0,0,0,0,0,0,0,0,0,0,~
0,0,0,0,0,0,0,0,0,0,0,0,0)';$S;IN;
    'PE1_RX_DP4':'(0,0,0,0,0,0,0,0,0,0,0,0,0,0,0,0,0,CE9,0,0,0,0,0,0,0,0,0,0,0,0~
,0,0,0,0,0,0,0,0,0,0,0,0)';$S;IN;
    'PE1_RX_DP3':'(0,0,0,0,0,0,0,0,0,0,0,0,0,0,0,0,0,CH10,0,0,0,0,0,0,0,0,0,0,0,~
0,0,0,0,0,0,0,0,0,0,0,0,0)';$S;IN;
    'PE1_RX_DP2':'(0,0,0,0,0,0,0,0,0,0,0,0,0,0,0,0,0,CJ9,0,0,0,0,0,0,0,0,0,0,0,0~
,0,0,0,0,0,0,0,0,0,0,0,0)';$S;IN;
    'PE1_RX_DP1':'(0,0,0,0,0,0,0,0,0,0,0,0,0,0,0,0,0,CM10,0,0,0,0,0,0,0,0,0,0,0,~
0,0,0,0,0,0,0,0,0,0,0,0,0)';$S;IN;
    'PE1_RX_DP0':'(0,0,0,0,0,0,0,0,0,0,0,0,0,0,0,0,0,CN9,0,0,0,0,0,0,0,0,0,0,0,0~
,0,0,0,0,0,0,0,0,0,0,0,0)';$S;IN;
    'PE1_TX_DN15':'(0,0,0,0,0,0,0,0,0,0,0,0,0,0,0,0,0,BE13,0,0,0,0,0,0,0,0,0,0,0~
,0,0,0,0,0,0,0,0,0,0,0,0,0)';$S;OUT;
    'PE1_TX_DN14':'(0,0,0,0,0,0,0,0,0,0,0,0,0,0,0,0,0,BF14,0,0,0,0,0,0,0,0,0,0,0~
,0,0,0,0,0,0,0,0,0,0,0,0,0)';$S;OUT;
    'PE1_TX_DN13':'(0,0,0,0,0,0,0,0,0,0,0,0,0,0,0,0,0,BJ13,0,0,0,0,0,0,0,0,0,0,0~
,0,0,0,0,0,0,0,0,0,0,0,0,0)';$S;OUT;
    'PE1_TX_DN12':'(0,0,0,0,0,0,0,0,0,0,0,0,0,0,0,0,0,BK14,0,0,0,0,0,0,0,0,0,0,0~
,0,0,0,0,0,0,0,0,0,0,0,0,0)';$S;OUT;
    'PE1_TX_DN11':'(0,0,0,0,0,0,0,0,0,0,0,0,0,0,0,0,0,BN13,0,0,0,0,0,0,0,0,0,0,0~
,0,0,0,0,0,0,0,0,0,0,0,0,0)';$S;OUT;
    'PE1_TX_DN10':'(0,0,0,0,0,0,0,0,0,0,0,0,0,0,0,0,0,BP14,0,0,0,0,0,0,0,0,0,0,0~
,0,0,0,0,0,0,0,0,0,0,0,0,0)';$S;OUT;
    'PE1_TX_DN9':'(0,0,0,0,0,0,0,0,0,0,0,0,0,0,0,0,0,BU13,0,0,0,0,0,0,0,0,0,0,0,~
0,0,0,0,0,0,0,0,0,0,0,0,0)';$S;OUT;
    'PE1_TX_DN8':'(0,0,0,0,0,0,0,0,0,0,0,0,0,0,0,0,0,BV14,0,0,0,0,0,0,0,0,0,0,0,~
0,0,0,0,0,0,0,0,0,0,0,0,0)';$S;OUT;
    'PE1_TX_DN7':'(0,0,0,0,0,0,0,0,0,0,0,0,0,0,0,0,0,CA13,0,0,0,0,0,0,0,0,0,0,0,~
0,0,0,0,0,0,0,0,0,0,0,0,0)';$S;OUT;
    'PE1_TX_DN6':'(0,0,0,0,0,0,0,0,0,0,0,0,0,0,0,0,0,CB14,0,0,0,0,0,0,0,0,0,0,0,~
0,0,0,0,0,0,0,0,0,0,0,0,0)';$S;OUT;
    'PE1_TX_DN5':'(0,0,0,0,0,0,0,0,0,0,0,0,0,0,0,0,0,CE13,0,0,0,0,0,0,0,0,0,0,0,~
0,0,0,0,0,0,0,0,0,0,0,0,0)';$S;OUT;
    'PE1_TX_DN4':'(0,0,0,0,0,0,0,0,0,0,0,0,0,0,0,0,0,CF14,0,0,0,0,0,0,0,0,0,0,0,~
0,0,0,0,0,0,0,0,0,0,0,0,0)';$S;OUT;
    'PE1_TX_DN3':'(0,0,0,0,0,0,0,0,0,0,0,0,0,0,0,0,0,CJ13,0,0,0,0,0,0,0,0,0,0,0,~
0,0,0,0,0,0,0,0,0,0,0,0,0)';$S;OUT;
    'PE1_TX_DN2':'(0,0,0,0,0,0,0,0,0,0,0,0,0,0,0,0,0,CK14,0,0,0,0,0,0,0,0,0,0,0,~
0,0,0,0,0,0,0,0,0,0,0,0,0)';$S;OUT;
    'PE1_TX_DN1':'(0,0,0,0,0,0,0,0,0,0,0,0,0,0,0,0,0,CN13,0,0,0,0,0,0,0,0,0,0,0,~
0,0,0,0,0,0,0,0,0,0,0,0,0)';$S;OUT;
    'PE1_TX_DN0':'(0,0,0,0,0,0,0,0,0,0,0,0,0,0,0,0,0,CP14,0,0,0,0,0,0,0,0,0,0,0,~
0,0,0,0,0,0,0,0,0,0,0,0,0)';$S;OUT;
    'PE1_TX_DP15':'(0,0,0,0,0,0,0,0,0,0,0,0,0,0,0,0,0,BD14,0,0,0,0,0,0,0,0,0,0,0~
,0,0,0,0,0,0,0,0,0,0,0,0,0)';$S;OUT;
    'PE1_TX_DP14':'(0,0,0,0,0,0,0,0,0,0,0,0,0,0,0,0,0,BG15,0,0,0,0,0,0,0,0,0,0,0~
,0,0,0,0,0,0,0,0,0,0,0,0,0)';$S;OUT;
    'PE1_TX_DP13':'(0,0,0,0,0,0,0,0,0,0,0,0,0,0,0,0,0,BH14,0,0,0,0,0,0,0,0,0,0,0~
,0,0,0,0,0,0,0,0,0,0,0,0,0)';$S;OUT;
    'PE1_TX_DP12':'(0,0,0,0,0,0,0,0,0,0,0,0,0,0,0,0,0,BL15,0,0,0,0,0,0,0,0,0,0,0~
,0,0,0,0,0,0,0,0,0,0,0,0,0)';$S;OUT;
    'PE1_TX_DP11':'(0,0,0,0,0,0,0,0,0,0,0,0,0,0,0,0,0,BM14,0,0,0,0,0,0,0,0,0,0,0~
,0,0,0,0,0,0,0,0,0,0,0,0,0)';$S;OUT;
    'PE1_TX_DP10':'(0,0,0,0,0,0,0,0,0,0,0,0,0,0,0,0,0,BR15,0,0,0,0,0,0,0,0,0,0,0~
,0,0,0,0,0,0,0,0,0,0,0,0,0)';$S;OUT;
    'PE1_TX_DP9':'(0,0,0,0,0,0,0,0,0,0,0,0,0,0,0,0,0,BT14,0,0,0,0,0,0,0,0,0,0,0,~
0,0,0,0,0,0,0,0,0,0,0,0,0)';$S;OUT;
    'PE1_TX_DP8':'(0,0,0,0,0,0,0,0,0,0,0,0,0,0,0,0,0,BW15,0,0,0,0,0,0,0,0,0,0,0,~
0,0,0,0,0,0,0,0,0,0,0,0,0)';$S;OUT;
    'PE1_TX_DP7':'(0,0,0,0,0,0,0,0,0,0,0,0,0,0,0,0,0,BY14,0,0,0,0,0,0,0,0,0,0,0,~
0,0,0,0,0,0,0,0,0,0,0,0,0)';$S;OUT;
    'PE1_TX_DP6':'(0,0,0,0,0,0,0,0,0,0,0,0,0,0,0,0,0,CC15,0,0,0,0,0,0,0,0,0,0,0,~
0,0,0,0,0,0,0,0,0,0,0,0,0)';$S;OUT;
    'PE1_TX_DP5':'(0,0,0,0,0,0,0,0,0,0,0,0,0,0,0,0,0,CD14,0,0,0,0,0,0,0,0,0,0,0,~
0,0,0,0,0,0,0,0,0,0,0,0,0)';$S;OUT;
    'PE1_TX_DP4':'(0,0,0,0,0,0,0,0,0,0,0,0,0,0,0,0,0,CG15,0,0,0,0,0,0,0,0,0,0,0,~
0,0,0,0,0,0,0,0,0,0,0,0,0)';$S;OUT;
    'PE1_TX_DP3':'(0,0,0,0,0,0,0,0,0,0,0,0,0,0,0,0,0,CH14,0,0,0,0,0,0,0,0,0,0,0,~
0,0,0,0,0,0,0,0,0,0,0,0,0)';$S;OUT;
    'PE1_TX_DP2':'(0,0,0,0,0,0,0,0,0,0,0,0,0,0,0,0,0,CL15,0,0,0,0,0,0,0,0,0,0,0,~
0,0,0,0,0,0,0,0,0,0,0,0,0)';$S;OUT;
    'PE1_TX_DP1':'(0,0,0,0,0,0,0,0,0,0,0,0,0,0,0,0,0,CM14,0,0,0,0,0,0,0,0,0,0,0,~
0,0,0,0,0,0,0,0,0,0,0,0,0)';$S;OUT;
    'PE1_TX_DP0':'(0,0,0,0,0,0,0,0,0,0,0,0,0,0,0,0,0,CR15,0,0,0,0,0,0,0,0,0,0,0,~
0,0,0,0,0,0,0,0,0,0,0,0,0)';$S;OUT;
    'PE2_RX_DN15':'(0,0,0,0,0,0,0,0,0,0,0,0,0,0,0,0,0,0,EH10,0,0,0,0,0,0,0,0,0,0~
,0,0,0,0,0,0,0,0,0,0,0,0,0)';$S;IN;
    'PE2_RX_DN14':'(0,0,0,0,0,0,0,0,0,0,0,0,0,0,0,0,0,0,EE9,0,0,0,0,0,0,0,0,0,0,~
0,0,0,0,0,0,0,0,0,0,0,0,0)';$S;IN;
    'PE2_RX_DN13':'(0,0,0,0,0,0,0,0,0,0,0,0,0,0,0,0,0,0,ED10,0,0,0,0,0,0,0,0,0,0~
,0,0,0,0,0,0,0,0,0,0,0,0,0)';$S;IN;
    'PE2_RX_DN12':'(0,0,0,0,0,0,0,0,0,0,0,0,0,0,0,0,0,0,EA9,0,0,0,0,0,0,0,0,0,0,~
0,0,0,0,0,0,0,0,0,0,0,0,0)';$S;IN;
    'PE2_RX_DN11':'(0,0,0,0,0,0,0,0,0,0,0,0,0,0,0,0,0,0,DY10,0,0,0,0,0,0,0,0,0,0~
,0,0,0,0,0,0,0,0,0,0,0,0,0)';$S;IN;
    'PE2_RX_DN10':'(0,0,0,0,0,0,0,0,0,0,0,0,0,0,0,0,0,0,DU9,0,0,0,0,0,0,0,0,0,0,~
0,0,0,0,0,0,0,0,0,0,0,0,0)';$S;IN;
    'PE2_RX_DN9':'(0,0,0,0,0,0,0,0,0,0,0,0,0,0,0,0,0,0,DT10,0,0,0,0,0,0,0,0,0,0,~
0,0,0,0,0,0,0,0,0,0,0,0,0)';$S;IN;
    'PE2_RX_DN8':'(0,0,0,0,0,0,0,0,0,0,0,0,0,0,0,0,0,0,DN9,0,0,0,0,0,0,0,0,0,0,0~
,0,0,0,0,0,0,0,0,0,0,0,0)';$S;IN;
    'PE2_RX_DN7':'(0,0,0,0,0,0,0,0,0,0,0,0,0,0,0,0,0,0,DM10,0,0,0,0,0,0,0,0,0,0,~
0,0,0,0,0,0,0,0,0,0,0,0,0)';$S;IN;
    'PE2_RX_DN6':'(0,0,0,0,0,0,0,0,0,0,0,0,0,0,0,0,0,0,DJ9,0,0,0,0,0,0,0,0,0,0,0~
,0,0,0,0,0,0,0,0,0,0,0,0)';$S;IN;
    'PE2_RX_DN5':'(0,0,0,0,0,0,0,0,0,0,0,0,0,0,0,0,0,0,DH10,0,0,0,0,0,0,0,0,0,0,~
0,0,0,0,0,0,0,0,0,0,0,0,0)';$S;IN;
    'PE2_RX_DN4':'(0,0,0,0,0,0,0,0,0,0,0,0,0,0,0,0,0,0,DE9,0,0,0,0,0,0,0,0,0,0,0~
,0,0,0,0,0,0,0,0,0,0,0,0)';$S;IN;
    'PE2_RX_DN3':'(0,0,0,0,0,0,0,0,0,0,0,0,0,0,0,0,0,0,DD10,0,0,0,0,0,0,0,0,0,0,~
0,0,0,0,0,0,0,0,0,0,0,0,0)';$S;IN;
    'PE2_RX_DN2':'(0,0,0,0,0,0,0,0,0,0,0,0,0,0,0,0,0,0,DA9,0,0,0,0,0,0,0,0,0,0,0~
,0,0,0,0,0,0,0,0,0,0,0,0)';$S;IN;
    'PE2_RX_DN1':'(0,0,0,0,0,0,0,0,0,0,0,0,0,0,0,0,0,0,CY10,0,0,0,0,0,0,0,0,0,0,~
0,0,0,0,0,0,0,0,0,0,0,0,0)';$S;IN;
    'PE2_RX_DN0':'(0,0,0,0,0,0,0,0,0,0,0,0,0,0,0,0,0,0,CU9,0,0,0,0,0,0,0,0,0,0,0~
,0,0,0,0,0,0,0,0,0,0,0,0)';$S;IN;
    'PE2_RX_DP15':'(0,0,0,0,0,0,0,0,0,0,0,0,0,0,0,0,0,0,EG11,0,0,0,0,0,0,0,0,0,0~
,0,0,0,0,0,0,0,0,0,0,0,0,0)';$S;IN;
    'PE2_RX_DP14':'(0,0,0,0,0,0,0,0,0,0,0,0,0,0,0,0,0,0,EF10,0,0,0,0,0,0,0,0,0,0~
,0,0,0,0,0,0,0,0,0,0,0,0,0)';$S;IN;
    'PE2_RX_DP13':'(0,0,0,0,0,0,0,0,0,0,0,0,0,0,0,0,0,0,EC11,0,0,0,0,0,0,0,0,0,0~
,0,0,0,0,0,0,0,0,0,0,0,0,0)';$S;IN;
    'PE2_RX_DP12':'(0,0,0,0,0,0,0,0,0,0,0,0,0,0,0,0,0,0,EB10,0,0,0,0,0,0,0,0,0,0~
,0,0,0,0,0,0,0,0,0,0,0,0,0)';$S;IN;
    'PE2_RX_DP11':'(0,0,0,0,0,0,0,0,0,0,0,0,0,0,0,0,0,0,DW11,0,0,0,0,0,0,0,0,0,0~
,0,0,0,0,0,0,0,0,0,0,0,0,0)';$S;IN;
    'PE2_RX_DP10':'(0,0,0,0,0,0,0,0,0,0,0,0,0,0,0,0,0,0,DV10,0,0,0,0,0,0,0,0,0,0~
,0,0,0,0,0,0,0,0,0,0,0,0,0)';$S;IN;
    'PE2_RX_DP9':'(0,0,0,0,0,0,0,0,0,0,0,0,0,0,0,0,0,0,DR11,0,0,0,0,0,0,0,0,0,0,~
0,0,0,0,0,0,0,0,0,0,0,0,0)';$S;IN;
    'PE2_RX_DP8':'(0,0,0,0,0,0,0,0,0,0,0,0,0,0,0,0,0,0,DP10,0,0,0,0,0,0,0,0,0,0,~
0,0,0,0,0,0,0,0,0,0,0,0,0)';$S;IN;
    'PE2_RX_DP7':'(0,0,0,0,0,0,0,0,0,0,0,0,0,0,0,0,0,0,DL11,0,0,0,0,0,0,0,0,0,0,~
0,0,0,0,0,0,0,0,0,0,0,0,0)';$S;IN;
    'PE2_RX_DP6':'(0,0,0,0,0,0,0,0,0,0,0,0,0,0,0,0,0,0,DK10,0,0,0,0,0,0,0,0,0,0,~
0,0,0,0,0,0,0,0,0,0,0,0,0)';$S;IN;
    'PE2_RX_DP5':'(0,0,0,0,0,0,0,0,0,0,0,0,0,0,0,0,0,0,DG11,0,0,0,0,0,0,0,0,0,0,~
0,0,0,0,0,0,0,0,0,0,0,0,0)';$S;IN;
    'PE2_RX_DP4':'(0,0,0,0,0,0,0,0,0,0,0,0,0,0,0,0,0,0,DF10,0,0,0,0,0,0,0,0,0,0,~
0,0,0,0,0,0,0,0,0,0,0,0,0)';$S;IN;
    'PE2_RX_DP3':'(0,0,0,0,0,0,0,0,0,0,0,0,0,0,0,0,0,0,DC11,0,0,0,0,0,0,0,0,0,0,~
0,0,0,0,0,0,0,0,0,0,0,0,0)';$S;IN;
    'PE2_RX_DP2':'(0,0,0,0,0,0,0,0,0,0,0,0,0,0,0,0,0,0,DB10,0,0,0,0,0,0,0,0,0,0,~
0,0,0,0,0,0,0,0,0,0,0,0,0)';$S;IN;
    'PE2_RX_DP1':'(0,0,0,0,0,0,0,0,0,0,0,0,0,0,0,0,0,0,CW11,0,0,0,0,0,0,0,0,0,0,~
0,0,0,0,0,0,0,0,0,0,0,0,0)';$S;IN;
    'PE2_RX_DP0':'(0,0,0,0,0,0,0,0,0,0,0,0,0,0,0,0,0,0,CV10,0,0,0,0,0,0,0,0,0,0,~
0,0,0,0,0,0,0,0,0,0,0,0,0)';$S;IN;
    'PE2_TX_DN15':'(0,0,0,0,0,0,0,0,0,0,0,0,0,0,0,0,0,0,EF14,0,0,0,0,0,0,0,0,0,0~
,0,0,0,0,0,0,0,0,0,0,0,0,0)';$S;OUT;
    'PE2_TX_DN14':'(0,0,0,0,0,0,0,0,0,0,0,0,0,0,0,0,0,0,EE13,0,0,0,0,0,0,0,0,0,0~
,0,0,0,0,0,0,0,0,0,0,0,0,0)';$S;OUT;
    'PE2_TX_DN13':'(0,0,0,0,0,0,0,0,0,0,0,0,0,0,0,0,0,0,EB14,0,0,0,0,0,0,0,0,0,0~
,0,0,0,0,0,0,0,0,0,0,0,0,0)';$S;OUT;
    'PE2_TX_DN12':'(0,0,0,0,0,0,0,0,0,0,0,0,0,0,0,0,0,0,EA13,0,0,0,0,0,0,0,0,0,0~
,0,0,0,0,0,0,0,0,0,0,0,0,0)';$S;OUT;
    'PE2_TX_DN11':'(0,0,0,0,0,0,0,0,0,0,0,0,0,0,0,0,0,0,DV14,0,0,0,0,0,0,0,0,0,0~
,0,0,0,0,0,0,0,0,0,0,0,0,0)';$S;OUT;
    'PE2_TX_DN10':'(0,0,0,0,0,0,0,0,0,0,0,0,0,0,0,0,0,0,DU13,0,0,0,0,0,0,0,0,0,0~
,0,0,0,0,0,0,0,0,0,0,0,0,0)';$S;OUT;
    'PE2_TX_DN9':'(0,0,0,0,0,0,0,0,0,0,0,0,0,0,0,0,0,0,DP14,0,0,0,0,0,0,0,0,0,0,~
0,0,0,0,0,0,0,0,0,0,0,0,0)';$S;OUT;
    'PE2_TX_DN8':'(0,0,0,0,0,0,0,0,0,0,0,0,0,0,0,0,0,0,DN13,0,0,0,0,0,0,0,0,0,0,~
0,0,0,0,0,0,0,0,0,0,0,0,0)';$S;OUT;
    'PE2_TX_DN7':'(0,0,0,0,0,0,0,0,0,0,0,0,0,0,0,0,0,0,DK14,0,0,0,0,0,0,0,0,0,0,~
0,0,0,0,0,0,0,0,0,0,0,0,0)';$S;OUT;
    'PE2_TX_DN6':'(0,0,0,0,0,0,0,0,0,0,0,0,0,0,0,0,0,0,DJ13,0,0,0,0,0,0,0,0,0,0,~
0,0,0,0,0,0,0,0,0,0,0,0,0)';$S;OUT;
    'PE2_TX_DN5':'(0,0,0,0,0,0,0,0,0,0,0,0,0,0,0,0,0,0,DF14,0,0,0,0,0,0,0,0,0,0,~
0,0,0,0,0,0,0,0,0,0,0,0,0)';$S;OUT;
    'PE2_TX_DN4':'(0,0,0,0,0,0,0,0,0,0,0,0,0,0,0,0,0,0,DE13,0,0,0,0,0,0,0,0,0,0,~
0,0,0,0,0,0,0,0,0,0,0,0,0)';$S;OUT;
    'PE2_TX_DN3':'(0,0,0,0,0,0,0,0,0,0,0,0,0,0,0,0,0,0,DB14,0,0,0,0,0,0,0,0,0,0,~
0,0,0,0,0,0,0,0,0,0,0,0,0)';$S;OUT;
    'PE2_TX_DN2':'(0,0,0,0,0,0,0,0,0,0,0,0,0,0,0,0,0,0,DA13,0,0,0,0,0,0,0,0,0,0,~
0,0,0,0,0,0,0,0,0,0,0,0,0)';$S;OUT;
    'PE2_TX_DN1':'(0,0,0,0,0,0,0,0,0,0,0,0,0,0,0,0,0,0,CV14,0,0,0,0,0,0,0,0,0,0,~
0,0,0,0,0,0,0,0,0,0,0,0,0)';$S;OUT;
    'PE2_TX_DN0':'(0,0,0,0,0,0,0,0,0,0,0,0,0,0,0,0,0,0,CU13,0,0,0,0,0,0,0,0,0,0,~
0,0,0,0,0,0,0,0,0,0,0,0,0)';$S;OUT;
    'PE2_TX_DP15':'(0,0,0,0,0,0,0,0,0,0,0,0,0,0,0,0,0,0,EG15,0,0,0,0,0,0,0,0,0,0~
,0,0,0,0,0,0,0,0,0,0,0,0,0)';$S;OUT;
    'PE2_TX_DP14':'(0,0,0,0,0,0,0,0,0,0,0,0,0,0,0,0,0,0,ED14,0,0,0,0,0,0,0,0,0,0~
,0,0,0,0,0,0,0,0,0,0,0,0,0)';$S;OUT;
    'PE2_TX_DP13':'(0,0,0,0,0,0,0,0,0,0,0,0,0,0,0,0,0,0,EC15,0,0,0,0,0,0,0,0,0,0~
,0,0,0,0,0,0,0,0,0,0,0,0,0)';$S;OUT;
    'PE2_TX_DP12':'(0,0,0,0,0,0,0,0,0,0,0,0,0,0,0,0,0,0,DY14,0,0,0,0,0,0,0,0,0,0~
,0,0,0,0,0,0,0,0,0,0,0,0,0)';$S;OUT;
    'PE2_TX_DP11':'(0,0,0,0,0,0,0,0,0,0,0,0,0,0,0,0,0,0,DW15,0,0,0,0,0,0,0,0,0,0~
,0,0,0,0,0,0,0,0,0,0,0,0,0)';$S;OUT;
    'PE2_TX_DP10':'(0,0,0,0,0,0,0,0,0,0,0,0,0,0,0,0,0,0,DT14,0,0,0,0,0,0,0,0,0,0~
,0,0,0,0,0,0,0,0,0,0,0,0,0)';$S;OUT;
    'PE2_TX_DP9':'(0,0,0,0,0,0,0,0,0,0,0,0,0,0,0,0,0,0,DR15,0,0,0,0,0,0,0,0,0,0,~
0,0,0,0,0,0,0,0,0,0,0,0,0)';$S;OUT;
    'PE2_TX_DP8':'(0,0,0,0,0,0,0,0,0,0,0,0,0,0,0,0,0,0,DM14,0,0,0,0,0,0,0,0,0,0,~
0,0,0,0,0,0,0,0,0,0,0,0,0)';$S;OUT;
    'PE2_TX_DP7':'(0,0,0,0,0,0,0,0,0,0,0,0,0,0,0,0,0,0,DL15,0,0,0,0,0,0,0,0,0,0,~
0,0,0,0,0,0,0,0,0,0,0,0,0)';$S;OUT;
    'PE2_TX_DP6':'(0,0,0,0,0,0,0,0,0,0,0,0,0,0,0,0,0,0,DH14,0,0,0,0,0,0,0,0,0,0,~
0,0,0,0,0,0,0,0,0,0,0,0,0)';$S;OUT;
    'PE2_TX_DP5':'(0,0,0,0,0,0,0,0,0,0,0,0,0,0,0,0,0,0,DG15,0,0,0,0,0,0,0,0,0,0,~
0,0,0,0,0,0,0,0,0,0,0,0,0)';$S;OUT;
    'PE2_TX_DP4':'(0,0,0,0,0,0,0,0,0,0,0,0,0,0,0,0,0,0,DD14,0,0,0,0,0,0,0,0,0,0,~
0,0,0,0,0,0,0,0,0,0,0,0,0)';$S;OUT;
    'PE2_TX_DP3':'(0,0,0,0,0,0,0,0,0,0,0,0,0,0,0,0,0,0,DC15,0,0,0,0,0,0,0,0,0,0,~
0,0,0,0,0,0,0,0,0,0,0,0,0)';$S;OUT;
    'PE2_TX_DP2':'(0,0,0,0,0,0,0,0,0,0,0,0,0,0,0,0,0,0,CY14,0,0,0,0,0,0,0,0,0,0,~
0,0,0,0,0,0,0,0,0,0,0,0,0)';$S;OUT;
    'PE2_TX_DP1':'(0,0,0,0,0,0,0,0,0,0,0,0,0,0,0,0,0,0,CW15,0,0,0,0,0,0,0,0,0,0,~
0,0,0,0,0,0,0,0,0,0,0,0,0)';$S;OUT;
    'PE2_TX_DP0':'(0,0,0,0,0,0,0,0,0,0,0,0,0,0,0,0,0,0,CT14,0,0,0,0,0,0,0,0,0,0,~
0,0,0,0,0,0,0,0,0,0,0,0,0)';$S;OUT;
    'PE3_RX_DN15':'(0,0,0,0,0,0,0,0,0,0,0,0,0,0,0,0,0,0,0,CU90,0,0,0,0,0,0,0,0,0~
,0,0,0,0,0,0,0,0,0,0,0,0,0)';$S;IN;
    'PE3_RX_DN14':'(0,0,0,0,0,0,0,0,0,0,0,0,0,0,0,0,0,0,0,CV89,0,0,0,0,0,0,0,0,0~
,0,0,0,0,0,0,0,0,0,0,0,0,0)';$S;IN;
    'PE3_RX_DN13':'(0,0,0,0,0,0,0,0,0,0,0,0,0,0,0,0,0,0,0,DA90,0,0,0,0,0,0,0,0,0~
,0,0,0,0,0,0,0,0,0,0,0,0,0)';$S;IN;
    'PE3_RX_DN12':'(0,0,0,0,0,0,0,0,0,0,0,0,0,0,0,0,0,0,0,DB89,0,0,0,0,0,0,0,0,0~
,0,0,0,0,0,0,0,0,0,0,0,0,0)';$S;IN;
    'PE3_RX_DN11':'(0,0,0,0,0,0,0,0,0,0,0,0,0,0,0,0,0,0,0,DD91,0,0,0,0,0,0,0,0,0~
,0,0,0,0,0,0,0,0,0,0,0,0,0)';$S;IN;
    'PE3_RX_DN10':'(0,0,0,0,0,0,0,0,0,0,0,0,0,0,0,0,0,0,0,DG90,0,0,0,0,0,0,0,0,0~
,0,0,0,0,0,0,0,0,0,0,0,0,0)';$S;IN;
    'PE3_RX_DN9':'(0,0,0,0,0,0,0,0,0,0,0,0,0,0,0,0,0,0,0,DH91,0,0,0,0,0,0,0,0,0,~
0,0,0,0,0,0,0,0,0,0,0,0,0)';$S;IN;
    'PE3_RX_DN8':'(0,0,0,0,0,0,0,0,0,0,0,0,0,0,0,0,0,0,0,DL90,0,0,0,0,0,0,0,0,0,~
0,0,0,0,0,0,0,0,0,0,0,0,0)';$S;IN;
    'PE3_RX_DN7':'(0,0,0,0,0,0,0,0,0,0,0,0,0,0,0,0,0,0,0,DN90,0,0,0,0,0,0,0,0,0,~
0,0,0,0,0,0,0,0,0,0,0,0,0)';$S;IN;
    'PE3_RX_DN6':'(0,0,0,0,0,0,0,0,0,0,0,0,0,0,0,0,0,0,0,DP89,0,0,0,0,0,0,0,0,0,~
0,0,0,0,0,0,0,0,0,0,0,0,0)';$S;IN;
    'PE3_RX_DN5':'(0,0,0,0,0,0,0,0,0,0,0,0,0,0,0,0,0,0,0,DU90,0,0,0,0,0,0,0,0,0,~
0,0,0,0,0,0,0,0,0,0,0,0,0)';$S;IN;
    'PE3_RX_DN4':'(0,0,0,0,0,0,0,0,0,0,0,0,0,0,0,0,0,0,0,DV89,0,0,0,0,0,0,0,0,0,~
0,0,0,0,0,0,0,0,0,0,0,0,0)';$S;IN;
    'PE3_RX_DN3':'(0,0,0,0,0,0,0,0,0,0,0,0,0,0,0,0,0,0,0,DY91,0,0,0,0,0,0,0,0,0,~
0,0,0,0,0,0,0,0,0,0,0,0,0)';$S;IN;
    'PE3_RX_DN2':'(0,0,0,0,0,0,0,0,0,0,0,0,0,0,0,0,0,0,0,EC90,0,0,0,0,0,0,0,0,0,~
0,0,0,0,0,0,0,0,0,0,0,0,0)';$S;IN;
    'PE3_RX_DN1':'(0,0,0,0,0,0,0,0,0,0,0,0,0,0,0,0,0,0,0,ED91,0,0,0,0,0,0,0,0,0,~
0,0,0,0,0,0,0,0,0,0,0,0,0)';$S;IN;
    'PE3_RX_DN0':'(0,0,0,0,0,0,0,0,0,0,0,0,0,0,0,0,0,0,0,EH89,0,0,0,0,0,0,0,0,0,~
0,0,0,0,0,0,0,0,0,0,0,0,0)';$S;IN;
    'PE3_RX_DP15':'(0,0,0,0,0,0,0,0,0,0,0,0,0,0,0,0,0,0,0,CT91,0,0,0,0,0,0,0,0,0~
,0,0,0,0,0,0,0,0,0,0,0,0,0)';$S;IN;
    'PE3_RX_DP14':'(0,0,0,0,0,0,0,0,0,0,0,0,0,0,0,0,0,0,0,CW90,0,0,0,0,0,0,0,0,0~
,0,0,0,0,0,0,0,0,0,0,0,0,0)';$S;IN;
    'PE3_RX_DP13':'(0,0,0,0,0,0,0,0,0,0,0,0,0,0,0,0,0,0,0,CY91,0,0,0,0,0,0,0,0,0~
,0,0,0,0,0,0,0,0,0,0,0,0,0)';$S;IN;
    'PE3_RX_DP12':'(0,0,0,0,0,0,0,0,0,0,0,0,0,0,0,0,0,0,0,DC90,0,0,0,0,0,0,0,0,0~
,0,0,0,0,0,0,0,0,0,0,0,0,0)';$S;IN;
    'PE3_RX_DP11':'(0,0,0,0,0,0,0,0,0,0,0,0,0,0,0,0,0,0,0,DE90,0,0,0,0,0,0,0,0,0~
,0,0,0,0,0,0,0,0,0,0,0,0,0)';$S;IN;
    'PE3_RX_DP10':'(0,0,0,0,0,0,0,0,0,0,0,0,0,0,0,0,0,0,0,DF89,0,0,0,0,0,0,0,0,0~
,0,0,0,0,0,0,0,0,0,0,0,0,0)';$S;IN;
    'PE3_RX_DP9':'(0,0,0,0,0,0,0,0,0,0,0,0,0,0,0,0,0,0,0,DJ90,0,0,0,0,0,0,0,0,0,~
0,0,0,0,0,0,0,0,0,0,0,0,0)';$S;IN;
    'PE3_RX_DP8':'(0,0,0,0,0,0,0,0,0,0,0,0,0,0,0,0,0,0,0,DK89,0,0,0,0,0,0,0,0,0,~
0,0,0,0,0,0,0,0,0,0,0,0,0)';$S;IN;
    'PE3_RX_DP7':'(0,0,0,0,0,0,0,0,0,0,0,0,0,0,0,0,0,0,0,DM91,0,0,0,0,0,0,0,0,0,~
0,0,0,0,0,0,0,0,0,0,0,0,0)';$S;IN;
    'PE3_RX_DP6':'(0,0,0,0,0,0,0,0,0,0,0,0,0,0,0,0,0,0,0,DR90,0,0,0,0,0,0,0,0,0,~
0,0,0,0,0,0,0,0,0,0,0,0,0)';$S;IN;
    'PE3_RX_DP5':'(0,0,0,0,0,0,0,0,0,0,0,0,0,0,0,0,0,0,0,DT91,0,0,0,0,0,0,0,0,0,~
0,0,0,0,0,0,0,0,0,0,0,0,0)';$S;IN;
    'PE3_RX_DP4':'(0,0,0,0,0,0,0,0,0,0,0,0,0,0,0,0,0,0,0,DW90,0,0,0,0,0,0,0,0,0,~
0,0,0,0,0,0,0,0,0,0,0,0,0)';$S;IN;
    'PE3_RX_DP3':'(0,0,0,0,0,0,0,0,0,0,0,0,0,0,0,0,0,0,0,EA90,0,0,0,0,0,0,0,0,0,~
0,0,0,0,0,0,0,0,0,0,0,0,0)';$S;IN;
    'PE3_RX_DP2':'(0,0,0,0,0,0,0,0,0,0,0,0,0,0,0,0,0,0,0,EB89,0,0,0,0,0,0,0,0,0,~
0,0,0,0,0,0,0,0,0,0,0,0,0)';$S;IN;
    'PE3_RX_DP1':'(0,0,0,0,0,0,0,0,0,0,0,0,0,0,0,0,0,0,0,EE90,0,0,0,0,0,0,0,0,0,~
0,0,0,0,0,0,0,0,0,0,0,0,0)';$S;IN;
    'PE3_RX_DP0':'(0,0,0,0,0,0,0,0,0,0,0,0,0,0,0,0,0,0,0,EJ90,0,0,0,0,0,0,0,0,0,~
0,0,0,0,0,0,0,0,0,0,0,0,0)';$S;IN;
    'PE3_TX_DN15':'(0,0,0,0,0,0,0,0,0,0,0,0,0,0,0,0,0,0,0,CP85,0,0,0,0,0,0,0,0,0~
,0,0,0,0,0,0,0,0,0,0,0,0,0)';$S;OUT;
    'PE3_TX_DN14':'(0,0,0,0,0,0,0,0,0,0,0,0,0,0,0,0,0,0,0,CT87,0,0,0,0,0,0,0,0,0~
,0,0,0,0,0,0,0,0,0,0,0,0,0)';$S;OUT;
    'PE3_TX_DN13':'(0,0,0,0,0,0,0,0,0,0,0,0,0,0,0,0,0,0,0,CV85,0,0,0,0,0,0,0,0,0~
,0,0,0,0,0,0,0,0,0,0,0,0,0)';$S;OUT;
    'PE3_TX_DN12':'(0,0,0,0,0,0,0,0,0,0,0,0,0,0,0,0,0,0,0,CY87,0,0,0,0,0,0,0,0,0~
,0,0,0,0,0,0,0,0,0,0,0,0,0)';$S;OUT;
    'PE3_TX_DN11':'(0,0,0,0,0,0,0,0,0,0,0,0,0,0,0,0,0,0,0,DB85,0,0,0,0,0,0,0,0,0~
,0,0,0,0,0,0,0,0,0,0,0,0,0)';$S;OUT;
    'PE3_TX_DN10':'(0,0,0,0,0,0,0,0,0,0,0,0,0,0,0,0,0,0,0,DD87,0,0,0,0,0,0,0,0,0~
,0,0,0,0,0,0,0,0,0,0,0,0,0)';$S;OUT;
    'PE3_TX_DN9':'(0,0,0,0,0,0,0,0,0,0,0,0,0,0,0,0,0,0,0,DF85,0,0,0,0,0,0,0,0,0,~
0,0,0,0,0,0,0,0,0,0,0,0,0)';$S;OUT;
    'PE3_TX_DN8':'(0,0,0,0,0,0,0,0,0,0,0,0,0,0,0,0,0,0,0,DH87,0,0,0,0,0,0,0,0,0,~
0,0,0,0,0,0,0,0,0,0,0,0,0)';$S;OUT;
    'PE3_TX_DN7':'(0,0,0,0,0,0,0,0,0,0,0,0,0,0,0,0,0,0,0,DK85,0,0,0,0,0,0,0,0,0,~
0,0,0,0,0,0,0,0,0,0,0,0,0)';$S;OUT;
    'PE3_TX_DN6':'(0,0,0,0,0,0,0,0,0,0,0,0,0,0,0,0,0,0,0,DM87,0,0,0,0,0,0,0,0,0,~
0,0,0,0,0,0,0,0,0,0,0,0,0)';$S;OUT;
    'PE3_TX_DN5':'(0,0,0,0,0,0,0,0,0,0,0,0,0,0,0,0,0,0,0,DP85,0,0,0,0,0,0,0,0,0,~
0,0,0,0,0,0,0,0,0,0,0,0,0)';$S;OUT;
    'PE3_TX_DN4':'(0,0,0,0,0,0,0,0,0,0,0,0,0,0,0,0,0,0,0,DT87,0,0,0,0,0,0,0,0,0,~
0,0,0,0,0,0,0,0,0,0,0,0,0)';$S;OUT;
    'PE3_TX_DN3':'(0,0,0,0,0,0,0,0,0,0,0,0,0,0,0,0,0,0,0,DV85,0,0,0,0,0,0,0,0,0,~
0,0,0,0,0,0,0,0,0,0,0,0,0)';$S;OUT;
    'PE3_TX_DN2':'(0,0,0,0,0,0,0,0,0,0,0,0,0,0,0,0,0,0,0,DY87,0,0,0,0,0,0,0,0,0,~
0,0,0,0,0,0,0,0,0,0,0,0,0)';$S;OUT;
    'PE3_TX_DN1':'(0,0,0,0,0,0,0,0,0,0,0,0,0,0,0,0,0,0,0,EB85,0,0,0,0,0,0,0,0,0,~
0,0,0,0,0,0,0,0,0,0,0,0,0)';$S;OUT;
    'PE3_TX_DN0':'(0,0,0,0,0,0,0,0,0,0,0,0,0,0,0,0,0,0,0,EE86,0,0,0,0,0,0,0,0,0,~
0,0,0,0,0,0,0,0,0,0,0,0,0)';$S;OUT;
    'PE3_TX_DP15':'(0,0,0,0,0,0,0,0,0,0,0,0,0,0,0,0,0,0,0,CR86,0,0,0,0,0,0,0,0,0~
,0,0,0,0,0,0,0,0,0,0,0,0,0)';$S;OUT;
    'PE3_TX_DP14':'(0,0,0,0,0,0,0,0,0,0,0,0,0,0,0,0,0,0,0,CU86,0,0,0,0,0,0,0,0,0~
,0,0,0,0,0,0,0,0,0,0,0,0,0)';$S;OUT;
    'PE3_TX_DP13':'(0,0,0,0,0,0,0,0,0,0,0,0,0,0,0,0,0,0,0,CW86,0,0,0,0,0,0,0,0,0~
,0,0,0,0,0,0,0,0,0,0,0,0,0)';$S;OUT;
    'PE3_TX_DP12':'(0,0,0,0,0,0,0,0,0,0,0,0,0,0,0,0,0,0,0,DA86,0,0,0,0,0,0,0,0,0~
,0,0,0,0,0,0,0,0,0,0,0,0,0)';$S;OUT;
    'PE3_TX_DP11':'(0,0,0,0,0,0,0,0,0,0,0,0,0,0,0,0,0,0,0,DC86,0,0,0,0,0,0,0,0,0~
,0,0,0,0,0,0,0,0,0,0,0,0,0)';$S;OUT;
    'PE3_TX_DP10':'(0,0,0,0,0,0,0,0,0,0,0,0,0,0,0,0,0,0,0,DE86,0,0,0,0,0,0,0,0,0~
,0,0,0,0,0,0,0,0,0,0,0,0,0)';$S;OUT;
    'PE3_TX_DP9':'(0,0,0,0,0,0,0,0,0,0,0,0,0,0,0,0,0,0,0,DG86,0,0,0,0,0,0,0,0,0,~
0,0,0,0,0,0,0,0,0,0,0,0,0)';$S;OUT;
    'PE3_TX_DP8':'(0,0,0,0,0,0,0,0,0,0,0,0,0,0,0,0,0,0,0,DJ86,0,0,0,0,0,0,0,0,0,~
0,0,0,0,0,0,0,0,0,0,0,0,0)';$S;OUT;
    'PE3_TX_DP7':'(0,0,0,0,0,0,0,0,0,0,0,0,0,0,0,0,0,0,0,DL86,0,0,0,0,0,0,0,0,0,~
0,0,0,0,0,0,0,0,0,0,0,0,0)';$S;OUT;
    'PE3_TX_DP6':'(0,0,0,0,0,0,0,0,0,0,0,0,0,0,0,0,0,0,0,DN86,0,0,0,0,0,0,0,0,0,~
0,0,0,0,0,0,0,0,0,0,0,0,0)';$S;OUT;
    'PE3_TX_DP5':'(0,0,0,0,0,0,0,0,0,0,0,0,0,0,0,0,0,0,0,DR86,0,0,0,0,0,0,0,0,0,~
0,0,0,0,0,0,0,0,0,0,0,0,0)';$S;OUT;
    'PE3_TX_DP4':'(0,0,0,0,0,0,0,0,0,0,0,0,0,0,0,0,0,0,0,DU86,0,0,0,0,0,0,0,0,0,~
0,0,0,0,0,0,0,0,0,0,0,0,0)';$S;OUT;
    'PE3_TX_DP3':'(0,0,0,0,0,0,0,0,0,0,0,0,0,0,0,0,0,0,0,DW86,0,0,0,0,0,0,0,0,0,~
0,0,0,0,0,0,0,0,0,0,0,0,0)';$S;OUT;
    'PE3_TX_DP2':'(0,0,0,0,0,0,0,0,0,0,0,0,0,0,0,0,0,0,0,EA86,0,0,0,0,0,0,0,0,0,~
0,0,0,0,0,0,0,0,0,0,0,0,0)';$S;OUT;
    'PE3_TX_DP1':'(0,0,0,0,0,0,0,0,0,0,0,0,0,0,0,0,0,0,0,EC86,0,0,0,0,0,0,0,0,0,~
0,0,0,0,0,0,0,0,0,0,0,0,0)';$S;OUT;
    'PE3_TX_DP0':'(0,0,0,0,0,0,0,0,0,0,0,0,0,0,0,0,0,0,0,ED87,0,0,0,0,0,0,0,0,0,~
0,0,0,0,0,0,0,0,0,0,0,0,0)';$S;OUT;
    'PE4_RX_DN15':'(0,0,0,0,0,0,0,0,0,0,0,0,0,0,0,0,0,0,0,0,BB89,0,0,0,0,0,0,0,0~
,0,0,0,0,0,0,0,0,0,0,0,0,0)';$S;IN;
    'PE4_RX_DN14':'(0,0,0,0,0,0,0,0,0,0,0,0,0,0,0,0,0,0,0,0,AY91,0,0,0,0,0,0,0,0~
,0,0,0,0,0,0,0,0,0,0,0,0,0)';$S;IN;
    'PE4_RX_DN13':'(0,0,0,0,0,0,0,0,0,0,0,0,0,0,0,0,0,0,0,0,AV89,0,0,0,0,0,0,0,0~
,0,0,0,0,0,0,0,0,0,0,0,0,0)';$S;IN;
    'PE4_RX_DN12':'(0,0,0,0,0,0,0,0,0,0,0,0,0,0,0,0,0,0,0,0,AT91,0,0,0,0,0,0,0,0~
,0,0,0,0,0,0,0,0,0,0,0,0,0)';$S;IN;
    'PE4_RX_DN11':'(0,0,0,0,0,0,0,0,0,0,0,0,0,0,0,0,0,0,0,0,AP89,0,0,0,0,0,0,0,0~
,0,0,0,0,0,0,0,0,0,0,0,0,0)';$S;IN;
    'PE4_RX_DN10':'(0,0,0,0,0,0,0,0,0,0,0,0,0,0,0,0,0,0,0,0,AM91,0,0,0,0,0,0,0,0~
,0,0,0,0,0,0,0,0,0,0,0,0,0)';$S;IN;
    'PE4_RX_DN9':'(0,0,0,0,0,0,0,0,0,0,0,0,0,0,0,0,0,0,0,0,AK89,0,0,0,0,0,0,0,0,~
0,0,0,0,0,0,0,0,0,0,0,0,0)';$S;IN;
    'PE4_RX_DN8':'(0,0,0,0,0,0,0,0,0,0,0,0,0,0,0,0,0,0,0,0,AH91,0,0,0,0,0,0,0,0,~
0,0,0,0,0,0,0,0,0,0,0,0,0)';$S;IN;
    'PE4_RX_DN7':'(0,0,0,0,0,0,0,0,0,0,0,0,0,0,0,0,0,0,0,0,AF89,0,0,0,0,0,0,0,0,~
0,0,0,0,0,0,0,0,0,0,0,0,0)';$S;IN;
    'PE4_RX_DN6':'(0,0,0,0,0,0,0,0,0,0,0,0,0,0,0,0,0,0,0,0,AD91,0,0,0,0,0,0,0,0,~
0,0,0,0,0,0,0,0,0,0,0,0,0)';$S;IN;
    'PE4_RX_DN5':'(0,0,0,0,0,0,0,0,0,0,0,0,0,0,0,0,0,0,0,0,AB89,0,0,0,0,0,0,0,0,~
0,0,0,0,0,0,0,0,0,0,0,0,0)';$S;IN;
    'PE4_RX_DN4':'(0,0,0,0,0,0,0,0,0,0,0,0,0,0,0,0,0,0,0,0,Y91,0,0,0,0,0,0,0,0,0~
,0,0,0,0,0,0,0,0,0,0,0,0)';$S;IN;
    'PE4_RX_DN3':'(0,0,0,0,0,0,0,0,0,0,0,0,0,0,0,0,0,0,0,0,V89,0,0,0,0,0,0,0,0,0~
,0,0,0,0,0,0,0,0,0,0,0,0)';$S;IN;
    'PE4_RX_DN2':'(0,0,0,0,0,0,0,0,0,0,0,0,0,0,0,0,0,0,0,0,T91,0,0,0,0,0,0,0,0,0~
,0,0,0,0,0,0,0,0,0,0,0,0)';$S;IN;
    'PE4_RX_DN1':'(0,0,0,0,0,0,0,0,0,0,0,0,0,0,0,0,0,0,0,0,P89,0,0,0,0,0,0,0,0,0~
,0,0,0,0,0,0,0,0,0,0,0,0)';$S;IN;
    'PE4_RX_DN0':'(0,0,0,0,0,0,0,0,0,0,0,0,0,0,0,0,0,0,0,0,J90,0,0,0,0,0,0,0,0,0~
,0,0,0,0,0,0,0,0,0,0,0,0)';$S;IN;
    'PE4_RX_DP15':'(0,0,0,0,0,0,0,0,0,0,0,0,0,0,0,0,0,0,0,0,BA90,0,0,0,0,0,0,0,0~
,0,0,0,0,0,0,0,0,0,0,0,0,0)';$S;IN;
    'PE4_RX_DP14':'(0,0,0,0,0,0,0,0,0,0,0,0,0,0,0,0,0,0,0,0,AW90,0,0,0,0,0,0,0,0~
,0,0,0,0,0,0,0,0,0,0,0,0,0)';$S;IN;
    'PE4_RX_DP13':'(0,0,0,0,0,0,0,0,0,0,0,0,0,0,0,0,0,0,0,0,AU90,0,0,0,0,0,0,0,0~
,0,0,0,0,0,0,0,0,0,0,0,0,0)';$S;IN;
    'PE4_RX_DP12':'(0,0,0,0,0,0,0,0,0,0,0,0,0,0,0,0,0,0,0,0,AR90,0,0,0,0,0,0,0,0~
,0,0,0,0,0,0,0,0,0,0,0,0,0)';$S;IN;
    'PE4_RX_DP11':'(0,0,0,0,0,0,0,0,0,0,0,0,0,0,0,0,0,0,0,0,AN90,0,0,0,0,0,0,0,0~
,0,0,0,0,0,0,0,0,0,0,0,0,0)';$S;IN;
    'PE4_RX_DP10':'(0,0,0,0,0,0,0,0,0,0,0,0,0,0,0,0,0,0,0,0,AL90,0,0,0,0,0,0,0,0~
,0,0,0,0,0,0,0,0,0,0,0,0,0)';$S;IN;
    'PE4_RX_DP9':'(0,0,0,0,0,0,0,0,0,0,0,0,0,0,0,0,0,0,0,0,AJ90,0,0,0,0,0,0,0,0,~
0,0,0,0,0,0,0,0,0,0,0,0,0)';$S;IN;
    'PE4_RX_DP8':'(0,0,0,0,0,0,0,0,0,0,0,0,0,0,0,0,0,0,0,0,AG90,0,0,0,0,0,0,0,0,~
0,0,0,0,0,0,0,0,0,0,0,0,0)';$S;IN;
    'PE4_RX_DP7':'(0,0,0,0,0,0,0,0,0,0,0,0,0,0,0,0,0,0,0,0,AE90,0,0,0,0,0,0,0,0,~
0,0,0,0,0,0,0,0,0,0,0,0,0)';$S;IN;
    'PE4_RX_DP6':'(0,0,0,0,0,0,0,0,0,0,0,0,0,0,0,0,0,0,0,0,AC90,0,0,0,0,0,0,0,0,~
0,0,0,0,0,0,0,0,0,0,0,0,0)';$S;IN;
    'PE4_RX_DP5':'(0,0,0,0,0,0,0,0,0,0,0,0,0,0,0,0,0,0,0,0,AA90,0,0,0,0,0,0,0,0,~
0,0,0,0,0,0,0,0,0,0,0,0,0)';$S;IN;
    'PE4_RX_DP4':'(0,0,0,0,0,0,0,0,0,0,0,0,0,0,0,0,0,0,0,0,W90,0,0,0,0,0,0,0,0,0~
,0,0,0,0,0,0,0,0,0,0,0,0)';$S;IN;
    'PE4_RX_DP3':'(0,0,0,0,0,0,0,0,0,0,0,0,0,0,0,0,0,0,0,0,U90,0,0,0,0,0,0,0,0,0~
,0,0,0,0,0,0,0,0,0,0,0,0)';$S;IN;
    'PE4_RX_DP2':'(0,0,0,0,0,0,0,0,0,0,0,0,0,0,0,0,0,0,0,0,R90,0,0,0,0,0,0,0,0,0~
,0,0,0,0,0,0,0,0,0,0,0,0)';$S;IN;
    'PE4_RX_DP1':'(0,0,0,0,0,0,0,0,0,0,0,0,0,0,0,0,0,0,0,0,N90,0,0,0,0,0,0,0,0,0~
,0,0,0,0,0,0,0,0,0,0,0,0)';$S;IN;
    'PE4_RX_DP0':'(0,0,0,0,0,0,0,0,0,0,0,0,0,0,0,0,0,0,0,0,K89,0,0,0,0,0,0,0,0,0~
,0,0,0,0,0,0,0,0,0,0,0,0)';$S;IN;
    'PE4_TX_DN15':'(0,0,0,0,0,0,0,0,0,0,0,0,0,0,0,0,0,0,0,0,BA86,0,0,0,0,0,0,0,0~
,0,0,0,0,0,0,0,0,0,0,0,0,0)';$S;OUT;
    'PE4_TX_DN14':'(0,0,0,0,0,0,0,0,0,0,0,0,0,0,0,0,0,0,0,0,AW86,0,0,0,0,0,0,0,0~
,0,0,0,0,0,0,0,0,0,0,0,0,0)';$S;OUT;
    'PE4_TX_DN13':'(0,0,0,0,0,0,0,0,0,0,0,0,0,0,0,0,0,0,0,0,AU86,0,0,0,0,0,0,0,0~
,0,0,0,0,0,0,0,0,0,0,0,0,0)';$S;OUT;
    'PE4_TX_DN12':'(0,0,0,0,0,0,0,0,0,0,0,0,0,0,0,0,0,0,0,0,AR86,0,0,0,0,0,0,0,0~
,0,0,0,0,0,0,0,0,0,0,0,0,0)';$S;OUT;
    'PE4_TX_DN11':'(0,0,0,0,0,0,0,0,0,0,0,0,0,0,0,0,0,0,0,0,AP85,0,0,0,0,0,0,0,0~
,0,0,0,0,0,0,0,0,0,0,0,0,0)';$S;OUT;
    'PE4_TX_DN10':'(0,0,0,0,0,0,0,0,0,0,0,0,0,0,0,0,0,0,0,0,AL86,0,0,0,0,0,0,0,0~
,0,0,0,0,0,0,0,0,0,0,0,0,0)';$S;OUT;
    'PE4_TX_DN9':'(0,0,0,0,0,0,0,0,0,0,0,0,0,0,0,0,0,0,0,0,AJ86,0,0,0,0,0,0,0,0,~
0,0,0,0,0,0,0,0,0,0,0,0,0)';$S;OUT;
    'PE4_TX_DN8':'(0,0,0,0,0,0,0,0,0,0,0,0,0,0,0,0,0,0,0,0,AG86,0,0,0,0,0,0,0,0,~
0,0,0,0,0,0,0,0,0,0,0,0,0)';$S;OUT;
    'PE4_TX_DN7':'(0,0,0,0,0,0,0,0,0,0,0,0,0,0,0,0,0,0,0,0,AE86,0,0,0,0,0,0,0,0,~
0,0,0,0,0,0,0,0,0,0,0,0,0)';$S;OUT;
    'PE4_TX_DN6':'(0,0,0,0,0,0,0,0,0,0,0,0,0,0,0,0,0,0,0,0,AC86,0,0,0,0,0,0,0,0,~
0,0,0,0,0,0,0,0,0,0,0,0,0)';$S;OUT;
    'PE4_TX_DN5':'(0,0,0,0,0,0,0,0,0,0,0,0,0,0,0,0,0,0,0,0,AA86,0,0,0,0,0,0,0,0,~
0,0,0,0,0,0,0,0,0,0,0,0,0)';$S;OUT;
    'PE4_TX_DN4':'(0,0,0,0,0,0,0,0,0,0,0,0,0,0,0,0,0,0,0,0,W86,0,0,0,0,0,0,0,0,0~
,0,0,0,0,0,0,0,0,0,0,0,0)';$S;OUT;
    'PE4_TX_DN3':'(0,0,0,0,0,0,0,0,0,0,0,0,0,0,0,0,0,0,0,0,U86,0,0,0,0,0,0,0,0,0~
,0,0,0,0,0,0,0,0,0,0,0,0)';$S;OUT;
    'PE4_TX_DN2':'(0,0,0,0,0,0,0,0,0,0,0,0,0,0,0,0,0,0,0,0,R86,0,0,0,0,0,0,0,0,0~
,0,0,0,0,0,0,0,0,0,0,0,0)';$S;OUT;
    'PE4_TX_DN1':'(0,0,0,0,0,0,0,0,0,0,0,0,0,0,0,0,0,0,0,0,P85,0,0,0,0,0,0,0,0,0~
,0,0,0,0,0,0,0,0,0,0,0,0)';$S;OUT;
    'PE4_TX_DN0':'(0,0,0,0,0,0,0,0,0,0,0,0,0,0,0,0,0,0,0,0,L86,0,0,0,0,0,0,0,0,0~
,0,0,0,0,0,0,0,0,0,0,0,0)';$S;OUT;
    'PE4_TX_DP15':'(0,0,0,0,0,0,0,0,0,0,0,0,0,0,0,0,0,0,0,0,BB85,0,0,0,0,0,0,0,0~
,0,0,0,0,0,0,0,0,0,0,0,0,0)';$S;OUT;
    'PE4_TX_DP14':'(0,0,0,0,0,0,0,0,0,0,0,0,0,0,0,0,0,0,0,0,AY87,0,0,0,0,0,0,0,0~
,0,0,0,0,0,0,0,0,0,0,0,0,0)';$S;OUT;
    'PE4_TX_DP13':'(0,0,0,0,0,0,0,0,0,0,0,0,0,0,0,0,0,0,0,0,AV85,0,0,0,0,0,0,0,0~
,0,0,0,0,0,0,0,0,0,0,0,0,0)';$S;OUT;
    'PE4_TX_DP12':'(0,0,0,0,0,0,0,0,0,0,0,0,0,0,0,0,0,0,0,0,AT87,0,0,0,0,0,0,0,0~
,0,0,0,0,0,0,0,0,0,0,0,0,0)';$S;OUT;
    'PE4_TX_DP11':'(0,0,0,0,0,0,0,0,0,0,0,0,0,0,0,0,0,0,0,0,AN86,0,0,0,0,0,0,0,0~
,0,0,0,0,0,0,0,0,0,0,0,0,0)';$S;OUT;
    'PE4_TX_DP10':'(0,0,0,0,0,0,0,0,0,0,0,0,0,0,0,0,0,0,0,0,AM87,0,0,0,0,0,0,0,0~
,0,0,0,0,0,0,0,0,0,0,0,0,0)';$S;OUT;
    'PE4_TX_DP9':'(0,0,0,0,0,0,0,0,0,0,0,0,0,0,0,0,0,0,0,0,AK85,0,0,0,0,0,0,0,0,~
0,0,0,0,0,0,0,0,0,0,0,0,0)';$S;OUT;
    'PE4_TX_DP8':'(0,0,0,0,0,0,0,0,0,0,0,0,0,0,0,0,0,0,0,0,AH87,0,0,0,0,0,0,0,0,~
0,0,0,0,0,0,0,0,0,0,0,0,0)';$S;OUT;
    'PE4_TX_DP7':'(0,0,0,0,0,0,0,0,0,0,0,0,0,0,0,0,0,0,0,0,AF85,0,0,0,0,0,0,0,0,~
0,0,0,0,0,0,0,0,0,0,0,0,0)';$S;OUT;
    'PE4_TX_DP6':'(0,0,0,0,0,0,0,0,0,0,0,0,0,0,0,0,0,0,0,0,AD87,0,0,0,0,0,0,0,0,~
0,0,0,0,0,0,0,0,0,0,0,0,0)';$S;OUT;
    'PE4_TX_DP5':'(0,0,0,0,0,0,0,0,0,0,0,0,0,0,0,0,0,0,0,0,AB85,0,0,0,0,0,0,0,0,~
0,0,0,0,0,0,0,0,0,0,0,0,0)';$S;OUT;
    'PE4_TX_DP4':'(0,0,0,0,0,0,0,0,0,0,0,0,0,0,0,0,0,0,0,0,Y87,0,0,0,0,0,0,0,0,0~
,0,0,0,0,0,0,0,0,0,0,0,0)';$S;OUT;
    'PE4_TX_DP3':'(0,0,0,0,0,0,0,0,0,0,0,0,0,0,0,0,0,0,0,0,V85,0,0,0,0,0,0,0,0,0~
,0,0,0,0,0,0,0,0,0,0,0,0)';$S;OUT;
    'PE4_TX_DP2':'(0,0,0,0,0,0,0,0,0,0,0,0,0,0,0,0,0,0,0,0,T87,0,0,0,0,0,0,0,0,0~
,0,0,0,0,0,0,0,0,0,0,0,0)';$S;OUT;
    'PE4_TX_DP1':'(0,0,0,0,0,0,0,0,0,0,0,0,0,0,0,0,0,0,0,0,N86,0,0,0,0,0,0,0,0,0~
,0,0,0,0,0,0,0,0,0,0,0,0)';$S;OUT;
    'PE4_TX_DP0':'(0,0,0,0,0,0,0,0,0,0,0,0,0,0,0,0,0,0,0,0,M87,0,0,0,0,0,0,0,0,0~
,0,0,0,0,0,0,0,0,0,0,0,0)';$S;OUT;
    'UPI0_RX_DN23':'(0,0,0,0,0,0,0,0,0,0,0,0,0,0,0,0,0,0,0,0,0,BU5,0,0,0,0,0,0,0~
,0,0,0,0,0,0,0,0,0,0,0,0,0)';$S;IN;
    'UPI0_RX_DN22':'(0,0,0,0,0,0,0,0,0,0,0,0,0,0,0,0,0,0,0,0,0,BR7,0,0,0,0,0,0,0~
,0,0,0,0,0,0,0,0,0,0,0,0,0)';$S;IN;
    'UPI0_RX_DN21':'(0,0,0,0,0,0,0,0,0,0,0,0,0,0,0,0,0,0,0,0,0,BN5,0,0,0,0,0,0,0~
,0,0,0,0,0,0,0,0,0,0,0,0,0)';$S;IN;
    'UPI0_RX_DN20':'(0,0,0,0,0,0,0,0,0,0,0,0,0,0,0,0,0,0,0,0,0,BK6,0,0,0,0,0,0,0~
,0,0,0,0,0,0,0,0,0,0,0,0,0)';$S;IN;
    'UPI0_RX_DN19':'(0,0,0,0,0,0,0,0,0,0,0,0,0,0,0,0,0,0,0,0,0,BJ5,0,0,0,0,0,0,0~
,0,0,0,0,0,0,0,0,0,0,0,0,0)';$S;IN;
    'UPI0_RX_DN18':'(0,0,0,0,0,0,0,0,0,0,0,0,0,0,0,0,0,0,0,0,0,BF6,0,0,0,0,0,0,0~
,0,0,0,0,0,0,0,0,0,0,0,0,0)';$S;IN;
    'UPI0_RX_DN17':'(0,0,0,0,0,0,0,0,0,0,0,0,0,0,0,0,0,0,0,0,0,BE5,0,0,0,0,0,0,0~
,0,0,0,0,0,0,0,0,0,0,0,0,0)';$S;IN;
    'UPI0_RX_DN16':'(0,0,0,0,0,0,0,0,0,0,0,0,0,0,0,0,0,0,0,0,0,BB6,0,0,0,0,0,0,0~
,0,0,0,0,0,0,0,0,0,0,0,0,0)';$S;IN;
    'UPI0_RX_DN15':'(0,0,0,0,0,0,0,0,0,0,0,0,0,0,0,0,0,0,0,0,0,BA5,0,0,0,0,0,0,0~
,0,0,0,0,0,0,0,0,0,0,0,0,0)';$S;IN;
    'UPI0_RX_DN14':'(0,0,0,0,0,0,0,0,0,0,0,0,0,0,0,0,0,0,0,0,0,AV6,0,0,0,0,0,0,0~
,0,0,0,0,0,0,0,0,0,0,0,0,0)';$S;IN;
    'UPI0_RX_DN13':'(0,0,0,0,0,0,0,0,0,0,0,0,0,0,0,0,0,0,0,0,0,AU5,0,0,0,0,0,0,0~
,0,0,0,0,0,0,0,0,0,0,0,0,0)';$S;IN;
    'UPI0_RX_DN12':'(0,0,0,0,0,0,0,0,0,0,0,0,0,0,0,0,0,0,0,0,0,AP6,0,0,0,0,0,0,0~
,0,0,0,0,0,0,0,0,0,0,0,0,0)';$S;IN;
    'UPI0_RX_DN11':'(0,0,0,0,0,0,0,0,0,0,0,0,0,0,0,0,0,0,0,0,0,AN5,0,0,0,0,0,0,0~
,0,0,0,0,0,0,0,0,0,0,0,0,0)';$S;IN;
    'UPI0_RX_DN10':'(0,0,0,0,0,0,0,0,0,0,0,0,0,0,0,0,0,0,0,0,0,AK6,0,0,0,0,0,0,0~
,0,0,0,0,0,0,0,0,0,0,0,0,0)';$S;IN;
    'UPI0_RX_DN9':'(0,0,0,0,0,0,0,0,0,0,0,0,0,0,0,0,0,0,0,0,0,AH6,0,0,0,0,0,0,0,~
0,0,0,0,0,0,0,0,0,0,0,0,0)';$S;IN;
    'UPI0_RX_DN8':'(0,0,0,0,0,0,0,0,0,0,0,0,0,0,0,0,0,0,0,0,0,AF6,0,0,0,0,0,0,0,~
0,0,0,0,0,0,0,0,0,0,0,0,0)';$S;IN;
    'UPI0_RX_DN7':'(0,0,0,0,0,0,0,0,0,0,0,0,0,0,0,0,0,0,0,0,0,AE5,0,0,0,0,0,0,0,~
0,0,0,0,0,0,0,0,0,0,0,0,0)';$S;IN;
    'UPI0_RX_DN6':'(0,0,0,0,0,0,0,0,0,0,0,0,0,0,0,0,0,0,0,0,0,AB6,0,0,0,0,0,0,0,~
0,0,0,0,0,0,0,0,0,0,0,0,0)';$S;IN;
    'UPI0_RX_DN5':'(0,0,0,0,0,0,0,0,0,0,0,0,0,0,0,0,0,0,0,0,0,AA5,0,0,0,0,0,0,0,~
0,0,0,0,0,0,0,0,0,0,0,0,0)';$S;IN;
    'UPI0_RX_DN4':'(0,0,0,0,0,0,0,0,0,0,0,0,0,0,0,0,0,0,0,0,0,V6,0,0,0,0,0,0,0,0~
,0,0,0,0,0,0,0,0,0,0,0,0)';$S;IN;
    'UPI0_RX_DN3':'(0,0,0,0,0,0,0,0,0,0,0,0,0,0,0,0,0,0,0,0,0,U5,0,0,0,0,0,0,0,0~
,0,0,0,0,0,0,0,0,0,0,0,0)';$S;IN;
    'UPI0_RX_DN2':'(0,0,0,0,0,0,0,0,0,0,0,0,0,0,0,0,0,0,0,0,0,P6,0,0,0,0,0,0,0,0~
,0,0,0,0,0,0,0,0,0,0,0,0)';$S;IN;
    'UPI0_RX_DN1':'(0,0,0,0,0,0,0,0,0,0,0,0,0,0,0,0,0,0,0,0,0,N5,0,0,0,0,0,0,0,0~
,0,0,0,0,0,0,0,0,0,0,0,0)';$S;IN;
    'UPI0_RX_DN0':'(0,0,0,0,0,0,0,0,0,0,0,0,0,0,0,0,0,0,0,0,0,K6,0,0,0,0,0,0,0,0~
,0,0,0,0,0,0,0,0,0,0,0,0)';$S;IN;
    'UPI0_RX_DP23':'(0,0,0,0,0,0,0,0,0,0,0,0,0,0,0,0,0,0,0,0,0,BT6,0,0,0,0,0,0,0~
,0,0,0,0,0,0,0,0,0,0,0,0,0)';$S;IN;
    'UPI0_RX_DP22':'(0,0,0,0,0,0,0,0,0,0,0,0,0,0,0,0,0,0,0,0,0,BP6,0,0,0,0,0,0,0~
,0,0,0,0,0,0,0,0,0,0,0,0,0)';$S;IN;
    'UPI0_RX_DP21':'(0,0,0,0,0,0,0,0,0,0,0,0,0,0,0,0,0,0,0,0,0,BM6,0,0,0,0,0,0,0~
,0,0,0,0,0,0,0,0,0,0,0,0,0)';$S;IN;
    'UPI0_RX_DP20':'(0,0,0,0,0,0,0,0,0,0,0,0,0,0,0,0,0,0,0,0,0,BL7,0,0,0,0,0,0,0~
,0,0,0,0,0,0,0,0,0,0,0,0,0)';$S;IN;
    'UPI0_RX_DP19':'(0,0,0,0,0,0,0,0,0,0,0,0,0,0,0,0,0,0,0,0,0,BH6,0,0,0,0,0,0,0~
,0,0,0,0,0,0,0,0,0,0,0,0,0)';$S;IN;
    'UPI0_RX_DP18':'(0,0,0,0,0,0,0,0,0,0,0,0,0,0,0,0,0,0,0,0,0,BG7,0,0,0,0,0,0,0~
,0,0,0,0,0,0,0,0,0,0,0,0,0)';$S;IN;
    'UPI0_RX_DP17':'(0,0,0,0,0,0,0,0,0,0,0,0,0,0,0,0,0,0,0,0,0,BD6,0,0,0,0,0,0,0~
,0,0,0,0,0,0,0,0,0,0,0,0,0)';$S;IN;
    'UPI0_RX_DP16':'(0,0,0,0,0,0,0,0,0,0,0,0,0,0,0,0,0,0,0,0,0,BC7,0,0,0,0,0,0,0~
,0,0,0,0,0,0,0,0,0,0,0,0,0)';$S;IN;
    'UPI0_RX_DP15':'(0,0,0,0,0,0,0,0,0,0,0,0,0,0,0,0,0,0,0,0,0,AY6,0,0,0,0,0,0,0~
,0,0,0,0,0,0,0,0,0,0,0,0,0)';$S;IN;
    'UPI0_RX_DP14':'(0,0,0,0,0,0,0,0,0,0,0,0,0,0,0,0,0,0,0,0,0,AW7,0,0,0,0,0,0,0~
,0,0,0,0,0,0,0,0,0,0,0,0,0)';$S;IN;
    'UPI0_RX_DP13':'(0,0,0,0,0,0,0,0,0,0,0,0,0,0,0,0,0,0,0,0,0,AT6,0,0,0,0,0,0,0~
,0,0,0,0,0,0,0,0,0,0,0,0,0)';$S;IN;
    'UPI0_RX_DP12':'(0,0,0,0,0,0,0,0,0,0,0,0,0,0,0,0,0,0,0,0,0,AR7,0,0,0,0,0,0,0~
,0,0,0,0,0,0,0,0,0,0,0,0,0)';$S;IN;
    'UPI0_RX_DP11':'(0,0,0,0,0,0,0,0,0,0,0,0,0,0,0,0,0,0,0,0,0,AM6,0,0,0,0,0,0,0~
,0,0,0,0,0,0,0,0,0,0,0,0,0)';$S;IN;
    'UPI0_RX_DP10':'(0,0,0,0,0,0,0,0,0,0,0,0,0,0,0,0,0,0,0,0,0,AL7,0,0,0,0,0,0,0~
,0,0,0,0,0,0,0,0,0,0,0,0,0)';$S;IN;
    'UPI0_RX_DP9':'(0,0,0,0,0,0,0,0,0,0,0,0,0,0,0,0,0,0,0,0,0,AJ5,0,0,0,0,0,0,0,~
0,0,0,0,0,0,0,0,0,0,0,0,0)';$S;IN;
    'UPI0_RX_DP8':'(0,0,0,0,0,0,0,0,0,0,0,0,0,0,0,0,0,0,0,0,0,AG7,0,0,0,0,0,0,0,~
0,0,0,0,0,0,0,0,0,0,0,0,0)';$S;IN;
    'UPI0_RX_DP7':'(0,0,0,0,0,0,0,0,0,0,0,0,0,0,0,0,0,0,0,0,0,AD6,0,0,0,0,0,0,0,~
0,0,0,0,0,0,0,0,0,0,0,0,0)';$S;IN;
    'UPI0_RX_DP6':'(0,0,0,0,0,0,0,0,0,0,0,0,0,0,0,0,0,0,0,0,0,AC7,0,0,0,0,0,0,0,~
0,0,0,0,0,0,0,0,0,0,0,0,0)';$S;IN;
    'UPI0_RX_DP5':'(0,0,0,0,0,0,0,0,0,0,0,0,0,0,0,0,0,0,0,0,0,Y6,0,0,0,0,0,0,0,0~
,0,0,0,0,0,0,0,0,0,0,0,0)';$S;IN;
    'UPI0_RX_DP4':'(0,0,0,0,0,0,0,0,0,0,0,0,0,0,0,0,0,0,0,0,0,W7,0,0,0,0,0,0,0,0~
,0,0,0,0,0,0,0,0,0,0,0,0)';$S;IN;
    'UPI0_RX_DP3':'(0,0,0,0,0,0,0,0,0,0,0,0,0,0,0,0,0,0,0,0,0,T6,0,0,0,0,0,0,0,0~
,0,0,0,0,0,0,0,0,0,0,0,0)';$S;IN;
    'UPI0_RX_DP2':'(0,0,0,0,0,0,0,0,0,0,0,0,0,0,0,0,0,0,0,0,0,R7,0,0,0,0,0,0,0,0~
,0,0,0,0,0,0,0,0,0,0,0,0)';$S;IN;
    'UPI0_RX_DP1':'(0,0,0,0,0,0,0,0,0,0,0,0,0,0,0,0,0,0,0,0,0,M6,0,0,0,0,0,0,0,0~
,0,0,0,0,0,0,0,0,0,0,0,0)';$S;IN;
    'UPI0_RX_DP0':'(0,0,0,0,0,0,0,0,0,0,0,0,0,0,0,0,0,0,0,0,0,L7,0,0,0,0,0,0,0,0~
,0,0,0,0,0,0,0,0,0,0,0,0)';$S;IN;
    'UPI0_TX_DN23':'(0,0,0,0,0,0,0,0,0,0,0,0,0,0,0,0,0,0,0,0,0,BT2,0,0,0,0,0,0,0~
,0,0,0,0,0,0,0,0,0,0,0,0,0)';$S;OUT;
    'UPI0_TX_DN22':'(0,0,0,0,0,0,0,0,0,0,0,0,0,0,0,0,0,0,0,0,0,BR3,0,0,0,0,0,0,0~
,0,0,0,0,0,0,0,0,0,0,0,0,0)';$S;OUT;
    'UPI0_TX_DN21':'(0,0,0,0,0,0,0,0,0,0,0,0,0,0,0,0,0,0,0,0,0,BM2,0,0,0,0,0,0,0~
,0,0,0,0,0,0,0,0,0,0,0,0,0)';$S;OUT;
    'UPI0_TX_DN20':'(0,0,0,0,0,0,0,0,0,0,0,0,0,0,0,0,0,0,0,0,0,BK2,0,0,0,0,0,0,0~
,0,0,0,0,0,0,0,0,0,0,0,0,0)';$S;OUT;
    'UPI0_TX_DN19':'(0,0,0,0,0,0,0,0,0,0,0,0,0,0,0,0,0,0,0,0,0,BH2,0,0,0,0,0,0,0~
,0,0,0,0,0,0,0,0,0,0,0,0,0)';$S;OUT;
    'UPI0_TX_DN18':'(0,0,0,0,0,0,0,0,0,0,0,0,0,0,0,0,0,0,0,0,0,BF2,0,0,0,0,0,0,0~
,0,0,0,0,0,0,0,0,0,0,0,0,0)';$S;OUT;
    'UPI0_TX_DN17':'(0,0,0,0,0,0,0,0,0,0,0,0,0,0,0,0,0,0,0,0,0,BD2,0,0,0,0,0,0,0~
,0,0,0,0,0,0,0,0,0,0,0,0,0)';$S;OUT;
    'UPI0_TX_DN16':'(0,0,0,0,0,0,0,0,0,0,0,0,0,0,0,0,0,0,0,0,0,BB2,0,0,0,0,0,0,0~
,0,0,0,0,0,0,0,0,0,0,0,0,0)';$S;OUT;
    'UPI0_TX_DN15':'(0,0,0,0,0,0,0,0,0,0,0,0,0,0,0,0,0,0,0,0,0,AY2,0,0,0,0,0,0,0~
,0,0,0,0,0,0,0,0,0,0,0,0,0)';$S;OUT;
    'UPI0_TX_DN14':'(0,0,0,0,0,0,0,0,0,0,0,0,0,0,0,0,0,0,0,0,0,AU1,0,0,0,0,0,0,0~
,0,0,0,0,0,0,0,0,0,0,0,0,0)';$S;OUT;
    'UPI0_TX_DN13':'(0,0,0,0,0,0,0,0,0,0,0,0,0,0,0,0,0,0,0,0,0,AT2,0,0,0,0,0,0,0~
,0,0,0,0,0,0,0,0,0,0,0,0,0)';$S;OUT;
    'UPI0_TX_DN12':'(0,0,0,0,0,0,0,0,0,0,0,0,0,0,0,0,0,0,0,0,0,AP2,0,0,0,0,0,0,0~
,0,0,0,0,0,0,0,0,0,0,0,0,0)';$S;OUT;
    'UPI0_TX_DN11':'(0,0,0,0,0,0,0,0,0,0,0,0,0,0,0,0,0,0,0,0,0,AM2,0,0,0,0,0,0,0~
,0,0,0,0,0,0,0,0,0,0,0,0,0)';$S;OUT;
    'UPI0_TX_DN10':'(0,0,0,0,0,0,0,0,0,0,0,0,0,0,0,0,0,0,0,0,0,AK2,0,0,0,0,0,0,0~
,0,0,0,0,0,0,0,0,0,0,0,0,0)';$S;OUT;
    'UPI0_TX_DN9':'(0,0,0,0,0,0,0,0,0,0,0,0,0,0,0,0,0,0,0,0,0,AH2,0,0,0,0,0,0,0,~
0,0,0,0,0,0,0,0,0,0,0,0,0)';$S;OUT;
    'UPI0_TX_DN8':'(0,0,0,0,0,0,0,0,0,0,0,0,0,0,0,0,0,0,0,0,0,AF2,0,0,0,0,0,0,0,~
0,0,0,0,0,0,0,0,0,0,0,0,0)';$S;OUT;
    'UPI0_TX_DN7':'(0,0,0,0,0,0,0,0,0,0,0,0,0,0,0,0,0,0,0,0,0,AD2,0,0,0,0,0,0,0,~
0,0,0,0,0,0,0,0,0,0,0,0,0)';$S;OUT;
    'UPI0_TX_DN6':'(0,0,0,0,0,0,0,0,0,0,0,0,0,0,0,0,0,0,0,0,0,AA1,0,0,0,0,0,0,0,~
0,0,0,0,0,0,0,0,0,0,0,0,0)';$S;OUT;
    'UPI0_TX_DN5':'(0,0,0,0,0,0,0,0,0,0,0,0,0,0,0,0,0,0,0,0,0,Y2,0,0,0,0,0,0,0,0~
,0,0,0,0,0,0,0,0,0,0,0,0)';$S;OUT;
    'UPI0_TX_DN4':'(0,0,0,0,0,0,0,0,0,0,0,0,0,0,0,0,0,0,0,0,0,U1,0,0,0,0,0,0,0,0~
,0,0,0,0,0,0,0,0,0,0,0,0)';$S;OUT;
    'UPI0_TX_DN3':'(0,0,0,0,0,0,0,0,0,0,0,0,0,0,0,0,0,0,0,0,0,T2,0,0,0,0,0,0,0,0~
,0,0,0,0,0,0,0,0,0,0,0,0)';$S;OUT;
    'UPI0_TX_DN2':'(0,0,0,0,0,0,0,0,0,0,0,0,0,0,0,0,0,0,0,0,0,N1,0,0,0,0,0,0,0,0~
,0,0,0,0,0,0,0,0,0,0,0,0)';$S;OUT;
    'UPI0_TX_DN1':'(0,0,0,0,0,0,0,0,0,0,0,0,0,0,0,0,0,0,0,0,0,M2,0,0,0,0,0,0,0,0~
,0,0,0,0,0,0,0,0,0,0,0,0)';$S;OUT;
    'UPI0_TX_DN0':'(0,0,0,0,0,0,0,0,0,0,0,0,0,0,0,0,0,0,0,0,0,K4,0,0,0,0,0,0,0,0~
,0,0,0,0,0,0,0,0,0,0,0,0)';$S;OUT;
    'UPI0_TX_DP23':'(0,0,0,0,0,0,0,0,0,0,0,0,0,0,0,0,0,0,0,0,0,BU3,0,0,0,0,0,0,0~
,0,0,0,0,0,0,0,0,0,0,0,0,0)';$S;OUT;
    'UPI0_TX_DP22':'(0,0,0,0,0,0,0,0,0,0,0,0,0,0,0,0,0,0,0,0,0,BN3,0,0,0,0,0,0,0~
,0,0,0,0,0,0,0,0,0,0,0,0,0)';$S;OUT;
    'UPI0_TX_DP21':'(0,0,0,0,0,0,0,0,0,0,0,0,0,0,0,0,0,0,0,0,0,BL3,0,0,0,0,0,0,0~
,0,0,0,0,0,0,0,0,0,0,0,0,0)';$S;OUT;
    'UPI0_TX_DP20':'(0,0,0,0,0,0,0,0,0,0,0,0,0,0,0,0,0,0,0,0,0,BJ1,0,0,0,0,0,0,0~
,0,0,0,0,0,0,0,0,0,0,0,0,0)';$S;OUT;
    'UPI0_TX_DP19':'(0,0,0,0,0,0,0,0,0,0,0,0,0,0,0,0,0,0,0,0,0,BG3,0,0,0,0,0,0,0~
,0,0,0,0,0,0,0,0,0,0,0,0,0)';$S;OUT;
    'UPI0_TX_DP18':'(0,0,0,0,0,0,0,0,0,0,0,0,0,0,0,0,0,0,0,0,0,BE1,0,0,0,0,0,0,0~
,0,0,0,0,0,0,0,0,0,0,0,0,0)';$S;OUT;
    'UPI0_TX_DP17':'(0,0,0,0,0,0,0,0,0,0,0,0,0,0,0,0,0,0,0,0,0,BC3,0,0,0,0,0,0,0~
,0,0,0,0,0,0,0,0,0,0,0,0,0)';$S;OUT;
    'UPI0_TX_DP16':'(0,0,0,0,0,0,0,0,0,0,0,0,0,0,0,0,0,0,0,0,0,BA1,0,0,0,0,0,0,0~
,0,0,0,0,0,0,0,0,0,0,0,0,0)';$S;OUT;
    'UPI0_TX_DP15':'(0,0,0,0,0,0,0,0,0,0,0,0,0,0,0,0,0,0,0,0,0,AW3,0,0,0,0,0,0,0~
,0,0,0,0,0,0,0,0,0,0,0,0,0)';$S;OUT;
    'UPI0_TX_DP14':'(0,0,0,0,0,0,0,0,0,0,0,0,0,0,0,0,0,0,0,0,0,AV2,0,0,0,0,0,0,0~
,0,0,0,0,0,0,0,0,0,0,0,0,0)';$S;OUT;
    'UPI0_TX_DP13':'(0,0,0,0,0,0,0,0,0,0,0,0,0,0,0,0,0,0,0,0,0,AR3,0,0,0,0,0,0,0~
,0,0,0,0,0,0,0,0,0,0,0,0,0)';$S;OUT;
    'UPI0_TX_DP12':'(0,0,0,0,0,0,0,0,0,0,0,0,0,0,0,0,0,0,0,0,0,AN1,0,0,0,0,0,0,0~
,0,0,0,0,0,0,0,0,0,0,0,0,0)';$S;OUT;
    'UPI0_TX_DP11':'(0,0,0,0,0,0,0,0,0,0,0,0,0,0,0,0,0,0,0,0,0,AL3,0,0,0,0,0,0,0~
,0,0,0,0,0,0,0,0,0,0,0,0,0)';$S;OUT;
    'UPI0_TX_DP10':'(0,0,0,0,0,0,0,0,0,0,0,0,0,0,0,0,0,0,0,0,0,AJ1,0,0,0,0,0,0,0~
,0,0,0,0,0,0,0,0,0,0,0,0,0)';$S;OUT;
    'UPI0_TX_DP9':'(0,0,0,0,0,0,0,0,0,0,0,0,0,0,0,0,0,0,0,0,0,AG3,0,0,0,0,0,0,0,~
0,0,0,0,0,0,0,0,0,0,0,0,0)';$S;OUT;
    'UPI0_TX_DP8':'(0,0,0,0,0,0,0,0,0,0,0,0,0,0,0,0,0,0,0,0,0,AE1,0,0,0,0,0,0,0,~
0,0,0,0,0,0,0,0,0,0,0,0,0)';$S;OUT;
    'UPI0_TX_DP7':'(0,0,0,0,0,0,0,0,0,0,0,0,0,0,0,0,0,0,0,0,0,AC3,0,0,0,0,0,0,0,~
0,0,0,0,0,0,0,0,0,0,0,0,0)';$S;OUT;
    'UPI0_TX_DP6':'(0,0,0,0,0,0,0,0,0,0,0,0,0,0,0,0,0,0,0,0,0,AB2,0,0,0,0,0,0,0,~
0,0,0,0,0,0,0,0,0,0,0,0,0)';$S;OUT;
    'UPI0_TX_DP5':'(0,0,0,0,0,0,0,0,0,0,0,0,0,0,0,0,0,0,0,0,0,W3,0,0,0,0,0,0,0,0~
,0,0,0,0,0,0,0,0,0,0,0,0)';$S;OUT;
    'UPI0_TX_DP4':'(0,0,0,0,0,0,0,0,0,0,0,0,0,0,0,0,0,0,0,0,0,V2,0,0,0,0,0,0,0,0~
,0,0,0,0,0,0,0,0,0,0,0,0)';$S;OUT;
    'UPI0_TX_DP3':'(0,0,0,0,0,0,0,0,0,0,0,0,0,0,0,0,0,0,0,0,0,R3,0,0,0,0,0,0,0,0~
,0,0,0,0,0,0,0,0,0,0,0,0)';$S;OUT;
    'UPI0_TX_DP2':'(0,0,0,0,0,0,0,0,0,0,0,0,0,0,0,0,0,0,0,0,0,P2,0,0,0,0,0,0,0,0~
,0,0,0,0,0,0,0,0,0,0,0,0)';$S;OUT;
    'UPI0_TX_DP1':'(0,0,0,0,0,0,0,0,0,0,0,0,0,0,0,0,0,0,0,0,0,L3,0,0,0,0,0,0,0,0~
,0,0,0,0,0,0,0,0,0,0,0,0)';$S;OUT;
    'UPI0_TX_DP0':'(0,0,0,0,0,0,0,0,0,0,0,0,0,0,0,0,0,0,0,0,0,J3,0,0,0,0,0,0,0,0~
,0,0,0,0,0,0,0,0,0,0,0,0)';$S;OUT;
    'UPI1_RX_DN23':'(0,0,0,0,0,0,0,0,0,0,0,0,0,0,0,0,0,0,0,0,0,0,CB2,0,0,0,0,0,0~
,0,0,0,0,0,0,0,0,0,0,0,0,0)';$S;IN;
    'UPI1_RX_DN22':'(0,0,0,0,0,0,0,0,0,0,0,0,0,0,0,0,0,0,0,0,0,0,CD2,0,0,0,0,0,0~
,0,0,0,0,0,0,0,0,0,0,0,0,0)';$S;IN;
    'UPI1_RX_DN21':'(0,0,0,0,0,0,0,0,0,0,0,0,0,0,0,0,0,0,0,0,0,0,CF2,0,0,0,0,0,0~
,0,0,0,0,0,0,0,0,0,0,0,0,0)';$S;IN;
    'UPI1_RX_DN20':'(0,0,0,0,0,0,0,0,0,0,0,0,0,0,0,0,0,0,0,0,0,0,CH2,0,0,0,0,0,0~
,0,0,0,0,0,0,0,0,0,0,0,0,0)';$S;IN;
    'UPI1_RX_DN19':'(0,0,0,0,0,0,0,0,0,0,0,0,0,0,0,0,0,0,0,0,0,0,CJ1,0,0,0,0,0,0~
,0,0,0,0,0,0,0,0,0,0,0,0,0)';$S;IN;
    'UPI1_RX_DN18':'(0,0,0,0,0,0,0,0,0,0,0,0,0,0,0,0,0,0,0,0,0,0,CL3,0,0,0,0,0,0~
,0,0,0,0,0,0,0,0,0,0,0,0,0)';$S;IN;
    'UPI1_RX_DN17':'(0,0,0,0,0,0,0,0,0,0,0,0,0,0,0,0,0,0,0,0,0,0,CN1,0,0,0,0,0,0~
,0,0,0,0,0,0,0,0,0,0,0,0,0)';$S;IN;
    'UPI1_RX_DN16':'(0,0,0,0,0,0,0,0,0,0,0,0,0,0,0,0,0,0,0,0,0,0,CR3,0,0,0,0,0,0~
,0,0,0,0,0,0,0,0,0,0,0,0,0)';$S;IN;
    'UPI1_RX_DN15':'(0,0,0,0,0,0,0,0,0,0,0,0,0,0,0,0,0,0,0,0,0,0,CV2,0,0,0,0,0,0~
,0,0,0,0,0,0,0,0,0,0,0,0,0)';$S;IN;
    'UPI1_RX_DN14':'(0,0,0,0,0,0,0,0,0,0,0,0,0,0,0,0,0,0,0,0,0,0,CY2,0,0,0,0,0,0~
,0,0,0,0,0,0,0,0,0,0,0,0,0)';$S;IN;
    'UPI1_RX_DN13':'(0,0,0,0,0,0,0,0,0,0,0,0,0,0,0,0,0,0,0,0,0,0,DB2,0,0,0,0,0,0~
,0,0,0,0,0,0,0,0,0,0,0,0,0)';$S;IN;
    'UPI1_RX_DN12':'(0,0,0,0,0,0,0,0,0,0,0,0,0,0,0,0,0,0,0,0,0,0,DD2,0,0,0,0,0,0~
,0,0,0,0,0,0,0,0,0,0,0,0,0)';$S;IN;
    'UPI1_RX_DN11':'(0,0,0,0,0,0,0,0,0,0,0,0,0,0,0,0,0,0,0,0,0,0,DE1,0,0,0,0,0,0~
,0,0,0,0,0,0,0,0,0,0,0,0,0)';$S;IN;
    'UPI1_RX_DN10':'(0,0,0,0,0,0,0,0,0,0,0,0,0,0,0,0,0,0,0,0,0,0,DG3,0,0,0,0,0,0~
,0,0,0,0,0,0,0,0,0,0,0,0,0)';$S;IN;
    'UPI1_RX_DN9':'(0,0,0,0,0,0,0,0,0,0,0,0,0,0,0,0,0,0,0,0,0,0,DJ1,0,0,0,0,0,0,~
0,0,0,0,0,0,0,0,0,0,0,0,0)';$S;IN;
    'UPI1_RX_DN8':'(0,0,0,0,0,0,0,0,0,0,0,0,0,0,0,0,0,0,0,0,0,0,DL3,0,0,0,0,0,0,~
0,0,0,0,0,0,0,0,0,0,0,0,0)';$S;IN;
    'UPI1_RX_DN7':'(0,0,0,0,0,0,0,0,0,0,0,0,0,0,0,0,0,0,0,0,0,0,DN1,0,0,0,0,0,0,~
0,0,0,0,0,0,0,0,0,0,0,0,0)';$S;IN;
    'UPI1_RX_DN6':'(0,0,0,0,0,0,0,0,0,0,0,0,0,0,0,0,0,0,0,0,0,0,DT2,0,0,0,0,0,0,~
0,0,0,0,0,0,0,0,0,0,0,0,0)';$S;IN;
    'UPI1_RX_DN5':'(0,0,0,0,0,0,0,0,0,0,0,0,0,0,0,0,0,0,0,0,0,0,DU1,0,0,0,0,0,0,~
0,0,0,0,0,0,0,0,0,0,0,0,0)';$S;IN;
    'UPI1_RX_DN4':'(0,0,0,0,0,0,0,0,0,0,0,0,0,0,0,0,0,0,0,0,0,0,DY2,0,0,0,0,0,0,~
0,0,0,0,0,0,0,0,0,0,0,0,0)';$S;IN;
    'UPI1_RX_DN3':'(0,0,0,0,0,0,0,0,0,0,0,0,0,0,0,0,0,0,0,0,0,0,EA1,0,0,0,0,0,0,~
0,0,0,0,0,0,0,0,0,0,0,0,0)';$S;IN;
    'UPI1_RX_DN2':'(0,0,0,0,0,0,0,0,0,0,0,0,0,0,0,0,0,0,0,0,0,0,ED2,0,0,0,0,0,0,~
0,0,0,0,0,0,0,0,0,0,0,0,0)';$S;IN;
    'UPI1_RX_DN1':'(0,0,0,0,0,0,0,0,0,0,0,0,0,0,0,0,0,0,0,0,0,0,EE3,0,0,0,0,0,0,~
0,0,0,0,0,0,0,0,0,0,0,0,0)';$S;IN;
    'UPI1_RX_DN0':'(0,0,0,0,0,0,0,0,0,0,0,0,0,0,0,0,0,0,0,0,0,0,EH2,0,0,0,0,0,0,~
0,0,0,0,0,0,0,0,0,0,0,0,0)';$S;IN;
    'UPI1_RX_DP23':'(0,0,0,0,0,0,0,0,0,0,0,0,0,0,0,0,0,0,0,0,0,0,BY2,0,0,0,0,0,0~
,0,0,0,0,0,0,0,0,0,0,0,0,0)';$S;IN;
    'UPI1_RX_DP22':'(0,0,0,0,0,0,0,0,0,0,0,0,0,0,0,0,0,0,0,0,0,0,CC3,0,0,0,0,0,0~
,0,0,0,0,0,0,0,0,0,0,0,0,0)';$S;IN;
    'UPI1_RX_DP21':'(0,0,0,0,0,0,0,0,0,0,0,0,0,0,0,0,0,0,0,0,0,0,CE1,0,0,0,0,0,0~
,0,0,0,0,0,0,0,0,0,0,0,0,0)';$S;IN;
    'UPI1_RX_DP20':'(0,0,0,0,0,0,0,0,0,0,0,0,0,0,0,0,0,0,0,0,0,0,CG3,0,0,0,0,0,0~
,0,0,0,0,0,0,0,0,0,0,0,0,0)';$S;IN;
    'UPI1_RX_DP19':'(0,0,0,0,0,0,0,0,0,0,0,0,0,0,0,0,0,0,0,0,0,0,CK2,0,0,0,0,0,0~
,0,0,0,0,0,0,0,0,0,0,0,0,0)';$S;IN;
    'UPI1_RX_DP18':'(0,0,0,0,0,0,0,0,0,0,0,0,0,0,0,0,0,0,0,0,0,0,CM2,0,0,0,0,0,0~
,0,0,0,0,0,0,0,0,0,0,0,0,0)';$S;IN;
    'UPI1_RX_DP17':'(0,0,0,0,0,0,0,0,0,0,0,0,0,0,0,0,0,0,0,0,0,0,CP2,0,0,0,0,0,0~
,0,0,0,0,0,0,0,0,0,0,0,0,0)';$S;IN;
    'UPI1_RX_DP16':'(0,0,0,0,0,0,0,0,0,0,0,0,0,0,0,0,0,0,0,0,0,0,CT2,0,0,0,0,0,0~
,0,0,0,0,0,0,0,0,0,0,0,0,0)';$S;IN;
    'UPI1_RX_DP15':'(0,0,0,0,0,0,0,0,0,0,0,0,0,0,0,0,0,0,0,0,0,0,CU1,0,0,0,0,0,0~
,0,0,0,0,0,0,0,0,0,0,0,0,0)';$S;IN;
    'UPI1_RX_DP14':'(0,0,0,0,0,0,0,0,0,0,0,0,0,0,0,0,0,0,0,0,0,0,CW3,0,0,0,0,0,0~
,0,0,0,0,0,0,0,0,0,0,0,0,0)';$S;IN;
    'UPI1_RX_DP13':'(0,0,0,0,0,0,0,0,0,0,0,0,0,0,0,0,0,0,0,0,0,0,DA1,0,0,0,0,0,0~
,0,0,0,0,0,0,0,0,0,0,0,0,0)';$S;IN;
    'UPI1_RX_DP12':'(0,0,0,0,0,0,0,0,0,0,0,0,0,0,0,0,0,0,0,0,0,0,DC3,0,0,0,0,0,0~
,0,0,0,0,0,0,0,0,0,0,0,0,0)';$S;IN;
    'UPI1_RX_DP11':'(0,0,0,0,0,0,0,0,0,0,0,0,0,0,0,0,0,0,0,0,0,0,DF2,0,0,0,0,0,0~
,0,0,0,0,0,0,0,0,0,0,0,0,0)';$S;IN;
    'UPI1_RX_DP10':'(0,0,0,0,0,0,0,0,0,0,0,0,0,0,0,0,0,0,0,0,0,0,DH2,0,0,0,0,0,0~
,0,0,0,0,0,0,0,0,0,0,0,0,0)';$S;IN;
    'UPI1_RX_DP9':'(0,0,0,0,0,0,0,0,0,0,0,0,0,0,0,0,0,0,0,0,0,0,DK2,0,0,0,0,0,0,~
0,0,0,0,0,0,0,0,0,0,0,0,0)';$S;IN;
    'UPI1_RX_DP8':'(0,0,0,0,0,0,0,0,0,0,0,0,0,0,0,0,0,0,0,0,0,0,DM2,0,0,0,0,0,0,~
0,0,0,0,0,0,0,0,0,0,0,0,0)';$S;IN;
    'UPI1_RX_DP7':'(0,0,0,0,0,0,0,0,0,0,0,0,0,0,0,0,0,0,0,0,0,0,DP2,0,0,0,0,0,0,~
0,0,0,0,0,0,0,0,0,0,0,0,0)';$S;IN;
    'UPI1_RX_DP6':'(0,0,0,0,0,0,0,0,0,0,0,0,0,0,0,0,0,0,0,0,0,0,DR3,0,0,0,0,0,0,~
0,0,0,0,0,0,0,0,0,0,0,0,0)';$S;IN;
    'UPI1_RX_DP5':'(0,0,0,0,0,0,0,0,0,0,0,0,0,0,0,0,0,0,0,0,0,0,DV2,0,0,0,0,0,0,~
0,0,0,0,0,0,0,0,0,0,0,0,0)';$S;IN;
    'UPI1_RX_DP4':'(0,0,0,0,0,0,0,0,0,0,0,0,0,0,0,0,0,0,0,0,0,0,DW3,0,0,0,0,0,0,~
0,0,0,0,0,0,0,0,0,0,0,0,0)';$S;IN;
    'UPI1_RX_DP3':'(0,0,0,0,0,0,0,0,0,0,0,0,0,0,0,0,0,0,0,0,0,0,EB2,0,0,0,0,0,0,~
0,0,0,0,0,0,0,0,0,0,0,0,0)';$S;IN;
    'UPI1_RX_DP2':'(0,0,0,0,0,0,0,0,0,0,0,0,0,0,0,0,0,0,0,0,0,0,EC3,0,0,0,0,0,0,~
0,0,0,0,0,0,0,0,0,0,0,0,0)';$S;IN;
    'UPI1_RX_DP1':'(0,0,0,0,0,0,0,0,0,0,0,0,0,0,0,0,0,0,0,0,0,0,EG3,0,0,0,0,0,0,~
0,0,0,0,0,0,0,0,0,0,0,0,0)';$S;IN;
    'UPI1_RX_DP0':'(0,0,0,0,0,0,0,0,0,0,0,0,0,0,0,0,0,0,0,0,0,0,EJ3,0,0,0,0,0,0,~
0,0,0,0,0,0,0,0,0,0,0,0,0)';$S;IN;
    'UPI1_TX_DN23':'(0,0,0,0,0,0,0,0,0,0,0,0,0,0,0,0,0,0,0,0,0,0,BY6,0,0,0,0,0,0~
,0,0,0,0,0,0,0,0,0,0,0,0,0)';$S;OUT;
    'UPI1_TX_DN22':'(0,0,0,0,0,0,0,0,0,0,0,0,0,0,0,0,0,0,0,0,0,0,CA5,0,0,0,0,0,0~
,0,0,0,0,0,0,0,0,0,0,0,0,0)';$S;OUT;
    'UPI1_TX_DN21':'(0,0,0,0,0,0,0,0,0,0,0,0,0,0,0,0,0,0,0,0,0,0,CD6,0,0,0,0,0,0~
,0,0,0,0,0,0,0,0,0,0,0,0,0)';$S;OUT;
    'UPI1_TX_DN20':'(0,0,0,0,0,0,0,0,0,0,0,0,0,0,0,0,0,0,0,0,0,0,CE5,0,0,0,0,0,0~
,0,0,0,0,0,0,0,0,0,0,0,0,0)';$S;OUT;
    'UPI1_TX_DN19':'(0,0,0,0,0,0,0,0,0,0,0,0,0,0,0,0,0,0,0,0,0,0,CH6,0,0,0,0,0,0~
,0,0,0,0,0,0,0,0,0,0,0,0,0)';$S;OUT;
    'UPI1_TX_DN18':'(0,0,0,0,0,0,0,0,0,0,0,0,0,0,0,0,0,0,0,0,0,0,CJ5,0,0,0,0,0,0~
,0,0,0,0,0,0,0,0,0,0,0,0,0)';$S;OUT;
    'UPI1_TX_DN17':'(0,0,0,0,0,0,0,0,0,0,0,0,0,0,0,0,0,0,0,0,0,0,CM6,0,0,0,0,0,0~
,0,0,0,0,0,0,0,0,0,0,0,0,0)';$S;OUT;
    'UPI1_TX_DN16':'(0,0,0,0,0,0,0,0,0,0,0,0,0,0,0,0,0,0,0,0,0,0,CN5,0,0,0,0,0,0~
,0,0,0,0,0,0,0,0,0,0,0,0,0)';$S;OUT;
    'UPI1_TX_DN15':'(0,0,0,0,0,0,0,0,0,0,0,0,0,0,0,0,0,0,0,0,0,0,CT6,0,0,0,0,0,0~
,0,0,0,0,0,0,0,0,0,0,0,0,0)';$S;OUT;
    'UPI1_TX_DN14':'(0,0,0,0,0,0,0,0,0,0,0,0,0,0,0,0,0,0,0,0,0,0,CU5,0,0,0,0,0,0~
,0,0,0,0,0,0,0,0,0,0,0,0,0)';$S;OUT;
    'UPI1_TX_DN13':'(0,0,0,0,0,0,0,0,0,0,0,0,0,0,0,0,0,0,0,0,0,0,CY6,0,0,0,0,0,0~
,0,0,0,0,0,0,0,0,0,0,0,0,0)';$S;OUT;
    'UPI1_TX_DN12':'(0,0,0,0,0,0,0,0,0,0,0,0,0,0,0,0,0,0,0,0,0,0,DA5,0,0,0,0,0,0~
,0,0,0,0,0,0,0,0,0,0,0,0,0)';$S;OUT;
    'UPI1_TX_DN11':'(0,0,0,0,0,0,0,0,0,0,0,0,0,0,0,0,0,0,0,0,0,0,DD6,0,0,0,0,0,0~
,0,0,0,0,0,0,0,0,0,0,0,0,0)';$S;OUT;
    'UPI1_TX_DN10':'(0,0,0,0,0,0,0,0,0,0,0,0,0,0,0,0,0,0,0,0,0,0,DE5,0,0,0,0,0,0~
,0,0,0,0,0,0,0,0,0,0,0,0,0)';$S;OUT;
    'UPI1_TX_DN9':'(0,0,0,0,0,0,0,0,0,0,0,0,0,0,0,0,0,0,0,0,0,0,DH6,0,0,0,0,0,0,~
0,0,0,0,0,0,0,0,0,0,0,0,0)';$S;OUT;
    'UPI1_TX_DN8':'(0,0,0,0,0,0,0,0,0,0,0,0,0,0,0,0,0,0,0,0,0,0,DK6,0,0,0,0,0,0,~
0,0,0,0,0,0,0,0,0,0,0,0,0)';$S;OUT;
    'UPI1_TX_DN7':'(0,0,0,0,0,0,0,0,0,0,0,0,0,0,0,0,0,0,0,0,0,0,DL7,0,0,0,0,0,0,~
0,0,0,0,0,0,0,0,0,0,0,0,0)';$S;OUT;
    'UPI1_TX_DN6':'(0,0,0,0,0,0,0,0,0,0,0,0,0,0,0,0,0,0,0,0,0,0,DP6,0,0,0,0,0,0,~
0,0,0,0,0,0,0,0,0,0,0,0,0)';$S;OUT;
    'UPI1_TX_DN5':'(0,0,0,0,0,0,0,0,0,0,0,0,0,0,0,0,0,0,0,0,0,0,DT6,0,0,0,0,0,0,~
0,0,0,0,0,0,0,0,0,0,0,0,0)';$S;OUT;
    'UPI1_TX_DN4':'(0,0,0,0,0,0,0,0,0,0,0,0,0,0,0,0,0,0,0,0,0,0,DV6,0,0,0,0,0,0,~
0,0,0,0,0,0,0,0,0,0,0,0,0)';$S;OUT;
    'UPI1_TX_DN3':'(0,0,0,0,0,0,0,0,0,0,0,0,0,0,0,0,0,0,0,0,0,0,DY6,0,0,0,0,0,0,~
0,0,0,0,0,0,0,0,0,0,0,0,0)';$S;OUT;
    'UPI1_TX_DN2':'(0,0,0,0,0,0,0,0,0,0,0,0,0,0,0,0,0,0,0,0,0,0,EB6,0,0,0,0,0,0,~
0,0,0,0,0,0,0,0,0,0,0,0,0)';$S;OUT;
    'UPI1_TX_DN1':'(0,0,0,0,0,0,0,0,0,0,0,0,0,0,0,0,0,0,0,0,0,0,EC7,0,0,0,0,0,0,~
0,0,0,0,0,0,0,0,0,0,0,0,0)';$S;OUT;
    'UPI1_TX_DN0':'(0,0,0,0,0,0,0,0,0,0,0,0,0,0,0,0,0,0,0,0,0,0,EF6,0,0,0,0,0,0,~
0,0,0,0,0,0,0,0,0,0,0,0,0)';$S;OUT;
    'UPI1_TX_DP23':'(0,0,0,0,0,0,0,0,0,0,0,0,0,0,0,0,0,0,0,0,0,0,BW7,0,0,0,0,0,0~
,0,0,0,0,0,0,0,0,0,0,0,0,0)';$S;OUT;
    'UPI1_TX_DP22':'(0,0,0,0,0,0,0,0,0,0,0,0,0,0,0,0,0,0,0,0,0,0,CB6,0,0,0,0,0,0~
,0,0,0,0,0,0,0,0,0,0,0,0,0)';$S;OUT;
    'UPI1_TX_DP21':'(0,0,0,0,0,0,0,0,0,0,0,0,0,0,0,0,0,0,0,0,0,0,CC7,0,0,0,0,0,0~
,0,0,0,0,0,0,0,0,0,0,0,0,0)';$S;OUT;
    'UPI1_TX_DP20':'(0,0,0,0,0,0,0,0,0,0,0,0,0,0,0,0,0,0,0,0,0,0,CF6,0,0,0,0,0,0~
,0,0,0,0,0,0,0,0,0,0,0,0,0)';$S;OUT;
    'UPI1_TX_DP19':'(0,0,0,0,0,0,0,0,0,0,0,0,0,0,0,0,0,0,0,0,0,0,CG7,0,0,0,0,0,0~
,0,0,0,0,0,0,0,0,0,0,0,0,0)';$S;OUT;
    'UPI1_TX_DP18':'(0,0,0,0,0,0,0,0,0,0,0,0,0,0,0,0,0,0,0,0,0,0,CK6,0,0,0,0,0,0~
,0,0,0,0,0,0,0,0,0,0,0,0,0)';$S;OUT;
    'UPI1_TX_DP17':'(0,0,0,0,0,0,0,0,0,0,0,0,0,0,0,0,0,0,0,0,0,0,CL7,0,0,0,0,0,0~
,0,0,0,0,0,0,0,0,0,0,0,0,0)';$S;OUT;
    'UPI1_TX_DP16':'(0,0,0,0,0,0,0,0,0,0,0,0,0,0,0,0,0,0,0,0,0,0,CP6,0,0,0,0,0,0~
,0,0,0,0,0,0,0,0,0,0,0,0,0)';$S;OUT;
    'UPI1_TX_DP15':'(0,0,0,0,0,0,0,0,0,0,0,0,0,0,0,0,0,0,0,0,0,0,CR7,0,0,0,0,0,0~
,0,0,0,0,0,0,0,0,0,0,0,0,0)';$S;OUT;
    'UPI1_TX_DP14':'(0,0,0,0,0,0,0,0,0,0,0,0,0,0,0,0,0,0,0,0,0,0,CV6,0,0,0,0,0,0~
,0,0,0,0,0,0,0,0,0,0,0,0,0)';$S;OUT;
    'UPI1_TX_DP13':'(0,0,0,0,0,0,0,0,0,0,0,0,0,0,0,0,0,0,0,0,0,0,CW7,0,0,0,0,0,0~
,0,0,0,0,0,0,0,0,0,0,0,0,0)';$S;OUT;
    'UPI1_TX_DP12':'(0,0,0,0,0,0,0,0,0,0,0,0,0,0,0,0,0,0,0,0,0,0,DB6,0,0,0,0,0,0~
,0,0,0,0,0,0,0,0,0,0,0,0,0)';$S;OUT;
    'UPI1_TX_DP11':'(0,0,0,0,0,0,0,0,0,0,0,0,0,0,0,0,0,0,0,0,0,0,DC7,0,0,0,0,0,0~
,0,0,0,0,0,0,0,0,0,0,0,0,0)';$S;OUT;
    'UPI1_TX_DP10':'(0,0,0,0,0,0,0,0,0,0,0,0,0,0,0,0,0,0,0,0,0,0,DF6,0,0,0,0,0,0~
,0,0,0,0,0,0,0,0,0,0,0,0,0)';$S;OUT;
    'UPI1_TX_DP9':'(0,0,0,0,0,0,0,0,0,0,0,0,0,0,0,0,0,0,0,0,0,0,DG7,0,0,0,0,0,0,~
0,0,0,0,0,0,0,0,0,0,0,0,0)';$S;OUT;
    'UPI1_TX_DP8':'(0,0,0,0,0,0,0,0,0,0,0,0,0,0,0,0,0,0,0,0,0,0,DJ5,0,0,0,0,0,0,~
0,0,0,0,0,0,0,0,0,0,0,0,0)';$S;OUT;
    'UPI1_TX_DP7':'(0,0,0,0,0,0,0,0,0,0,0,0,0,0,0,0,0,0,0,0,0,0,DM6,0,0,0,0,0,0,~
0,0,0,0,0,0,0,0,0,0,0,0,0)';$S;OUT;
    'UPI1_TX_DP6':'(0,0,0,0,0,0,0,0,0,0,0,0,0,0,0,0,0,0,0,0,0,0,DN5,0,0,0,0,0,0,~
0,0,0,0,0,0,0,0,0,0,0,0,0)';$S;OUT;
    'UPI1_TX_DP5':'(0,0,0,0,0,0,0,0,0,0,0,0,0,0,0,0,0,0,0,0,0,0,DR7,0,0,0,0,0,0,~
0,0,0,0,0,0,0,0,0,0,0,0,0)';$S;OUT;
    'UPI1_TX_DP4':'(0,0,0,0,0,0,0,0,0,0,0,0,0,0,0,0,0,0,0,0,0,0,DU5,0,0,0,0,0,0,~
0,0,0,0,0,0,0,0,0,0,0,0,0)';$S;OUT;
    'UPI1_TX_DP3':'(0,0,0,0,0,0,0,0,0,0,0,0,0,0,0,0,0,0,0,0,0,0,DW7,0,0,0,0,0,0,~
0,0,0,0,0,0,0,0,0,0,0,0,0)';$S;OUT;
    'UPI1_TX_DP2':'(0,0,0,0,0,0,0,0,0,0,0,0,0,0,0,0,0,0,0,0,0,0,EA5,0,0,0,0,0,0,~
0,0,0,0,0,0,0,0,0,0,0,0,0)';$S;OUT;
    'UPI1_TX_DP1':'(0,0,0,0,0,0,0,0,0,0,0,0,0,0,0,0,0,0,0,0,0,0,ED6,0,0,0,0,0,0,~
0,0,0,0,0,0,0,0,0,0,0,0,0)';$S;OUT;
    'UPI1_TX_DP0':'(0,0,0,0,0,0,0,0,0,0,0,0,0,0,0,0,0,0,0,0,0,0,EE5,0,0,0,0,0,0,~
0,0,0,0,0,0,0,0,0,0,0,0,0)';$S;OUT;
    'UPI2_RX_DN23':'(0,0,0,0,0,0,0,0,0,0,0,0,0,0,0,0,0,0,0,0,0,0,0,BD73,0,0,0,0,~
0,0,0,0,0,0,0,0,0,0,0,0,0,0)';$S;IN;
    'UPI2_RX_DN22':'(0,0,0,0,0,0,0,0,0,0,0,0,0,0,0,0,0,0,0,0,0,0,0,BK73,0,0,0,0,~
0,0,0,0,0,0,0,0,0,0,0,0,0,0)';$S;IN;
    'UPI2_RX_DN21':'(0,0,0,0,0,0,0,0,0,0,0,0,0,0,0,0,0,0,0,0,0,0,0,BN74,0,0,0,0,~
0,0,0,0,0,0,0,0,0,0,0,0,0,0)';$S;IN;
    'UPI2_RX_DN20':'(0,0,0,0,0,0,0,0,0,0,0,0,0,0,0,0,0,0,0,0,0,0,0,BG74,0,0,0,0,~
0,0,0,0,0,0,0,0,0,0,0,0,0,0)';$S;IN;
    'UPI2_RX_DN19':'(0,0,0,0,0,0,0,0,0,0,0,0,0,0,0,0,0,0,0,0,0,0,0,BL76,0,0,0,0,~
0,0,0,0,0,0,0,0,0,0,0,0,0,0)';$S;IN;
    'UPI2_RX_DN18':'(0,0,0,0,0,0,0,0,0,0,0,0,0,0,0,0,0,0,0,0,0,0,0,BJ76,0,0,0,0,~
0,0,0,0,0,0,0,0,0,0,0,0,0,0)';$S;IN;
    'UPI2_RX_DN17':'(0,0,0,0,0,0,0,0,0,0,0,0,0,0,0,0,0,0,0,0,0,0,0,BH75,0,0,0,0,~
0,0,0,0,0,0,0,0,0,0,0,0,0,0)';$S;IN;
    'UPI2_RX_DN16':'(0,0,0,0,0,0,0,0,0,0,0,0,0,0,0,0,0,0,0,0,0,0,0,AW74,0,0,0,0,~
0,0,0,0,0,0,0,0,0,0,0,0,0,0)';$S;IN;
    'UPI2_RX_DN15':'(0,0,0,0,0,0,0,0,0,0,0,0,0,0,0,0,0,0,0,0,0,0,0,BB75,0,0,0,0,~
0,0,0,0,0,0,0,0,0,0,0,0,0,0)';$S;IN;
    'UPI2_RX_DN14':'(0,0,0,0,0,0,0,0,0,0,0,0,0,0,0,0,0,0,0,0,0,0,0,AY75,0,0,0,0,~
0,0,0,0,0,0,0,0,0,0,0,0,0,0)';$S;IN;
    'UPI2_RX_DN13':'(0,0,0,0,0,0,0,0,0,0,0,0,0,0,0,0,0,0,0,0,0,0,0,AV73,0,0,0,0,~
0,0,0,0,0,0,0,0,0,0,0,0,0,0)';$S;IN;
    'UPI2_RX_DN12':'(0,0,0,0,0,0,0,0,0,0,0,0,0,0,0,0,0,0,0,0,0,0,0,BA72,0,0,0,0,~
0,0,0,0,0,0,0,0,0,0,0,0,0,0)';$S;IN;
    'UPI2_RX_DN11':'(0,0,0,0,0,0,0,0,0,0,0,0,0,0,0,0,0,0,0,0,0,0,0,AG82,0,0,0,0,~
0,0,0,0,0,0,0,0,0,0,0,0,0,0)';$S;IN;
    'UPI2_RX_DN10':'(0,0,0,0,0,0,0,0,0,0,0,0,0,0,0,0,0,0,0,0,0,0,0,AJ80,0,0,0,0,~
0,0,0,0,0,0,0,0,0,0,0,0,0,0)';$S;IN;
    'UPI2_RX_DN9':'(0,0,0,0,0,0,0,0,0,0,0,0,0,0,0,0,0,0,0,0,0,0,0,AE82,0,0,0,0,0~
,0,0,0,0,0,0,0,0,0,0,0,0,0)';$S;IN;
    'UPI2_RX_DN8':'(0,0,0,0,0,0,0,0,0,0,0,0,0,0,0,0,0,0,0,0,0,0,0,AF79,0,0,0,0,0~
,0,0,0,0,0,0,0,0,0,0,0,0,0)';$S;IN;
    'UPI2_RX_DN7':'(0,0,0,0,0,0,0,0,0,0,0,0,0,0,0,0,0,0,0,0,0,0,0,AD81,0,0,0,0,0~
,0,0,0,0,0,0,0,0,0,0,0,0,0)';$S;IN;
    'UPI2_RX_DN6':'(0,0,0,0,0,0,0,0,0,0,0,0,0,0,0,0,0,0,0,0,0,0,0,AC80,0,0,0,0,0~
,0,0,0,0,0,0,0,0,0,0,0,0,0)';$S;IN;
    'UPI2_RX_DN5':'(0,0,0,0,0,0,0,0,0,0,0,0,0,0,0,0,0,0,0,0,0,0,0,L80,0,0,0,0,0,~
0,0,0,0,0,0,0,0,0,0,0,0,0)';$S;IN;
    'UPI2_RX_DN4':'(0,0,0,0,0,0,0,0,0,0,0,0,0,0,0,0,0,0,0,0,0,0,0,J82,0,0,0,0,0,~
0,0,0,0,0,0,0,0,0,0,0,0,0)';$S;IN;
    'UPI2_RX_DN3':'(0,0,0,0,0,0,0,0,0,0,0,0,0,0,0,0,0,0,0,0,0,0,0,K79,0,0,0,0,0,~
0,0,0,0,0,0,0,0,0,0,0,0,0)';$S;IN;
    'UPI2_RX_DN2':'(0,0,0,0,0,0,0,0,0,0,0,0,0,0,0,0,0,0,0,0,0,0,0,G82,0,0,0,0,0,~
0,0,0,0,0,0,0,0,0,0,0,0,0)';$S;IN;
    'UPI2_RX_DN1':'(0,0,0,0,0,0,0,0,0,0,0,0,0,0,0,0,0,0,0,0,0,0,0,F81,0,0,0,0,0,~
0,0,0,0,0,0,0,0,0,0,0,0,0)';$S;IN;
    'UPI2_RX_DN0':'(0,0,0,0,0,0,0,0,0,0,0,0,0,0,0,0,0,0,0,0,0,0,0,E80,0,0,0,0,0,~
0,0,0,0,0,0,0,0,0,0,0,0,0)';$S;IN;
    'UPI2_RX_DP23':'(0,0,0,0,0,0,0,0,0,0,0,0,0,0,0,0,0,0,0,0,0,0,0,BC74,0,0,0,0,~
0,0,0,0,0,0,0,0,0,0,0,0,0,0)';$S;IN;
    'UPI2_RX_DP22':'(0,0,0,0,0,0,0,0,0,0,0,0,0,0,0,0,0,0,0,0,0,0,0,BL74,0,0,0,0,~
0,0,0,0,0,0,0,0,0,0,0,0,0,0)';$S;IN;
    'UPI2_RX_DP21':'(0,0,0,0,0,0,0,0,0,0,0,0,0,0,0,0,0,0,0,0,0,0,0,BM75,0,0,0,0,~
0,0,0,0,0,0,0,0,0,0,0,0,0,0)';$S;IN;
    'UPI2_RX_DP20':'(0,0,0,0,0,0,0,0,0,0,0,0,0,0,0,0,0,0,0,0,0,0,0,BJ74,0,0,0,0,~
0,0,0,0,0,0,0,0,0,0,0,0,0,0)';$S;IN;
    'UPI2_RX_DP19':'(0,0,0,0,0,0,0,0,0,0,0,0,0,0,0,0,0,0,0,0,0,0,0,BN76,0,0,0,0,~
0,0,0,0,0,0,0,0,0,0,0,0,0,0)';$S;IN;
    'UPI2_RX_DP18':'(0,0,0,0,0,0,0,0,0,0,0,0,0,0,0,0,0,0,0,0,0,0,0,BK77,0,0,0,0,~
0,0,0,0,0,0,0,0,0,0,0,0,0,0)';$S;IN;
    'UPI2_RX_DP17':'(0,0,0,0,0,0,0,0,0,0,0,0,0,0,0,0,0,0,0,0,0,0,0,BG76,0,0,0,0,~
0,0,0,0,0,0,0,0,0,0,0,0,0,0)';$S;IN;
    'UPI2_RX_DP16':'(0,0,0,0,0,0,0,0,0,0,0,0,0,0,0,0,0,0,0,0,0,0,0,AV75,0,0,0,0,~
0,0,0,0,0,0,0,0,0,0,0,0,0,0)';$S;IN;
    'UPI2_RX_DP15':'(0,0,0,0,0,0,0,0,0,0,0,0,0,0,0,0,0,0,0,0,0,0,0,BD75,0,0,0,0,~
0,0,0,0,0,0,0,0,0,0,0,0,0,0)';$S;IN;
    'UPI2_RX_DP14':'(0,0,0,0,0,0,0,0,0,0,0,0,0,0,0,0,0,0,0,0,0,0,0,BA76,0,0,0,0,~
0,0,0,0,0,0,0,0,0,0,0,0,0,0)';$S;IN;
    'UPI2_RX_DP13':'(0,0,0,0,0,0,0,0,0,0,0,0,0,0,0,0,0,0,0,0,0,0,0,AY73,0,0,0,0,~
0,0,0,0,0,0,0,0,0,0,0,0,0,0)';$S;IN;
    'UPI2_RX_DP12':'(0,0,0,0,0,0,0,0,0,0,0,0,0,0,0,0,0,0,0,0,0,0,0,BB73,0,0,0,0,~
0,0,0,0,0,0,0,0,0,0,0,0,0,0)';$S;IN;
    'UPI2_RX_DP11':'(0,0,0,0,0,0,0,0,0,0,0,0,0,0,0,0,0,0,0,0,0,0,0,AJ82,0,0,0,0,~
0,0,0,0,0,0,0,0,0,0,0,0,0,0)';$S;IN;
    'UPI2_RX_DP10':'(0,0,0,0,0,0,0,0,0,0,0,0,0,0,0,0,0,0,0,0,0,0,0,AH81,0,0,0,0,~
0,0,0,0,0,0,0,0,0,0,0,0,0,0)';$S;IN;
    'UPI2_RX_DP9':'(0,0,0,0,0,0,0,0,0,0,0,0,0,0,0,0,0,0,0,0,0,0,0,AF83,0,0,0,0,0~
,0,0,0,0,0,0,0,0,0,0,0,0,0)';$S;IN;
    'UPI2_RX_DP8':'(0,0,0,0,0,0,0,0,0,0,0,0,0,0,0,0,0,0,0,0,0,0,0,AG80,0,0,0,0,0~
,0,0,0,0,0,0,0,0,0,0,0,0,0)';$S;IN;
    'UPI2_RX_DP7':'(0,0,0,0,0,0,0,0,0,0,0,0,0,0,0,0,0,0,0,0,0,0,0,AC82,0,0,0,0,0~
,0,0,0,0,0,0,0,0,0,0,0,0,0)';$S;IN;
    'UPI2_RX_DP6':'(0,0,0,0,0,0,0,0,0,0,0,0,0,0,0,0,0,0,0,0,0,0,0,AE80,0,0,0,0,0~
,0,0,0,0,0,0,0,0,0,0,0,0,0)';$S;IN;
    'UPI2_RX_DP5':'(0,0,0,0,0,0,0,0,0,0,0,0,0,0,0,0,0,0,0,0,0,0,0,K81,0,0,0,0,0,~
0,0,0,0,0,0,0,0,0,0,0,0,0)';$S;IN;
    'UPI2_RX_DP4':'(0,0,0,0,0,0,0,0,0,0,0,0,0,0,0,0,0,0,0,0,0,0,0,L82,0,0,0,0,0,~
0,0,0,0,0,0,0,0,0,0,0,0,0)';$S;IN;
    'UPI2_RX_DP3':'(0,0,0,0,0,0,0,0,0,0,0,0,0,0,0,0,0,0,0,0,0,0,0,M79,0,0,0,0,0,~
0,0,0,0,0,0,0,0,0,0,0,0,0)';$S;IN;
    'UPI2_RX_DP2':'(0,0,0,0,0,0,0,0,0,0,0,0,0,0,0,0,0,0,0,0,0,0,0,H83,0,0,0,0,0,~
0,0,0,0,0,0,0,0,0,0,0,0,0)';$S;IN;
    'UPI2_RX_DP1':'(0,0,0,0,0,0,0,0,0,0,0,0,0,0,0,0,0,0,0,0,0,0,0,E82,0,0,0,0,0,~
0,0,0,0,0,0,0,0,0,0,0,0,0)';$S;IN;
    'UPI2_RX_DP0':'(0,0,0,0,0,0,0,0,0,0,0,0,0,0,0,0,0,0,0,0,0,0,0,G80,0,0,0,0,0,~
0,0,0,0,0,0,0,0,0,0,0,0,0)';$S;IN;
    'UPI2_TX_DN23':'(0,0,0,0,0,0,0,0,0,0,0,0,0,0,0,0,0,0,0,0,0,0,0,BM71,0,0,0,0,~
0,0,0,0,0,0,0,0,0,0,0,0,0,0)';$S;OUT;
    'UPI2_TX_DN22':'(0,0,0,0,0,0,0,0,0,0,0,0,0,0,0,0,0,0,0,0,0,0,0,BG80,0,0,0,0,~
0,0,0,0,0,0,0,0,0,0,0,0,0,0)';$S;OUT;
    'UPI2_TX_DN21':'(0,0,0,0,0,0,0,0,0,0,0,0,0,0,0,0,0,0,0,0,0,0,0,BF81,0,0,0,0,~
0,0,0,0,0,0,0,0,0,0,0,0,0,0)';$S;OUT;
    'UPI2_TX_DN20':'(0,0,0,0,0,0,0,0,0,0,0,0,0,0,0,0,0,0,0,0,0,0,0,BD79,0,0,0,0,~
0,0,0,0,0,0,0,0,0,0,0,0,0,0)';$S;OUT;
    'UPI2_TX_DN19':'(0,0,0,0,0,0,0,0,0,0,0,0,0,0,0,0,0,0,0,0,0,0,0,BE82,0,0,0,0,~
0,0,0,0,0,0,0,0,0,0,0,0,0,0)';$S;OUT;
    'UPI2_TX_DN18':'(0,0,0,0,0,0,0,0,0,0,0,0,0,0,0,0,0,0,0,0,0,0,0,BC82,0,0,0,0,~
0,0,0,0,0,0,0,0,0,0,0,0,0,0)';$S;OUT;
    'UPI2_TX_DN17':'(0,0,0,0,0,0,0,0,0,0,0,0,0,0,0,0,0,0,0,0,0,0,0,BA80,0,0,0,0,~
0,0,0,0,0,0,0,0,0,0,0,0,0,0)';$S;OUT;
    'UPI2_TX_DN16':'(0,0,0,0,0,0,0,0,0,0,0,0,0,0,0,0,0,0,0,0,0,0,0,AV81,0,0,0,0,~
0,0,0,0,0,0,0,0,0,0,0,0,0,0)';$S;OUT;
    'UPI2_TX_DN15':'(0,0,0,0,0,0,0,0,0,0,0,0,0,0,0,0,0,0,0,0,0,0,0,AT83,0,0,0,0,~
0,0,0,0,0,0,0,0,0,0,0,0,0,0)';$S;OUT;
    'UPI2_TX_DN14':'(0,0,0,0,0,0,0,0,0,0,0,0,0,0,0,0,0,0,0,0,0,0,0,AR80,0,0,0,0,~
0,0,0,0,0,0,0,0,0,0,0,0,0,0)';$S;OUT;
    'UPI2_TX_DN13':'(0,0,0,0,0,0,0,0,0,0,0,0,0,0,0,0,0,0,0,0,0,0,0,AN82,0,0,0,0,~
0,0,0,0,0,0,0,0,0,0,0,0,0,0)';$S;OUT;
    'UPI2_TX_DN12':'(0,0,0,0,0,0,0,0,0,0,0,0,0,0,0,0,0,0,0,0,0,0,0,AM81,0,0,0,0,~
0,0,0,0,0,0,0,0,0,0,0,0,0,0)';$S;OUT;
    'UPI2_TX_DN11':'(0,0,0,0,0,0,0,0,0,0,0,0,0,0,0,0,0,0,0,0,0,0,0,AU78,0,0,0,0,~
0,0,0,0,0,0,0,0,0,0,0,0,0,0)';$S;OUT;
    'UPI2_TX_DN10':'(0,0,0,0,0,0,0,0,0,0,0,0,0,0,0,0,0,0,0,0,0,0,0,AW78,0,0,0,0,~
0,0,0,0,0,0,0,0,0,0,0,0,0,0)';$S;OUT;
    'UPI2_TX_DN9':'(0,0,0,0,0,0,0,0,0,0,0,0,0,0,0,0,0,0,0,0,0,0,0,Y81,0,0,0,0,0,~
0,0,0,0,0,0,0,0,0,0,0,0,0)';$S;OUT;
    'UPI2_TX_DN8':'(0,0,0,0,0,0,0,0,0,0,0,0,0,0,0,0,0,0,0,0,0,0,0,V83,0,0,0,0,0,~
0,0,0,0,0,0,0,0,0,0,0,0,0)';$S;OUT;
    'UPI2_TX_DN7':'(0,0,0,0,0,0,0,0,0,0,0,0,0,0,0,0,0,0,0,0,0,0,0,U80,0,0,0,0,0,~
0,0,0,0,0,0,0,0,0,0,0,0,0)';$S;OUT;
    'UPI2_TX_DN6':'(0,0,0,0,0,0,0,0,0,0,0,0,0,0,0,0,0,0,0,0,0,0,0,R82,0,0,0,0,0,~
0,0,0,0,0,0,0,0,0,0,0,0,0)';$S;OUT;
    'UPI2_TX_DN5':'(0,0,0,0,0,0,0,0,0,0,0,0,0,0,0,0,0,0,0,0,0,0,0,P81,0,0,0,0,0,~
0,0,0,0,0,0,0,0,0,0,0,0,0)';$S;OUT;
    'UPI2_TX_DN4':'(0,0,0,0,0,0,0,0,0,0,0,0,0,0,0,0,0,0,0,0,0,0,0,H85,0,0,0,0,0,~
0,0,0,0,0,0,0,0,0,0,0,0,0)';$S;OUT;
    'UPI2_TX_DN3':'(0,0,0,0,0,0,0,0,0,0,0,0,0,0,0,0,0,0,0,0,0,0,0,F87,0,0,0,0,0,~
0,0,0,0,0,0,0,0,0,0,0,0,0)';$S;OUT;
    'UPI2_TX_DN2':'(0,0,0,0,0,0,0,0,0,0,0,0,0,0,0,0,0,0,0,0,0,0,0,D87,0,0,0,0,0,~
0,0,0,0,0,0,0,0,0,0,0,0,0)';$S;OUT;
    'UPI2_TX_DN1':'(0,0,0,0,0,0,0,0,0,0,0,0,0,0,0,0,0,0,0,0,0,0,0,E84,0,0,0,0,0,~
0,0,0,0,0,0,0,0,0,0,0,0,0)';$S;OUT;
    'UPI2_TX_DN0':'(0,0,0,0,0,0,0,0,0,0,0,0,0,0,0,0,0,0,0,0,0,0,0,B85,0,0,0,0,0,~
0,0,0,0,0,0,0,0,0,0,0,0,0)';$S;OUT;
    'UPI2_TX_DP23':'(0,0,0,0,0,0,0,0,0,0,0,0,0,0,0,0,0,0,0,0,0,0,0,BN72,0,0,0,0,~
0,0,0,0,0,0,0,0,0,0,0,0,0,0)';$S;OUT;
    'UPI2_TX_DP22':'(0,0,0,0,0,0,0,0,0,0,0,0,0,0,0,0,0,0,0,0,0,0,0,BE80,0,0,0,0,~
0,0,0,0,0,0,0,0,0,0,0,0,0,0)';$S;OUT;
    'UPI2_TX_DP21':'(0,0,0,0,0,0,0,0,0,0,0,0,0,0,0,0,0,0,0,0,0,0,0,BG82,0,0,0,0,~
0,0,0,0,0,0,0,0,0,0,0,0,0,0)';$S;OUT;
    'UPI2_TX_DP20':'(0,0,0,0,0,0,0,0,0,0,0,0,0,0,0,0,0,0,0,0,0,0,0,BC80,0,0,0,0,~
0,0,0,0,0,0,0,0,0,0,0,0,0,0)';$S;OUT;
    'UPI2_TX_DP19':'(0,0,0,0,0,0,0,0,0,0,0,0,0,0,0,0,0,0,0,0,0,0,0,BD83,0,0,0,0,~
0,0,0,0,0,0,0,0,0,0,0,0,0,0)';$S;OUT;
    'UPI2_TX_DP18':'(0,0,0,0,0,0,0,0,0,0,0,0,0,0,0,0,0,0,0,0,0,0,0,BA82,0,0,0,0,~
0,0,0,0,0,0,0,0,0,0,0,0,0,0)';$S;OUT;
    'UPI2_TX_DP17':'(0,0,0,0,0,0,0,0,0,0,0,0,0,0,0,0,0,0,0,0,0,0,0,BB81,0,0,0,0,~
0,0,0,0,0,0,0,0,0,0,0,0,0,0)';$S;OUT;
    'UPI2_TX_DP16':'(0,0,0,0,0,0,0,0,0,0,0,0,0,0,0,0,0,0,0,0,0,0,0,AU82,0,0,0,0,~
0,0,0,0,0,0,0,0,0,0,0,0,0,0)';$S;OUT;
    'UPI2_TX_DP15':'(0,0,0,0,0,0,0,0,0,0,0,0,0,0,0,0,0,0,0,0,0,0,0,AV83,0,0,0,0,~
0,0,0,0,0,0,0,0,0,0,0,0,0,0)';$S;OUT;
    'UPI2_TX_DP14':'(0,0,0,0,0,0,0,0,0,0,0,0,0,0,0,0,0,0,0,0,0,0,0,AT81,0,0,0,0,~
0,0,0,0,0,0,0,0,0,0,0,0,0,0)';$S;OUT;
    'UPI2_TX_DP13':'(0,0,0,0,0,0,0,0,0,0,0,0,0,0,0,0,0,0,0,0,0,0,0,AM83,0,0,0,0,~
0,0,0,0,0,0,0,0,0,0,0,0,0,0)';$S;OUT;
    'UPI2_TX_DP12':'(0,0,0,0,0,0,0,0,0,0,0,0,0,0,0,0,0,0,0,0,0,0,0,AP81,0,0,0,0,~
0,0,0,0,0,0,0,0,0,0,0,0,0,0)';$S;OUT;
    'UPI2_TX_DP11':'(0,0,0,0,0,0,0,0,0,0,0,0,0,0,0,0,0,0,0,0,0,0,0,AV79,0,0,0,0,~
0,0,0,0,0,0,0,0,0,0,0,0,0,0)';$S;OUT;
    'UPI2_TX_DP10':'(0,0,0,0,0,0,0,0,0,0,0,0,0,0,0,0,0,0,0,0,0,0,0,BA78,0,0,0,0,~
0,0,0,0,0,0,0,0,0,0,0,0,0,0)';$S;OUT;
    'UPI2_TX_DP9':'(0,0,0,0,0,0,0,0,0,0,0,0,0,0,0,0,0,0,0,0,0,0,0,W82,0,0,0,0,0,~
0,0,0,0,0,0,0,0,0,0,0,0,0)';$S;OUT;
    'UPI2_TX_DP8':'(0,0,0,0,0,0,0,0,0,0,0,0,0,0,0,0,0,0,0,0,0,0,0,Y83,0,0,0,0,0,~
0,0,0,0,0,0,0,0,0,0,0,0,0)';$S;OUT;
    'UPI2_TX_DP7':'(0,0,0,0,0,0,0,0,0,0,0,0,0,0,0,0,0,0,0,0,0,0,0,V81,0,0,0,0,0,~
0,0,0,0,0,0,0,0,0,0,0,0,0)';$S;OUT;
    'UPI2_TX_DP6':'(0,0,0,0,0,0,0,0,0,0,0,0,0,0,0,0,0,0,0,0,0,0,0,P83,0,0,0,0,0,~
0,0,0,0,0,0,0,0,0,0,0,0,0)';$S;OUT;
    'UPI2_TX_DP5':'(0,0,0,0,0,0,0,0,0,0,0,0,0,0,0,0,0,0,0,0,0,0,0,T81,0,0,0,0,0,~
0,0,0,0,0,0,0,0,0,0,0,0,0)';$S;OUT;
    'UPI2_TX_DP4':'(0,0,0,0,0,0,0,0,0,0,0,0,0,0,0,0,0,0,0,0,0,0,0,G86,0,0,0,0,0,~
0,0,0,0,0,0,0,0,0,0,0,0,0)';$S;OUT;
    'UPI2_TX_DP3':'(0,0,0,0,0,0,0,0,0,0,0,0,0,0,0,0,0,0,0,0,0,0,0,H87,0,0,0,0,0,~
0,0,0,0,0,0,0,0,0,0,0,0,0)';$S;OUT;
    'UPI2_TX_DP2':'(0,0,0,0,0,0,0,0,0,0,0,0,0,0,0,0,0,0,0,0,0,0,0,E88,0,0,0,0,0,~
0,0,0,0,0,0,0,0,0,0,0,0,0)';$S;OUT;
    'UPI2_TX_DP1':'(0,0,0,0,0,0,0,0,0,0,0,0,0,0,0,0,0,0,0,0,0,0,0,F85,0,0,0,0,0,~
0,0,0,0,0,0,0,0,0,0,0,0,0)';$S;OUT;
    'UPI2_TX_DP0':'(0,0,0,0,0,0,0,0,0,0,0,0,0,0,0,0,0,0,0,0,0,0,0,D85,0,0,0,0,0,~
0,0,0,0,0,0,0,0,0,0,0,0,0)';$S;OUT;
    'UPI3_RX_DN23':'(0,0,0,0,0,0,0,0,0,0,0,0,0,0,0,0,0,0,0,0,0,0,0,0,DA78,0,0,0,~
0,0,0,0,0,0,0,0,0,0,0,0,0,0)';$S;IN;
    'UPI3_RX_DN22':'(0,0,0,0,0,0,0,0,0,0,0,0,0,0,0,0,0,0,0,0,0,0,0,0,CT79,0,0,0,~
0,0,0,0,0,0,0,0,0,0,0,0,0,0)';$S;IN;
    'UPI3_RX_DN21':'(0,0,0,0,0,0,0,0,0,0,0,0,0,0,0,0,0,0,0,0,0,0,0,0,CN80,0,0,0,~
0,0,0,0,0,0,0,0,0,0,0,0,0,0)';$S;IN;
    'UPI3_RX_DN20':'(0,0,0,0,0,0,0,0,0,0,0,0,0,0,0,0,0,0,0,0,0,0,0,0,CP81,0,0,0,~
0,0,0,0,0,0,0,0,0,0,0,0,0,0)';$S;IN;
    'UPI3_RX_DN19':'(0,0,0,0,0,0,0,0,0,0,0,0,0,0,0,0,0,0,0,0,0,0,0,0,CW80,0,0,0,~
0,0,0,0,0,0,0,0,0,0,0,0,0,0)';$S;IN;
    'UPI3_RX_DN18':'(0,0,0,0,0,0,0,0,0,0,0,0,0,0,0,0,0,0,0,0,0,0,0,0,CR82,0,0,0,~
0,0,0,0,0,0,0,0,0,0,0,0,0,0)';$S;IN;
    'UPI3_RX_DN17':'(0,0,0,0,0,0,0,0,0,0,0,0,0,0,0,0,0,0,0,0,0,0,0,0,CU82,0,0,0,~
0,0,0,0,0,0,0,0,0,0,0,0,0,0)';$S;IN;
    'UPI3_RX_DN16':'(0,0,0,0,0,0,0,0,0,0,0,0,0,0,0,0,0,0,0,0,0,0,0,0,DF77,0,0,0,~
0,0,0,0,0,0,0,0,0,0,0,0,0,0)';$S;IN;
    'UPI3_RX_DN15':'(0,0,0,0,0,0,0,0,0,0,0,0,0,0,0,0,0,0,0,0,0,0,0,0,DB81,0,0,0,~
0,0,0,0,0,0,0,0,0,0,0,0,0,0)';$S;IN;
    'UPI3_RX_DN14':'(0,0,0,0,0,0,0,0,0,0,0,0,0,0,0,0,0,0,0,0,0,0,0,0,DC82,0,0,0,~
0,0,0,0,0,0,0,0,0,0,0,0,0,0)';$S;IN;
    'UPI3_RX_DN13':'(0,0,0,0,0,0,0,0,0,0,0,0,0,0,0,0,0,0,0,0,0,0,0,0,DE80,0,0,0,~
0,0,0,0,0,0,0,0,0,0,0,0,0,0)';$S;IN;
    'UPI3_RX_DN12':'(0,0,0,0,0,0,0,0,0,0,0,0,0,0,0,0,0,0,0,0,0,0,0,0,DF83,0,0,0,~
0,0,0,0,0,0,0,0,0,0,0,0,0,0)';$S;IN;
    'UPI3_RX_DN11':'(0,0,0,0,0,0,0,0,0,0,0,0,0,0,0,0,0,0,0,0,0,0,0,0,DH81,0,0,0,~
0,0,0,0,0,0,0,0,0,0,0,0,0,0)';$S;IN;
    'UPI3_RX_DN10':'(0,0,0,0,0,0,0,0,0,0,0,0,0,0,0,0,0,0,0,0,0,0,0,0,DG78,0,0,0,~
0,0,0,0,0,0,0,0,0,0,0,0,0,0)';$S;IN;
    'UPI3_RX_DN9':'(0,0,0,0,0,0,0,0,0,0,0,0,0,0,0,0,0,0,0,0,0,0,0,0,DJ78,0,0,0,0~
,0,0,0,0,0,0,0,0,0,0,0,0,0)';$S;IN;
    'UPI3_RX_DN8':'(0,0,0,0,0,0,0,0,0,0,0,0,0,0,0,0,0,0,0,0,0,0,0,0,DY81,0,0,0,0~
,0,0,0,0,0,0,0,0,0,0,0,0,0)';$S;IN;
    'UPI3_RX_DN7':'(0,0,0,0,0,0,0,0,0,0,0,0,0,0,0,0,0,0,0,0,0,0,0,0,EA82,0,0,0,0~
,0,0,0,0,0,0,0,0,0,0,0,0,0)';$S;IN;
    'UPI3_RX_DN6':'(0,0,0,0,0,0,0,0,0,0,0,0,0,0,0,0,0,0,0,0,0,0,0,0,EC80,0,0,0,0~
,0,0,0,0,0,0,0,0,0,0,0,0,0)';$S;IN;
    'UPI3_RX_DN5':'(0,0,0,0,0,0,0,0,0,0,0,0,0,0,0,0,0,0,0,0,0,0,0,0,ED83,0,0,0,0~
,0,0,0,0,0,0,0,0,0,0,0,0,0)';$S;IN;
    'UPI3_RX_DN4':'(0,0,0,0,0,0,0,0,0,0,0,0,0,0,0,0,0,0,0,0,0,0,0,0,EF81,0,0,0,0~
,0,0,0,0,0,0,0,0,0,0,0,0,0)';$S;IN;
    'UPI3_RX_DN3':'(0,0,0,0,0,0,0,0,0,0,0,0,0,0,0,0,0,0,0,0,0,0,0,0,EK81,0,0,0,0~
,0,0,0,0,0,0,0,0,0,0,0,0,0)';$S;IN;
    'UPI3_RX_DN2':'(0,0,0,0,0,0,0,0,0,0,0,0,0,0,0,0,0,0,0,0,0,0,0,0,EL82,0,0,0,0~
,0,0,0,0,0,0,0,0,0,0,0,0,0)';$S;IN;
    'UPI3_RX_DN1':'(0,0,0,0,0,0,0,0,0,0,0,0,0,0,0,0,0,0,0,0,0,0,0,0,EP81,0,0,0,0~
,0,0,0,0,0,0,0,0,0,0,0,0,0)';$S;IN;
    'UPI3_RX_DN0':'(0,0,0,0,0,0,0,0,0,0,0,0,0,0,0,0,0,0,0,0,0,0,0,0,EJ80,0,0,0,0~
,0,0,0,0,0,0,0,0,0,0,0,0,0)';$S;IN;
    'UPI3_RX_DP23':'(0,0,0,0,0,0,0,0,0,0,0,0,0,0,0,0,0,0,0,0,0,0,0,0,DB79,0,0,0,~
0,0,0,0,0,0,0,0,0,0,0,0,0,0)';$S;IN;
    'UPI3_RX_DP22':'(0,0,0,0,0,0,0,0,0,0,0,0,0,0,0,0,0,0,0,0,0,0,0,0,CU80,0,0,0,~
0,0,0,0,0,0,0,0,0,0,0,0,0,0)';$S;IN;
    'UPI3_RX_DP21':'(0,0,0,0,0,0,0,0,0,0,0,0,0,0,0,0,0,0,0,0,0,0,0,0,CR80,0,0,0,~
0,0,0,0,0,0,0,0,0,0,0,0,0,0)';$S;IN;
    'UPI3_RX_DP20':'(0,0,0,0,0,0,0,0,0,0,0,0,0,0,0,0,0,0,0,0,0,0,0,0,CN82,0,0,0,~
0,0,0,0,0,0,0,0,0,0,0,0,0,0)';$S;IN;
    'UPI3_RX_DP19':'(0,0,0,0,0,0,0,0,0,0,0,0,0,0,0,0,0,0,0,0,0,0,0,0,CV81,0,0,0,~
0,0,0,0,0,0,0,0,0,0,0,0,0,0)';$S;IN;
    'UPI3_RX_DP18':'(0,0,0,0,0,0,0,0,0,0,0,0,0,0,0,0,0,0,0,0,0,0,0,0,CT83,0,0,0,~
0,0,0,0,0,0,0,0,0,0,0,0,0,0)';$S;IN;
    'UPI3_RX_DP17':'(0,0,0,0,0,0,0,0,0,0,0,0,0,0,0,0,0,0,0,0,0,0,0,0,CW82,0,0,0,~
0,0,0,0,0,0,0,0,0,0,0,0,0,0)';$S;IN;
    'UPI3_RX_DP16':'(0,0,0,0,0,0,0,0,0,0,0,0,0,0,0,0,0,0,0,0,0,0,0,0,DE78,0,0,0,~
0,0,0,0,0,0,0,0,0,0,0,0,0,0)';$S;IN;
    'UPI3_RX_DP15':'(0,0,0,0,0,0,0,0,0,0,0,0,0,0,0,0,0,0,0,0,0,0,0,0,DD81,0,0,0,~
0,0,0,0,0,0,0,0,0,0,0,0,0,0)';$S;IN;
    'UPI3_RX_DP14':'(0,0,0,0,0,0,0,0,0,0,0,0,0,0,0,0,0,0,0,0,0,0,0,0,DB83,0,0,0,~
0,0,0,0,0,0,0,0,0,0,0,0,0,0)';$S;IN;
    'UPI3_RX_DP13':'(0,0,0,0,0,0,0,0,0,0,0,0,0,0,0,0,0,0,0,0,0,0,0,0,DF81,0,0,0,~
0,0,0,0,0,0,0,0,0,0,0,0,0,0)';$S;IN;
    'UPI3_RX_DP12':'(0,0,0,0,0,0,0,0,0,0,0,0,0,0,0,0,0,0,0,0,0,0,0,0,DH83,0,0,0,~
0,0,0,0,0,0,0,0,0,0,0,0,0,0)';$S;IN;
    'UPI3_RX_DP11':'(0,0,0,0,0,0,0,0,0,0,0,0,0,0,0,0,0,0,0,0,0,0,0,0,DG82,0,0,0,~
0,0,0,0,0,0,0,0,0,0,0,0,0,0)';$S;IN;
    'UPI3_RX_DP10':'(0,0,0,0,0,0,0,0,0,0,0,0,0,0,0,0,0,0,0,0,0,0,0,0,DH79,0,0,0,~
0,0,0,0,0,0,0,0,0,0,0,0,0,0)';$S;IN;
    'UPI3_RX_DP9':'(0,0,0,0,0,0,0,0,0,0,0,0,0,0,0,0,0,0,0,0,0,0,0,0,DL78,0,0,0,0~
,0,0,0,0,0,0,0,0,0,0,0,0,0)';$S;IN;
    'UPI3_RX_DP8':'(0,0,0,0,0,0,0,0,0,0,0,0,0,0,0,0,0,0,0,0,0,0,0,0,EB81,0,0,0,0~
,0,0,0,0,0,0,0,0,0,0,0,0,0)';$S;IN;
    'UPI3_RX_DP7':'(0,0,0,0,0,0,0,0,0,0,0,0,0,0,0,0,0,0,0,0,0,0,0,0,DY83,0,0,0,0~
,0,0,0,0,0,0,0,0,0,0,0,0,0)';$S;IN;
    'UPI3_RX_DP6':'(0,0,0,0,0,0,0,0,0,0,0,0,0,0,0,0,0,0,0,0,0,0,0,0,ED81,0,0,0,0~
,0,0,0,0,0,0,0,0,0,0,0,0,0)';$S;IN;
    'UPI3_RX_DP5':'(0,0,0,0,0,0,0,0,0,0,0,0,0,0,0,0,0,0,0,0,0,0,0,0,EF83,0,0,0,0~
,0,0,0,0,0,0,0,0,0,0,0,0,0)';$S;IN;
    'UPI3_RX_DP4':'(0,0,0,0,0,0,0,0,0,0,0,0,0,0,0,0,0,0,0,0,0,0,0,0,EE82,0,0,0,0~
,0,0,0,0,0,0,0,0,0,0,0,0,0)';$S;IN;
    'UPI3_RX_DP3':'(0,0,0,0,0,0,0,0,0,0,0,0,0,0,0,0,0,0,0,0,0,0,0,0,EJ82,0,0,0,0~
,0,0,0,0,0,0,0,0,0,0,0,0,0)';$S;IN;
    'UPI3_RX_DP2':'(0,0,0,0,0,0,0,0,0,0,0,0,0,0,0,0,0,0,0,0,0,0,0,0,EN82,0,0,0,0~
,0,0,0,0,0,0,0,0,0,0,0,0,0)';$S;IN;
    'UPI3_RX_DP1':'(0,0,0,0,0,0,0,0,0,0,0,0,0,0,0,0,0,0,0,0,0,0,0,0,ER82,0,0,0,0~
,0,0,0,0,0,0,0,0,0,0,0,0,0)';$S;IN;
    'UPI3_RX_DP0':'(0,0,0,0,0,0,0,0,0,0,0,0,0,0,0,0,0,0,0,0,0,0,0,0,EL80,0,0,0,0~
,0,0,0,0,0,0,0,0,0,0,0,0,0)';$S;IN;
    'UPI3_TX_DN23':'(0,0,0,0,0,0,0,0,0,0,0,0,0,0,0,0,0,0,0,0,0,0,0,0,CF73,0,0,0,~
0,0,0,0,0,0,0,0,0,0,0,0,0,0)';$S;OUT;
    'UPI3_TX_DN22':'(0,0,0,0,0,0,0,0,0,0,0,0,0,0,0,0,0,0,0,0,0,0,0,0,CV73,0,0,0,~
0,0,0,0,0,0,0,0,0,0,0,0,0,0)';$S;OUT;
    'UPI3_TX_DN21':'(0,0,0,0,0,0,0,0,0,0,0,0,0,0,0,0,0,0,0,0,0,0,0,0,CJ74,0,0,0,~
0,0,0,0,0,0,0,0,0,0,0,0,0,0)';$S;OUT;
    'UPI3_TX_DN20':'(0,0,0,0,0,0,0,0,0,0,0,0,0,0,0,0,0,0,0,0,0,0,0,0,CF75,0,0,0,~
0,0,0,0,0,0,0,0,0,0,0,0,0,0)';$S;OUT;
    'UPI3_TX_DN19':'(0,0,0,0,0,0,0,0,0,0,0,0,0,0,0,0,0,0,0,0,0,0,0,0,CG76,0,0,0,~
0,0,0,0,0,0,0,0,0,0,0,0,0,0)';$S;OUT;
    'UPI3_TX_DN18':'(0,0,0,0,0,0,0,0,0,0,0,0,0,0,0,0,0,0,0,0,0,0,0,0,CM75,0,0,0,~
0,0,0,0,0,0,0,0,0,0,0,0,0,0)';$S;OUT;
    'UPI3_TX_DN17':'(0,0,0,0,0,0,0,0,0,0,0,0,0,0,0,0,0,0,0,0,0,0,0,0,CH77,0,0,0,~
0,0,0,0,0,0,0,0,0,0,0,0,0,0)';$S;OUT;
    'UPI3_TX_DN16':'(0,0,0,0,0,0,0,0,0,0,0,0,0,0,0,0,0,0,0,0,0,0,0,0,CK77,0,0,0,~
0,0,0,0,0,0,0,0,0,0,0,0,0,0)';$S;OUT;
    'UPI3_TX_DN15':'(0,0,0,0,0,0,0,0,0,0,0,0,0,0,0,0,0,0,0,0,0,0,0,0,CR74,0,0,0,~
0,0,0,0,0,0,0,0,0,0,0,0,0,0)';$S;OUT;
    'UPI3_TX_DN14':'(0,0,0,0,0,0,0,0,0,0,0,0,0,0,0,0,0,0,0,0,0,0,0,0,CT75,0,0,0,~
0,0,0,0,0,0,0,0,0,0,0,0,0,0)';$S;OUT;
    'UPI3_TX_DN13':'(0,0,0,0,0,0,0,0,0,0,0,0,0,0,0,0,0,0,0,0,0,0,0,0,CU76,0,0,0,~
0,0,0,0,0,0,0,0,0,0,0,0,0,0)';$S;OUT;
    'UPI3_TX_DN12':'(0,0,0,0,0,0,0,0,0,0,0,0,0,0,0,0,0,0,0,0,0,0,0,0,CW76,0,0,0,~
0,0,0,0,0,0,0,0,0,0,0,0,0,0)';$S;OUT;
    'UPI3_TX_DN11':'(0,0,0,0,0,0,0,0,0,0,0,0,0,0,0,0,0,0,0,0,0,0,0,0,DL80,0,0,0,~
0,0,0,0,0,0,0,0,0,0,0,0,0,0)';$S;OUT;
    'UPI3_TX_DN10':'(0,0,0,0,0,0,0,0,0,0,0,0,0,0,0,0,0,0,0,0,0,0,0,0,DM81,0,0,0,~
0,0,0,0,0,0,0,0,0,0,0,0,0,0)';$S;OUT;
    'UPI3_TX_DN9':'(0,0,0,0,0,0,0,0,0,0,0,0,0,0,0,0,0,0,0,0,0,0,0,0,DN82,0,0,0,0~
,0,0,0,0,0,0,0,0,0,0,0,0,0)';$S;OUT;
    'UPI3_TX_DN8':'(0,0,0,0,0,0,0,0,0,0,0,0,0,0,0,0,0,0,0,0,0,0,0,0,DP79,0,0,0,0~
,0,0,0,0,0,0,0,0,0,0,0,0,0)';$S;OUT;
    'UPI3_TX_DN7':'(0,0,0,0,0,0,0,0,0,0,0,0,0,0,0,0,0,0,0,0,0,0,0,0,DR82,0,0,0,0~
,0,0,0,0,0,0,0,0,0,0,0,0,0)';$S;OUT;
    'UPI3_TX_DN6':'(0,0,0,0,0,0,0,0,0,0,0,0,0,0,0,0,0,0,0,0,0,0,0,0,DU80,0,0,0,0~
,0,0,0,0,0,0,0,0,0,0,0,0,0)';$S;OUT;
    'UPI3_TX_DN5':'(0,0,0,0,0,0,0,0,0,0,0,0,0,0,0,0,0,0,0,0,0,0,0,0,EK87,0,0,0,0~
,0,0,0,0,0,0,0,0,0,0,0,0,0)';$S;OUT;
    'UPI3_TX_DN4':'(0,0,0,0,0,0,0,0,0,0,0,0,0,0,0,0,0,0,0,0,0,0,0,0,EJ86,0,0,0,0~
,0,0,0,0,0,0,0,0,0,0,0,0,0)';$S;OUT;
    'UPI3_TX_DN3':'(0,0,0,0,0,0,0,0,0,0,0,0,0,0,0,0,0,0,0,0,0,0,0,0,EM87,0,0,0,0~
,0,0,0,0,0,0,0,0,0,0,0,0,0)';$S;OUT;
    'UPI3_TX_DN2':'(0,0,0,0,0,0,0,0,0,0,0,0,0,0,0,0,0,0,0,0,0,0,0,0,EP85,0,0,0,0~
,0,0,0,0,0,0,0,0,0,0,0,0,0)';$S;OUT;
    'UPI3_TX_DN1':'(0,0,0,0,0,0,0,0,0,0,0,0,0,0,0,0,0,0,0,0,0,0,0,0,EL84,0,0,0,0~
,0,0,0,0,0,0,0,0,0,0,0,0,0)';$S;OUT;
    'UPI3_TX_DN0':'(0,0,0,0,0,0,0,0,0,0,0,0,0,0,0,0,0,0,0,0,0,0,0,0,EH85,0,0,0,0~
,0,0,0,0,0,0,0,0,0,0,0,0,0)';$S;OUT;
    'UPI3_TX_DP23':'(0,0,0,0,0,0,0,0,0,0,0,0,0,0,0,0,0,0,0,0,0,0,0,0,CD73,0,0,0,~
0,0,0,0,0,0,0,0,0,0,0,0,0,0)';$S;OUT;
    'UPI3_TX_DP22':'(0,0,0,0,0,0,0,0,0,0,0,0,0,0,0,0,0,0,0,0,0,0,0,0,CW74,0,0,0,~
0,0,0,0,0,0,0,0,0,0,0,0,0,0)';$S;OUT;
    'UPI3_TX_DP21':'(0,0,0,0,0,0,0,0,0,0,0,0,0,0,0,0,0,0,0,0,0,0,0,0,CK75,0,0,0,~
0,0,0,0,0,0,0,0,0,0,0,0,0,0)';$S;OUT;
    'UPI3_TX_DP20':'(0,0,0,0,0,0,0,0,0,0,0,0,0,0,0,0,0,0,0,0,0,0,0,0,CH75,0,0,0,~
0,0,0,0,0,0,0,0,0,0,0,0,0,0)';$S;OUT;
    'UPI3_TX_DP19':'(0,0,0,0,0,0,0,0,0,0,0,0,0,0,0,0,0,0,0,0,0,0,0,0,CF77,0,0,0,~
0,0,0,0,0,0,0,0,0,0,0,0,0,0)';$S;OUT;
    'UPI3_TX_DP18':'(0,0,0,0,0,0,0,0,0,0,0,0,0,0,0,0,0,0,0,0,0,0,0,0,CL76,0,0,0,~
0,0,0,0,0,0,0,0,0,0,0,0,0,0)';$S;OUT;
    'UPI3_TX_DP17':'(0,0,0,0,0,0,0,0,0,0,0,0,0,0,0,0,0,0,0,0,0,0,0,0,CJ78,0,0,0,~
0,0,0,0,0,0,0,0,0,0,0,0,0,0)';$S;OUT;
    'UPI3_TX_DP16':'(0,0,0,0,0,0,0,0,0,0,0,0,0,0,0,0,0,0,0,0,0,0,0,0,CM77,0,0,0,~
0,0,0,0,0,0,0,0,0,0,0,0,0,0)';$S;OUT;
    'UPI3_TX_DP15':'(0,0,0,0,0,0,0,0,0,0,0,0,0,0,0,0,0,0,0,0,0,0,0,0,CU74,0,0,0,~
0,0,0,0,0,0,0,0,0,0,0,0,0,0)';$S;OUT;
    'UPI3_TX_DP14':'(0,0,0,0,0,0,0,0,0,0,0,0,0,0,0,0,0,0,0,0,0,0,0,0,CR76,0,0,0,~
0,0,0,0,0,0,0,0,0,0,0,0,0,0)';$S;OUT;
    'UPI3_TX_DP13':'(0,0,0,0,0,0,0,0,0,0,0,0,0,0,0,0,0,0,0,0,0,0,0,0,CV77,0,0,0,~
0,0,0,0,0,0,0,0,0,0,0,0,0,0)';$S;OUT;
    'UPI3_TX_DP12':'(0,0,0,0,0,0,0,0,0,0,0,0,0,0,0,0,0,0,0,0,0,0,0,0,DA76,0,0,0,~
0,0,0,0,0,0,0,0,0,0,0,0,0,0)';$S;OUT;
    'UPI3_TX_DP11':'(0,0,0,0,0,0,0,0,0,0,0,0,0,0,0,0,0,0,0,0,0,0,0,0,DN80,0,0,0,~
0,0,0,0,0,0,0,0,0,0,0,0,0,0)';$S;OUT;
    'UPI3_TX_DP10':'(0,0,0,0,0,0,0,0,0,0,0,0,0,0,0,0,0,0,0,0,0,0,0,0,DL82,0,0,0,~
0,0,0,0,0,0,0,0,0,0,0,0,0,0)';$S;OUT;
    'UPI3_TX_DP9':'(0,0,0,0,0,0,0,0,0,0,0,0,0,0,0,0,0,0,0,0,0,0,0,0,DP83,0,0,0,0~
,0,0,0,0,0,0,0,0,0,0,0,0,0)';$S;OUT;
    'UPI3_TX_DP8':'(0,0,0,0,0,0,0,0,0,0,0,0,0,0,0,0,0,0,0,0,0,0,0,0,DR80,0,0,0,0~
,0,0,0,0,0,0,0,0,0,0,0,0,0)';$S;OUT;
    'UPI3_TX_DP7':'(0,0,0,0,0,0,0,0,0,0,0,0,0,0,0,0,0,0,0,0,0,0,0,0,DU82,0,0,0,0~
,0,0,0,0,0,0,0,0,0,0,0,0,0)';$S;OUT;
    'UPI3_TX_DP6':'(0,0,0,0,0,0,0,0,0,0,0,0,0,0,0,0,0,0,0,0,0,0,0,0,DT81,0,0,0,0~
,0,0,0,0,0,0,0,0,0,0,0,0,0)';$S;OUT;
    'UPI3_TX_DP5':'(0,0,0,0,0,0,0,0,0,0,0,0,0,0,0,0,0,0,0,0,0,0,0,0,EL88,0,0,0,0~
,0,0,0,0,0,0,0,0,0,0,0,0,0)';$S;OUT;
    'UPI3_TX_DP4':'(0,0,0,0,0,0,0,0,0,0,0,0,0,0,0,0,0,0,0,0,0,0,0,0,EH87,0,0,0,0~
,0,0,0,0,0,0,0,0,0,0,0,0,0)';$S;OUT;
    'UPI3_TX_DP3':'(0,0,0,0,0,0,0,0,0,0,0,0,0,0,0,0,0,0,0,0,0,0,0,0,EP87,0,0,0,0~
,0,0,0,0,0,0,0,0,0,0,0,0,0)';$S;OUT;
    'UPI3_TX_DP2':'(0,0,0,0,0,0,0,0,0,0,0,0,0,0,0,0,0,0,0,0,0,0,0,0,EN86,0,0,0,0~
,0,0,0,0,0,0,0,0,0,0,0,0,0)';$S;OUT;
    'UPI3_TX_DP1':'(0,0,0,0,0,0,0,0,0,0,0,0,0,0,0,0,0,0,0,0,0,0,0,0,EM85,0,0,0,0~
,0,0,0,0,0,0,0,0,0,0,0,0,0)';$S;OUT;
    'UPI3_TX_DP0':'(0,0,0,0,0,0,0,0,0,0,0,0,0,0,0,0,0,0,0,0,0,0,0,0,EK85,0,0,0,0~
,0,0,0,0,0,0,0,0,0,0,0,0,0)';$S;OUT;
    'VCCIN339':'(0,0,0,0,0,0,0,0,0,0,0,0,0,0,0,0,0,0,0,0,0,0,0,0,0,CM89,0,0,0,0,~
0,0,0,0,0,0,0,0,0,0,0,0)';$S;
    'VCCIN338':'(0,0,0,0,0,0,0,0,0,0,0,0,0,0,0,0,0,0,0,0,0,0,0,0,0,CP89,0,0,0,0,~
0,0,0,0,0,0,0,0,0,0,0,0)';$S;
    'VCCIN337':'(0,0,0,0,0,0,0,0,0,0,0,0,0,0,0,0,0,0,0,0,0,0,0,0,0,CN90,0,0,0,0,~
0,0,0,0,0,0,0,0,0,0,0,0)';$S;
    'VCCIN336':'(0,0,0,0,0,0,0,0,0,0,0,0,0,0,0,0,0,0,0,0,0,0,0,0,0,CN88,0,0,0,0,~
0,0,0,0,0,0,0,0,0,0,0,0)';$S;
    'VCCIN335':'(0,0,0,0,0,0,0,0,0,0,0,0,0,0,0,0,0,0,0,0,0,0,0,0,0,CM91,0,0,0,0,~
0,0,0,0,0,0,0,0,0,0,0,0)';$S;
    'VCCIN334':'(0,0,0,0,0,0,0,0,0,0,0,0,0,0,0,0,0,0,0,0,0,0,0,0,0,CM87,0,0,0,0,~
0,0,0,0,0,0,0,0,0,0,0,0)';$S;
    'VCCIN333':'(0,0,0,0,0,0,0,0,0,0,0,0,0,0,0,0,0,0,0,0,0,0,0,0,0,CL90,0,0,0,0,~
0,0,0,0,0,0,0,0,0,0,0,0)';$S;
    'VCCIN332':'(0,0,0,0,0,0,0,0,0,0,0,0,0,0,0,0,0,0,0,0,0,0,0,0,0,CL88,0,0,0,0,~
0,0,0,0,0,0,0,0,0,0,0,0)';$S;
    'VCCIN331':'(0,0,0,0,0,0,0,0,0,0,0,0,0,0,0,0,0,0,0,0,0,0,0,0,0,CL86,0,0,0,0,~
0,0,0,0,0,0,0,0,0,0,0,0)';$S;
    'VCCIN330':'(0,0,0,0,0,0,0,0,0,0,0,0,0,0,0,0,0,0,0,0,0,0,0,0,0,CL84,0,0,0,0,~
0,0,0,0,0,0,0,0,0,0,0,0)';$S;
    'VCCIN329':'(0,0,0,0,0,0,0,0,0,0,0,0,0,0,0,0,0,0,0,0,0,0,0,0,0,CK91,0,0,0,0,~
0,0,0,0,0,0,0,0,0,0,0,0)';$S;
    'VCCIN328':'(0,0,0,0,0,0,0,0,0,0,0,0,0,0,0,0,0,0,0,0,0,0,0,0,0,CK89,0,0,0,0,~
0,0,0,0,0,0,0,0,0,0,0,0)';$S;
    'VCCIN327':'(0,0,0,0,0,0,0,0,0,0,0,0,0,0,0,0,0,0,0,0,0,0,0,0,0,CK87,0,0,0,0,~
0,0,0,0,0,0,0,0,0,0,0,0)';$S;
    'VCCIN326':'(0,0,0,0,0,0,0,0,0,0,0,0,0,0,0,0,0,0,0,0,0,0,0,0,0,CK85,0,0,0,0,~
0,0,0,0,0,0,0,0,0,0,0,0)';$S;
    'VCCIN325':'(0,0,0,0,0,0,0,0,0,0,0,0,0,0,0,0,0,0,0,0,0,0,0,0,0,CK83,0,0,0,0,~
0,0,0,0,0,0,0,0,0,0,0,0)';$S;
    'VCCIN324':'(0,0,0,0,0,0,0,0,0,0,0,0,0,0,0,0,0,0,0,0,0,0,0,0,0,CJ90,0,0,0,0,~
0,0,0,0,0,0,0,0,0,0,0,0)';$S;
    'VCCIN323':'(0,0,0,0,0,0,0,0,0,0,0,0,0,0,0,0,0,0,0,0,0,0,0,0,0,CJ88,0,0,0,0,~
0,0,0,0,0,0,0,0,0,0,0,0)';$S;
    'VCCIN322':'(0,0,0,0,0,0,0,0,0,0,0,0,0,0,0,0,0,0,0,0,0,0,0,0,0,CJ86,0,0,0,0,~
0,0,0,0,0,0,0,0,0,0,0,0)';$S;
    'VCCIN321':'(0,0,0,0,0,0,0,0,0,0,0,0,0,0,0,0,0,0,0,0,0,0,0,0,0,CJ84,0,0,0,0,~
0,0,0,0,0,0,0,0,0,0,0,0)';$S;
    'VCCIN320':'(0,0,0,0,0,0,0,0,0,0,0,0,0,0,0,0,0,0,0,0,0,0,0,0,0,CJ82,0,0,0,0,~
0,0,0,0,0,0,0,0,0,0,0,0)';$S;
    'VCCIN319':'(0,0,0,0,0,0,0,0,0,0,0,0,0,0,0,0,0,0,0,0,0,0,0,0,0,CH91,0,0,0,0,~
0,0,0,0,0,0,0,0,0,0,0,0)';$S;
    'VCCIN318':'(0,0,0,0,0,0,0,0,0,0,0,0,0,0,0,0,0,0,0,0,0,0,0,0,0,CH81,0,0,0,0,~
0,0,0,0,0,0,0,0,0,0,0,0)';$S;
    'VCCIN317':'(0,0,0,0,0,0,0,0,0,0,0,0,0,0,0,0,0,0,0,0,0,0,0,0,0,CG90,0,0,0,0,~
0,0,0,0,0,0,0,0,0,0,0,0)';$S;
    'VCCIN316':'(0,0,0,0,0,0,0,0,0,0,0,0,0,0,0,0,0,0,0,0,0,0,0,0,0,CG88,0,0,0,0,~
0,0,0,0,0,0,0,0,0,0,0,0)';$S;
    'VCCIN315':'(0,0,0,0,0,0,0,0,0,0,0,0,0,0,0,0,0,0,0,0,0,0,0,0,0,CG86,0,0,0,0,~
0,0,0,0,0,0,0,0,0,0,0,0)';$S;
    'VCCIN314':'(0,0,0,0,0,0,0,0,0,0,0,0,0,0,0,0,0,0,0,0,0,0,0,0,0,CG84,0,0,0,0,~
0,0,0,0,0,0,0,0,0,0,0,0)';$S;
    'VCCIN313':'(0,0,0,0,0,0,0,0,0,0,0,0,0,0,0,0,0,0,0,0,0,0,0,0,0,CG82,0,0,0,0,~
0,0,0,0,0,0,0,0,0,0,0,0)';$S;
    'VCCIN312':'(0,0,0,0,0,0,0,0,0,0,0,0,0,0,0,0,0,0,0,0,0,0,0,0,0,CG80,0,0,0,0,~
0,0,0,0,0,0,0,0,0,0,0,0)';$S;
    'VCCIN311':'(0,0,0,0,0,0,0,0,0,0,0,0,0,0,0,0,0,0,0,0,0,0,0,0,0,CF91,0,0,0,0,~
0,0,0,0,0,0,0,0,0,0,0,0)';$S;
    'VCCIN310':'(0,0,0,0,0,0,0,0,0,0,0,0,0,0,0,0,0,0,0,0,0,0,0,0,0,CF89,0,0,0,0,~
0,0,0,0,0,0,0,0,0,0,0,0)';$S;
    'VCCIN309':'(0,0,0,0,0,0,0,0,0,0,0,0,0,0,0,0,0,0,0,0,0,0,0,0,0,CF87,0,0,0,0,~
0,0,0,0,0,0,0,0,0,0,0,0)';$S;
    'VCCIN308':'(0,0,0,0,0,0,0,0,0,0,0,0,0,0,0,0,0,0,0,0,0,0,0,0,0,CF85,0,0,0,0,~
0,0,0,0,0,0,0,0,0,0,0,0)';$S;
    'VCCIN307':'(0,0,0,0,0,0,0,0,0,0,0,0,0,0,0,0,0,0,0,0,0,0,0,0,0,CF83,0,0,0,0,~
0,0,0,0,0,0,0,0,0,0,0,0)';$S;
    'VCCIN306':'(0,0,0,0,0,0,0,0,0,0,0,0,0,0,0,0,0,0,0,0,0,0,0,0,0,CF81,0,0,0,0,~
0,0,0,0,0,0,0,0,0,0,0,0)';$S;
    'VCCIN305':'(0,0,0,0,0,0,0,0,0,0,0,0,0,0,0,0,0,0,0,0,0,0,0,0,0,CF79,0,0,0,0,~
0,0,0,0,0,0,0,0,0,0,0,0)';$S;
    'VCCIN304':'(0,0,0,0,0,0,0,0,0,0,0,0,0,0,0,0,0,0,0,0,0,0,0,0,0,CE90,0,0,0,0,~
0,0,0,0,0,0,0,0,0,0,0,0)';$S;
    'VCCIN303':'(0,0,0,0,0,0,0,0,0,0,0,0,0,0,0,0,0,0,0,0,0,0,0,0,0,CE88,0,0,0,0,~
0,0,0,0,0,0,0,0,0,0,0,0)';$S;
    'VCCIN302':'(0,0,0,0,0,0,0,0,0,0,0,0,0,0,0,0,0,0,0,0,0,0,0,0,0,CE86,0,0,0,0,~
0,0,0,0,0,0,0,0,0,0,0,0)';$S;
    'VCCIN301':'(0,0,0,0,0,0,0,0,0,0,0,0,0,0,0,0,0,0,0,0,0,0,0,0,0,CE84,0,0,0,0,~
0,0,0,0,0,0,0,0,0,0,0,0)';$S;
    'VCCIN300':'(0,0,0,0,0,0,0,0,0,0,0,0,0,0,0,0,0,0,0,0,0,0,0,0,0,CE82,0,0,0,0,~
0,0,0,0,0,0,0,0,0,0,0,0)';$S;
    'VCCIN299':'(0,0,0,0,0,0,0,0,0,0,0,0,0,0,0,0,0,0,0,0,0,0,0,0,0,CE80,0,0,0,0,~
0,0,0,0,0,0,0,0,0,0,0,0)';$S;
    'VCCIN298':'(0,0,0,0,0,0,0,0,0,0,0,0,0,0,0,0,0,0,0,0,0,0,0,0,0,CD89,0,0,0,0,~
0,0,0,0,0,0,0,0,0,0,0,0)';$S;
    'VCCIN297':'(0,0,0,0,0,0,0,0,0,0,0,0,0,0,0,0,0,0,0,0,0,0,0,0,0,CD87,0,0,0,0,~
0,0,0,0,0,0,0,0,0,0,0,0)';$S;
    'VCCIN296':'(0,0,0,0,0,0,0,0,0,0,0,0,0,0,0,0,0,0,0,0,0,0,0,0,0,CD85,0,0,0,0,~
0,0,0,0,0,0,0,0,0,0,0,0)';$S;
    'VCCIN295':'(0,0,0,0,0,0,0,0,0,0,0,0,0,0,0,0,0,0,0,0,0,0,0,0,0,CD83,0,0,0,0,~
0,0,0,0,0,0,0,0,0,0,0,0)';$S;
    'VCCIN294':'(0,0,0,0,0,0,0,0,0,0,0,0,0,0,0,0,0,0,0,0,0,0,0,0,0,CD81,0,0,0,0,~
0,0,0,0,0,0,0,0,0,0,0,0)';$S;
    'VCCIN293':'(0,0,0,0,0,0,0,0,0,0,0,0,0,0,0,0,0,0,0,0,0,0,0,0,0,CD79,0,0,0,0,~
0,0,0,0,0,0,0,0,0,0,0,0)';$S;
    'VCCIN292':'(0,0,0,0,0,0,0,0,0,0,0,0,0,0,0,0,0,0,0,0,0,0,0,0,0,CD59,0,0,0,0,~
0,0,0,0,0,0,0,0,0,0,0,0)';$S;
    'VCCIN291':'(0,0,0,0,0,0,0,0,0,0,0,0,0,0,0,0,0,0,0,0,0,0,0,0,0,CD57,0,0,0,0,~
0,0,0,0,0,0,0,0,0,0,0,0)';$S;
    'VCCIN290':'(0,0,0,0,0,0,0,0,0,0,0,0,0,0,0,0,0,0,0,0,0,0,0,0,0,CD55,0,0,0,0,~
0,0,0,0,0,0,0,0,0,0,0,0)';$S;
    'VCCIN289':'(0,0,0,0,0,0,0,0,0,0,0,0,0,0,0,0,0,0,0,0,0,0,0,0,0,CD53,0,0,0,0,~
0,0,0,0,0,0,0,0,0,0,0,0)';$S;
    'VCCIN288':'(0,0,0,0,0,0,0,0,0,0,0,0,0,0,0,0,0,0,0,0,0,0,0,0,0,CD51,0,0,0,0,~
0,0,0,0,0,0,0,0,0,0,0,0)';$S;
    'VCCIN287':'(0,0,0,0,0,0,0,0,0,0,0,0,0,0,0,0,0,0,0,0,0,0,0,0,0,CD49,0,0,0,0,~
0,0,0,0,0,0,0,0,0,0,0,0)';$S;
    'VCCIN286':'(0,0,0,0,0,0,0,0,0,0,0,0,0,0,0,0,0,0,0,0,0,0,0,0,0,CD47,0,0,0,0,~
0,0,0,0,0,0,0,0,0,0,0,0)';$S;
    'VCCIN285':'(0,0,0,0,0,0,0,0,0,0,0,0,0,0,0,0,0,0,0,0,0,0,0,0,0,CD44,0,0,0,0,~
0,0,0,0,0,0,0,0,0,0,0,0)';$S;
    'VCCIN284':'(0,0,0,0,0,0,0,0,0,0,0,0,0,0,0,0,0,0,0,0,0,0,0,0,0,CD42,0,0,0,0,~
0,0,0,0,0,0,0,0,0,0,0,0)';$S;
    'VCCIN283':'(0,0,0,0,0,0,0,0,0,0,0,0,0,0,0,0,0,0,0,0,0,0,0,0,0,CD40,0,0,0,0,~
0,0,0,0,0,0,0,0,0,0,0,0)';$S;
    'VCCIN282':'(0,0,0,0,0,0,0,0,0,0,0,0,0,0,0,0,0,0,0,0,0,0,0,0,0,CD38,0,0,0,0,~
0,0,0,0,0,0,0,0,0,0,0,0)';$S;
    'VCCIN281':'(0,0,0,0,0,0,0,0,0,0,0,0,0,0,0,0,0,0,0,0,0,0,0,0,0,CD36,0,0,0,0,~
0,0,0,0,0,0,0,0,0,0,0,0)';$S;
    'VCCIN280':'(0,0,0,0,0,0,0,0,0,0,0,0,0,0,0,0,0,0,0,0,0,0,0,0,0,CD34,0,0,0,0,~
0,0,0,0,0,0,0,0,0,0,0,0)';$S;
    'VCCIN279':'(0,0,0,0,0,0,0,0,0,0,0,0,0,0,0,0,0,0,0,0,0,0,0,0,0,CD32,0,0,0,0,~
0,0,0,0,0,0,0,0,0,0,0,0)';$S;
    'VCCIN278':'(0,0,0,0,0,0,0,0,0,0,0,0,0,0,0,0,0,0,0,0,0,0,0,0,0,CC90,0,0,0,0,~
0,0,0,0,0,0,0,0,0,0,0,0)';$S;
    'VCCIN277':'(0,0,0,0,0,0,0,0,0,0,0,0,0,0,0,0,0,0,0,0,0,0,0,0,0,CC88,0,0,0,0,~
0,0,0,0,0,0,0,0,0,0,0,0)';$S;
    'VCCIN276':'(0,0,0,0,0,0,0,0,0,0,0,0,0,0,0,0,0,0,0,0,0,0,0,0,0,CC86,0,0,0,0,~
0,0,0,0,0,0,0,0,0,0,0,0)';$S;
    'VCCIN275':'(0,0,0,0,0,0,0,0,0,0,0,0,0,0,0,0,0,0,0,0,0,0,0,0,0,CC84,0,0,0,0,~
0,0,0,0,0,0,0,0,0,0,0,0)';$S;
    'VCCIN274':'(0,0,0,0,0,0,0,0,0,0,0,0,0,0,0,0,0,0,0,0,0,0,0,0,0,CC82,0,0,0,0,~
0,0,0,0,0,0,0,0,0,0,0,0)';$S;
    'VCCIN273':'(0,0,0,0,0,0,0,0,0,0,0,0,0,0,0,0,0,0,0,0,0,0,0,0,0,CC80,0,0,0,0,~
0,0,0,0,0,0,0,0,0,0,0,0)';$S;
    'VCCIN272':'(0,0,0,0,0,0,0,0,0,0,0,0,0,0,0,0,0,0,0,0,0,0,0,0,0,CC78,0,0,0,0,~
0,0,0,0,0,0,0,0,0,0,0,0)';$S;
    'VCCIN271':'(0,0,0,0,0,0,0,0,0,0,0,0,0,0,0,0,0,0,0,0,0,0,0,0,0,CC76,0,0,0,0,~
0,0,0,0,0,0,0,0,0,0,0,0)';$S;
    'VCCIN270':'(0,0,0,0,0,0,0,0,0,0,0,0,0,0,0,0,0,0,0,0,0,0,0,0,0,CC60,0,0,0,0,~
0,0,0,0,0,0,0,0,0,0,0,0)';$S;
    'VCCIN269':'(0,0,0,0,0,0,0,0,0,0,0,0,0,0,0,0,0,0,0,0,0,0,0,0,0,CC58,0,0,0,0,~
0,0,0,0,0,0,0,0,0,0,0,0)';$S;
    'VCCIN268':'(0,0,0,0,0,0,0,0,0,0,0,0,0,0,0,0,0,0,0,0,0,0,0,0,0,CC56,0,0,0,0,~
0,0,0,0,0,0,0,0,0,0,0,0)';$S;
    'VCCIN267':'(0,0,0,0,0,0,0,0,0,0,0,0,0,0,0,0,0,0,0,0,0,0,0,0,0,CC54,0,0,0,0,~
0,0,0,0,0,0,0,0,0,0,0,0)';$S;
    'VCCIN266':'(0,0,0,0,0,0,0,0,0,0,0,0,0,0,0,0,0,0,0,0,0,0,0,0,0,CC52,0,0,0,0,~
0,0,0,0,0,0,0,0,0,0,0,0)';$S;
    'VCCIN265':'(0,0,0,0,0,0,0,0,0,0,0,0,0,0,0,0,0,0,0,0,0,0,0,0,0,CC50,0,0,0,0,~
0,0,0,0,0,0,0,0,0,0,0,0)';$S;
    'VCCIN264':'(0,0,0,0,0,0,0,0,0,0,0,0,0,0,0,0,0,0,0,0,0,0,0,0,0,CC48,0,0,0,0,~
0,0,0,0,0,0,0,0,0,0,0,0)';$S;
    'VCCIN263':'(0,0,0,0,0,0,0,0,0,0,0,0,0,0,0,0,0,0,0,0,0,0,0,0,0,CC45,0,0,0,0,~
0,0,0,0,0,0,0,0,0,0,0,0)';$S;
    'VCCIN262':'(0,0,0,0,0,0,0,0,0,0,0,0,0,0,0,0,0,0,0,0,0,0,0,0,0,CC43,0,0,0,0,~
0,0,0,0,0,0,0,0,0,0,0,0)';$S;
    'VCCIN261':'(0,0,0,0,0,0,0,0,0,0,0,0,0,0,0,0,0,0,0,0,0,0,0,0,0,CC41,0,0,0,0,~
0,0,0,0,0,0,0,0,0,0,0,0)';$S;
    'VCCIN260':'(0,0,0,0,0,0,0,0,0,0,0,0,0,0,0,0,0,0,0,0,0,0,0,0,0,CC39,0,0,0,0,~
0,0,0,0,0,0,0,0,0,0,0,0)';$S;
    'VCCIN259':'(0,0,0,0,0,0,0,0,0,0,0,0,0,0,0,0,0,0,0,0,0,0,0,0,0,CC37,0,0,0,0,~
0,0,0,0,0,0,0,0,0,0,0,0)';$S;
    'VCCIN258':'(0,0,0,0,0,0,0,0,0,0,0,0,0,0,0,0,0,0,0,0,0,0,0,0,0,CC35,0,0,0,0,~
0,0,0,0,0,0,0,0,0,0,0,0)';$S;
    'VCCIN257':'(0,0,0,0,0,0,0,0,0,0,0,0,0,0,0,0,0,0,0,0,0,0,0,0,0,CC33,0,0,0,0,~
0,0,0,0,0,0,0,0,0,0,0,0)';$S;
    'VCCIN256':'(0,0,0,0,0,0,0,0,0,0,0,0,0,0,0,0,0,0,0,0,0,0,0,0,0,CB77,0,0,0,0,~
0,0,0,0,0,0,0,0,0,0,0,0)';$S;
    'VCCIN255':'(0,0,0,0,0,0,0,0,0,0,0,0,0,0,0,0,0,0,0,0,0,0,0,0,0,CB75,0,0,0,0,~
0,0,0,0,0,0,0,0,0,0,0,0)';$S;
    'VCCIN254':'(0,0,0,0,0,0,0,0,0,0,0,0,0,0,0,0,0,0,0,0,0,0,0,0,0,CB61,0,0,0,0,~
0,0,0,0,0,0,0,0,0,0,0,0)';$S;
    'VCCIN253':'(0,0,0,0,0,0,0,0,0,0,0,0,0,0,0,0,0,0,0,0,0,0,0,0,0,CA90,0,0,0,0,~
0,0,0,0,0,0,0,0,0,0,0,0)';$S;
    'VCCIN252':'(0,0,0,0,0,0,0,0,0,0,0,0,0,0,0,0,0,0,0,0,0,0,0,0,0,CA88,0,0,0,0,~
0,0,0,0,0,0,0,0,0,0,0,0)';$S;
    'VCCIN251':'(0,0,0,0,0,0,0,0,0,0,0,0,0,0,0,0,0,0,0,0,0,0,0,0,0,CA86,0,0,0,0,~
0,0,0,0,0,0,0,0,0,0,0,0)';$S;
    'VCCIN250':'(0,0,0,0,0,0,0,0,0,0,0,0,0,0,0,0,0,0,0,0,0,0,0,0,0,CA84,0,0,0,0,~
0,0,0,0,0,0,0,0,0,0,0,0)';$S;
    'VCCIN249':'(0,0,0,0,0,0,0,0,0,0,0,0,0,0,0,0,0,0,0,0,0,0,0,0,0,CA82,0,0,0,0,~
0,0,0,0,0,0,0,0,0,0,0,0)';$S;
    'VCCIN248':'(0,0,0,0,0,0,0,0,0,0,0,0,0,0,0,0,0,0,0,0,0,0,0,0,0,CA80,0,0,0,0,~
0,0,0,0,0,0,0,0,0,0,0,0)';$S;
    'VCCIN247':'(0,0,0,0,0,0,0,0,0,0,0,0,0,0,0,0,0,0,0,0,0,0,0,0,0,CA78,0,0,0,0,~
0,0,0,0,0,0,0,0,0,0,0,0)';$S;
    'VCCIN246':'(0,0,0,0,0,0,0,0,0,0,0,0,0,0,0,0,0,0,0,0,0,0,0,0,0,CA76,0,0,0,0,~
0,0,0,0,0,0,0,0,0,0,0,0)';$S;
    'VCCIN245':'(0,0,0,0,0,0,0,0,0,0,0,0,0,0,0,0,0,0,0,0,0,0,0,0,0,CA74,0,0,0,0,~
0,0,0,0,0,0,0,0,0,0,0,0)';$S;
    'VCCIN244':'(0,0,0,0,0,0,0,0,0,0,0,0,0,0,0,0,0,0,0,0,0,0,0,0,0,CA72,0,0,0,0,~
0,0,0,0,0,0,0,0,0,0,0,0)';$S;
    'VCCIN243':'(0,0,0,0,0,0,0,0,0,0,0,0,0,0,0,0,0,0,0,0,0,0,0,0,0,CA70,0,0,0,0,~
0,0,0,0,0,0,0,0,0,0,0,0)';$S;
    'VCCIN242':'(0,0,0,0,0,0,0,0,0,0,0,0,0,0,0,0,0,0,0,0,0,0,0,0,0,CA68,0,0,0,0,~
0,0,0,0,0,0,0,0,0,0,0,0)';$S;
    'VCCIN241':'(0,0,0,0,0,0,0,0,0,0,0,0,0,0,0,0,0,0,0,0,0,0,0,0,0,CA66,0,0,0,0,~
0,0,0,0,0,0,0,0,0,0,0,0)';$S;
    'VCCIN240':'(0,0,0,0,0,0,0,0,0,0,0,0,0,0,0,0,0,0,0,0,0,0,0,0,0,CA64,0,0,0,0,~
0,0,0,0,0,0,0,0,0,0,0,0)';$S;
    'VCCIN239':'(0,0,0,0,0,0,0,0,0,0,0,0,0,0,0,0,0,0,0,0,0,0,0,0,0,CA62,0,0,0,0,~
0,0,0,0,0,0,0,0,0,0,0,0)';$S;
    'VCCIN238':'(0,0,0,0,0,0,0,0,0,0,0,0,0,0,0,0,0,0,0,0,0,0,0,0,0,CA60,0,0,0,0,~
0,0,0,0,0,0,0,0,0,0,0,0)';$S;
    'VCCIN237':'(0,0,0,0,0,0,0,0,0,0,0,0,0,0,0,0,0,0,0,0,0,0,0,0,0,CA58,0,0,0,0,~
0,0,0,0,0,0,0,0,0,0,0,0)';$S;
    'VCCIN236':'(0,0,0,0,0,0,0,0,0,0,0,0,0,0,0,0,0,0,0,0,0,0,0,0,0,CA56,0,0,0,0,~
0,0,0,0,0,0,0,0,0,0,0,0)';$S;
    'VCCIN235':'(0,0,0,0,0,0,0,0,0,0,0,0,0,0,0,0,0,0,0,0,0,0,0,0,0,CA54,0,0,0,0,~
0,0,0,0,0,0,0,0,0,0,0,0)';$S;
    'VCCIN234':'(0,0,0,0,0,0,0,0,0,0,0,0,0,0,0,0,0,0,0,0,0,0,0,0,0,CA52,0,0,0,0,~
0,0,0,0,0,0,0,0,0,0,0,0)';$S;
    'VCCIN233':'(0,0,0,0,0,0,0,0,0,0,0,0,0,0,0,0,0,0,0,0,0,0,0,0,0,CA50,0,0,0,0,~
0,0,0,0,0,0,0,0,0,0,0,0)';$S;
    'VCCIN232':'(0,0,0,0,0,0,0,0,0,0,0,0,0,0,0,0,0,0,0,0,0,0,0,0,0,CA48,0,0,0,0,~
0,0,0,0,0,0,0,0,0,0,0,0)';$S;
    'VCCIN231':'(0,0,0,0,0,0,0,0,0,0,0,0,0,0,0,0,0,0,0,0,0,0,0,0,0,CA45,0,0,0,0,~
0,0,0,0,0,0,0,0,0,0,0,0)';$S;
    'VCCIN230':'(0,0,0,0,0,0,0,0,0,0,0,0,0,0,0,0,0,0,0,0,0,0,0,0,0,CA43,0,0,0,0,~
0,0,0,0,0,0,0,0,0,0,0,0)';$S;
    'VCCIN229':'(0,0,0,0,0,0,0,0,0,0,0,0,0,0,0,0,0,0,0,0,0,0,0,0,0,CA41,0,0,0,0,~
0,0,0,0,0,0,0,0,0,0,0,0)';$S;
    'VCCIN228':'(0,0,0,0,0,0,0,0,0,0,0,0,0,0,0,0,0,0,0,0,0,0,0,0,0,CA39,0,0,0,0,~
0,0,0,0,0,0,0,0,0,0,0,0)';$S;
    'VCCIN227':'(0,0,0,0,0,0,0,0,0,0,0,0,0,0,0,0,0,0,0,0,0,0,0,0,0,CA37,0,0,0,0,~
0,0,0,0,0,0,0,0,0,0,0,0)';$S;
    'VCCIN226':'(0,0,0,0,0,0,0,0,0,0,0,0,0,0,0,0,0,0,0,0,0,0,0,0,0,CA35,0,0,0,0,~
0,0,0,0,0,0,0,0,0,0,0,0)';$S;
    'VCCIN225':'(0,0,0,0,0,0,0,0,0,0,0,0,0,0,0,0,0,0,0,0,0,0,0,0,0,CA33,0,0,0,0,~
0,0,0,0,0,0,0,0,0,0,0,0)';$S;
    'VCCIN224':'(0,0,0,0,0,0,0,0,0,0,0,0,0,0,0,0,0,0,0,0,0,0,0,0,0,BY89,0,0,0,0,~
0,0,0,0,0,0,0,0,0,0,0,0)';$S;
    'VCCIN223':'(0,0,0,0,0,0,0,0,0,0,0,0,0,0,0,0,0,0,0,0,0,0,0,0,0,BY87,0,0,0,0,~
0,0,0,0,0,0,0,0,0,0,0,0)';$S;
    'VCCIN222':'(0,0,0,0,0,0,0,0,0,0,0,0,0,0,0,0,0,0,0,0,0,0,0,0,0,BY85,0,0,0,0,~
0,0,0,0,0,0,0,0,0,0,0,0)';$S;
    'VCCIN221':'(0,0,0,0,0,0,0,0,0,0,0,0,0,0,0,0,0,0,0,0,0,0,0,0,0,BY83,0,0,0,0,~
0,0,0,0,0,0,0,0,0,0,0,0)';$S;
    'VCCIN220':'(0,0,0,0,0,0,0,0,0,0,0,0,0,0,0,0,0,0,0,0,0,0,0,0,0,BY81,0,0,0,0,~
0,0,0,0,0,0,0,0,0,0,0,0)';$S;
    'VCCIN219':'(0,0,0,0,0,0,0,0,0,0,0,0,0,0,0,0,0,0,0,0,0,0,0,0,0,BY79,0,0,0,0,~
0,0,0,0,0,0,0,0,0,0,0,0)';$S;
    'VCCIN218':'(0,0,0,0,0,0,0,0,0,0,0,0,0,0,0,0,0,0,0,0,0,0,0,0,0,BY77,0,0,0,0,~
0,0,0,0,0,0,0,0,0,0,0,0)';$S;
    'VCCIN217':'(0,0,0,0,0,0,0,0,0,0,0,0,0,0,0,0,0,0,0,0,0,0,0,0,0,BY75,0,0,0,0,~
0,0,0,0,0,0,0,0,0,0,0,0)';$S;
    'VCCIN216':'(0,0,0,0,0,0,0,0,0,0,0,0,0,0,0,0,0,0,0,0,0,0,0,0,0,BY73,0,0,0,0,~
0,0,0,0,0,0,0,0,0,0,0,0)';$S;
    'VCCIN215':'(0,0,0,0,0,0,0,0,0,0,0,0,0,0,0,0,0,0,0,0,0,0,0,0,0,BY71,0,0,0,0,~
0,0,0,0,0,0,0,0,0,0,0,0)';$S;
    'VCCIN214':'(0,0,0,0,0,0,0,0,0,0,0,0,0,0,0,0,0,0,0,0,0,0,0,0,0,BY69,0,0,0,0,~
0,0,0,0,0,0,0,0,0,0,0,0)';$S;
    'VCCIN213':'(0,0,0,0,0,0,0,0,0,0,0,0,0,0,0,0,0,0,0,0,0,0,0,0,0,BY67,0,0,0,0,~
0,0,0,0,0,0,0,0,0,0,0,0)';$S;
    'VCCIN212':'(0,0,0,0,0,0,0,0,0,0,0,0,0,0,0,0,0,0,0,0,0,0,0,0,0,BY65,0,0,0,0,~
0,0,0,0,0,0,0,0,0,0,0,0)';$S;
    'VCCIN211':'(0,0,0,0,0,0,0,0,0,0,0,0,0,0,0,0,0,0,0,0,0,0,0,0,0,BY63,0,0,0,0,~
0,0,0,0,0,0,0,0,0,0,0,0)';$S;
    'VCCIN210':'(0,0,0,0,0,0,0,0,0,0,0,0,0,0,0,0,0,0,0,0,0,0,0,0,0,BY61,0,0,0,0,~
0,0,0,0,0,0,0,0,0,0,0,0)';$S;
    'VCCIN209':'(0,0,0,0,0,0,0,0,0,0,0,0,0,0,0,0,0,0,0,0,0,0,0,0,0,BY59,0,0,0,0,~
0,0,0,0,0,0,0,0,0,0,0,0)';$S;
    'VCCIN208':'(0,0,0,0,0,0,0,0,0,0,0,0,0,0,0,0,0,0,0,0,0,0,0,0,0,BY57,0,0,0,0,~
0,0,0,0,0,0,0,0,0,0,0,0)';$S;
    'VCCIN207':'(0,0,0,0,0,0,0,0,0,0,0,0,0,0,0,0,0,0,0,0,0,0,0,0,0,BY55,0,0,0,0,~
0,0,0,0,0,0,0,0,0,0,0,0)';$S;
    'VCCIN206':'(0,0,0,0,0,0,0,0,0,0,0,0,0,0,0,0,0,0,0,0,0,0,0,0,0,BY53,0,0,0,0,~
0,0,0,0,0,0,0,0,0,0,0,0)';$S;
    'VCCIN205':'(0,0,0,0,0,0,0,0,0,0,0,0,0,0,0,0,0,0,0,0,0,0,0,0,0,BY51,0,0,0,0,~
0,0,0,0,0,0,0,0,0,0,0,0)';$S;
    'VCCIN204':'(0,0,0,0,0,0,0,0,0,0,0,0,0,0,0,0,0,0,0,0,0,0,0,0,0,BY49,0,0,0,0,~
0,0,0,0,0,0,0,0,0,0,0,0)';$S;
    'VCCIN203':'(0,0,0,0,0,0,0,0,0,0,0,0,0,0,0,0,0,0,0,0,0,0,0,0,0,BY47,0,0,0,0,~
0,0,0,0,0,0,0,0,0,0,0,0)';$S;
    'VCCIN202':'(0,0,0,0,0,0,0,0,0,0,0,0,0,0,0,0,0,0,0,0,0,0,0,0,0,BY44,0,0,0,0,~
0,0,0,0,0,0,0,0,0,0,0,0)';$S;
    'VCCIN201':'(0,0,0,0,0,0,0,0,0,0,0,0,0,0,0,0,0,0,0,0,0,0,0,0,0,BY42,0,0,0,0,~
0,0,0,0,0,0,0,0,0,0,0,0)';$S;
    'VCCIN200':'(0,0,0,0,0,0,0,0,0,0,0,0,0,0,0,0,0,0,0,0,0,0,0,0,0,BY40,0,0,0,0,~
0,0,0,0,0,0,0,0,0,0,0,0)';$S;
    'VCCIN199':'(0,0,0,0,0,0,0,0,0,0,0,0,0,0,0,0,0,0,0,0,0,0,0,0,0,BY38,0,0,0,0,~
0,0,0,0,0,0,0,0,0,0,0,0)';$S;
    'VCCIN198':'(0,0,0,0,0,0,0,0,0,0,0,0,0,0,0,0,0,0,0,0,0,0,0,0,0,BY36,0,0,0,0,~
0,0,0,0,0,0,0,0,0,0,0,0)';$S;
    'VCCIN197':'(0,0,0,0,0,0,0,0,0,0,0,0,0,0,0,0,0,0,0,0,0,0,0,0,0,BY34,0,0,0,0,~
0,0,0,0,0,0,0,0,0,0,0,0)';$S;
    'VCCIN196':'(0,0,0,0,0,0,0,0,0,0,0,0,0,0,0,0,0,0,0,0,0,0,0,0,0,BY32,0,0,0,0,~
0,0,0,0,0,0,0,0,0,0,0,0)';$S;
    'VCCIN195':'(0,0,0,0,0,0,0,0,0,0,0,0,0,0,0,0,0,0,0,0,0,0,0,0,0,BW90,0,0,0,0,~
0,0,0,0,0,0,0,0,0,0,0,0)';$S;
    'VCCIN194':'(0,0,0,0,0,0,0,0,0,0,0,0,0,0,0,0,0,0,0,0,0,0,0,0,0,BW88,0,0,0,0,~
0,0,0,0,0,0,0,0,0,0,0,0)';$S;
    'VCCIN193':'(0,0,0,0,0,0,0,0,0,0,0,0,0,0,0,0,0,0,0,0,0,0,0,0,0,BW86,0,0,0,0,~
0,0,0,0,0,0,0,0,0,0,0,0)';$S;
    'VCCIN192':'(0,0,0,0,0,0,0,0,0,0,0,0,0,0,0,0,0,0,0,0,0,0,0,0,0,BW84,0,0,0,0,~
0,0,0,0,0,0,0,0,0,0,0,0)';$S;
    'VCCIN191':'(0,0,0,0,0,0,0,0,0,0,0,0,0,0,0,0,0,0,0,0,0,0,0,0,0,BW82,0,0,0,0,~
0,0,0,0,0,0,0,0,0,0,0,0)';$S;
    'VCCIN190':'(0,0,0,0,0,0,0,0,0,0,0,0,0,0,0,0,0,0,0,0,0,0,0,0,0,BW80,0,0,0,0,~
0,0,0,0,0,0,0,0,0,0,0,0)';$S;
    'VCCIN189':'(0,0,0,0,0,0,0,0,0,0,0,0,0,0,0,0,0,0,0,0,0,0,0,0,0,0,BW78,0,0,0,~
0,0,0,0,0,0,0,0,0,0,0,0)';$S;
    'VCCIN188':'(0,0,0,0,0,0,0,0,0,0,0,0,0,0,0,0,0,0,0,0,0,0,0,0,0,0,BW76,0,0,0,~
0,0,0,0,0,0,0,0,0,0,0,0)';$S;
    'VCCIN187':'(0,0,0,0,0,0,0,0,0,0,0,0,0,0,0,0,0,0,0,0,0,0,0,0,0,0,BW74,0,0,0,~
0,0,0,0,0,0,0,0,0,0,0,0)';$S;
    'VCCIN186':'(0,0,0,0,0,0,0,0,0,0,0,0,0,0,0,0,0,0,0,0,0,0,0,0,0,0,BW72,0,0,0,~
0,0,0,0,0,0,0,0,0,0,0,0)';$S;
    'VCCIN185':'(0,0,0,0,0,0,0,0,0,0,0,0,0,0,0,0,0,0,0,0,0,0,0,0,0,0,BW70,0,0,0,~
0,0,0,0,0,0,0,0,0,0,0,0)';$S;
    'VCCIN184':'(0,0,0,0,0,0,0,0,0,0,0,0,0,0,0,0,0,0,0,0,0,0,0,0,0,0,BW68,0,0,0,~
0,0,0,0,0,0,0,0,0,0,0,0)';$S;
    'VCCIN183':'(0,0,0,0,0,0,0,0,0,0,0,0,0,0,0,0,0,0,0,0,0,0,0,0,0,0,BW66,0,0,0,~
0,0,0,0,0,0,0,0,0,0,0,0)';$S;
    'VCCIN182':'(0,0,0,0,0,0,0,0,0,0,0,0,0,0,0,0,0,0,0,0,0,0,0,0,0,0,BW64,0,0,0,~
0,0,0,0,0,0,0,0,0,0,0,0)';$S;
    'VCCIN181':'(0,0,0,0,0,0,0,0,0,0,0,0,0,0,0,0,0,0,0,0,0,0,0,0,0,0,BW62,0,0,0,~
0,0,0,0,0,0,0,0,0,0,0,0)';$S;
    'VCCIN180':'(0,0,0,0,0,0,0,0,0,0,0,0,0,0,0,0,0,0,0,0,0,0,0,0,0,0,BW60,0,0,0,~
0,0,0,0,0,0,0,0,0,0,0,0)';$S;
    'VCCIN179':'(0,0,0,0,0,0,0,0,0,0,0,0,0,0,0,0,0,0,0,0,0,0,0,0,0,0,BW58,0,0,0,~
0,0,0,0,0,0,0,0,0,0,0,0)';$S;
    'VCCIN178':'(0,0,0,0,0,0,0,0,0,0,0,0,0,0,0,0,0,0,0,0,0,0,0,0,0,0,BW56,0,0,0,~
0,0,0,0,0,0,0,0,0,0,0,0)';$S;
    'VCCIN177':'(0,0,0,0,0,0,0,0,0,0,0,0,0,0,0,0,0,0,0,0,0,0,0,0,0,0,BW54,0,0,0,~
0,0,0,0,0,0,0,0,0,0,0,0)';$S;
    'VCCIN176':'(0,0,0,0,0,0,0,0,0,0,0,0,0,0,0,0,0,0,0,0,0,0,0,0,0,0,BW52,0,0,0,~
0,0,0,0,0,0,0,0,0,0,0,0)';$S;
    'VCCIN175':'(0,0,0,0,0,0,0,0,0,0,0,0,0,0,0,0,0,0,0,0,0,0,0,0,0,0,BW50,0,0,0,~
0,0,0,0,0,0,0,0,0,0,0,0)';$S;
    'VCCIN174':'(0,0,0,0,0,0,0,0,0,0,0,0,0,0,0,0,0,0,0,0,0,0,0,0,0,0,BW48,0,0,0,~
0,0,0,0,0,0,0,0,0,0,0,0)';$S;
    'VCCIN173':'(0,0,0,0,0,0,0,0,0,0,0,0,0,0,0,0,0,0,0,0,0,0,0,0,0,0,BW45,0,0,0,~
0,0,0,0,0,0,0,0,0,0,0,0)';$S;
    'VCCIN172':'(0,0,0,0,0,0,0,0,0,0,0,0,0,0,0,0,0,0,0,0,0,0,0,0,0,0,BW43,0,0,0,~
0,0,0,0,0,0,0,0,0,0,0,0)';$S;
    'VCCIN171':'(0,0,0,0,0,0,0,0,0,0,0,0,0,0,0,0,0,0,0,0,0,0,0,0,0,0,BW41,0,0,0,~
0,0,0,0,0,0,0,0,0,0,0,0)';$S;
    'VCCIN170':'(0,0,0,0,0,0,0,0,0,0,0,0,0,0,0,0,0,0,0,0,0,0,0,0,0,0,BW39,0,0,0,~
0,0,0,0,0,0,0,0,0,0,0,0)';$S;
    'VCCIN169':'(0,0,0,0,0,0,0,0,0,0,0,0,0,0,0,0,0,0,0,0,0,0,0,0,0,0,BW37,0,0,0,~
0,0,0,0,0,0,0,0,0,0,0,0)';$S;
    'VCCIN168':'(0,0,0,0,0,0,0,0,0,0,0,0,0,0,0,0,0,0,0,0,0,0,0,0,0,0,BW35,0,0,0,~
0,0,0,0,0,0,0,0,0,0,0,0)';$S;
    'VCCIN167':'(0,0,0,0,0,0,0,0,0,0,0,0,0,0,0,0,0,0,0,0,0,0,0,0,0,0,BW33,0,0,0,~
0,0,0,0,0,0,0,0,0,0,0,0)';$S;
    'VCCIN166':'(0,0,0,0,0,0,0,0,0,0,0,0,0,0,0,0,0,0,0,0,0,0,0,0,0,0,BV89,0,0,0,~
0,0,0,0,0,0,0,0,0,0,0,0)';$S;
    'VCCIN165':'(0,0,0,0,0,0,0,0,0,0,0,0,0,0,0,0,0,0,0,0,0,0,0,0,0,0,BV87,0,0,0,~
0,0,0,0,0,0,0,0,0,0,0,0)';$S;
    'VCCIN164':'(0,0,0,0,0,0,0,0,0,0,0,0,0,0,0,0,0,0,0,0,0,0,0,0,0,0,BV85,0,0,0,~
0,0,0,0,0,0,0,0,0,0,0,0)';$S;
    'VCCIN163':'(0,0,0,0,0,0,0,0,0,0,0,0,0,0,0,0,0,0,0,0,0,0,0,0,0,0,BV83,0,0,0,~
0,0,0,0,0,0,0,0,0,0,0,0)';$S;
    'VCCIN162':'(0,0,0,0,0,0,0,0,0,0,0,0,0,0,0,0,0,0,0,0,0,0,0,0,0,0,BV81,0,0,0,~
0,0,0,0,0,0,0,0,0,0,0,0)';$S;
    'VCCIN161':'(0,0,0,0,0,0,0,0,0,0,0,0,0,0,0,0,0,0,0,0,0,0,0,0,0,0,BV79,0,0,0,~
0,0,0,0,0,0,0,0,0,0,0,0)';$S;
    'VCCIN160':'(0,0,0,0,0,0,0,0,0,0,0,0,0,0,0,0,0,0,0,0,0,0,0,0,0,0,BV77,0,0,0,~
0,0,0,0,0,0,0,0,0,0,0,0)';$S;
    'VCCIN159':'(0,0,0,0,0,0,0,0,0,0,0,0,0,0,0,0,0,0,0,0,0,0,0,0,0,0,BV75,0,0,0,~
0,0,0,0,0,0,0,0,0,0,0,0)';$S;
    'VCCIN158':'(0,0,0,0,0,0,0,0,0,0,0,0,0,0,0,0,0,0,0,0,0,0,0,0,0,0,BV73,0,0,0,~
0,0,0,0,0,0,0,0,0,0,0,0)';$S;
    'VCCIN157':'(0,0,0,0,0,0,0,0,0,0,0,0,0,0,0,0,0,0,0,0,0,0,0,0,0,0,BV71,0,0,0,~
0,0,0,0,0,0,0,0,0,0,0,0)';$S;
    'VCCIN156':'(0,0,0,0,0,0,0,0,0,0,0,0,0,0,0,0,0,0,0,0,0,0,0,0,0,0,BV69,0,0,0,~
0,0,0,0,0,0,0,0,0,0,0,0)';$S;
    'VCCIN155':'(0,0,0,0,0,0,0,0,0,0,0,0,0,0,0,0,0,0,0,0,0,0,0,0,0,0,BV67,0,0,0,~
0,0,0,0,0,0,0,0,0,0,0,0)';$S;
    'VCCIN154':'(0,0,0,0,0,0,0,0,0,0,0,0,0,0,0,0,0,0,0,0,0,0,0,0,0,0,BV65,0,0,0,~
0,0,0,0,0,0,0,0,0,0,0,0)';$S;
    'VCCIN153':'(0,0,0,0,0,0,0,0,0,0,0,0,0,0,0,0,0,0,0,0,0,0,0,0,0,0,BV63,0,0,0,~
0,0,0,0,0,0,0,0,0,0,0,0)';$S;
    'VCCIN152':'(0,0,0,0,0,0,0,0,0,0,0,0,0,0,0,0,0,0,0,0,0,0,0,0,0,0,BV61,0,0,0,~
0,0,0,0,0,0,0,0,0,0,0,0)';$S;
    'VCCIN151':'(0,0,0,0,0,0,0,0,0,0,0,0,0,0,0,0,0,0,0,0,0,0,0,0,0,0,BV59,0,0,0,~
0,0,0,0,0,0,0,0,0,0,0,0)';$S;
    'VCCIN150':'(0,0,0,0,0,0,0,0,0,0,0,0,0,0,0,0,0,0,0,0,0,0,0,0,0,0,BV57,0,0,0,~
0,0,0,0,0,0,0,0,0,0,0,0)';$S;
    'VCCIN149':'(0,0,0,0,0,0,0,0,0,0,0,0,0,0,0,0,0,0,0,0,0,0,0,0,0,0,BV55,0,0,0,~
0,0,0,0,0,0,0,0,0,0,0,0)';$S;
    'VCCIN148':'(0,0,0,0,0,0,0,0,0,0,0,0,0,0,0,0,0,0,0,0,0,0,0,0,0,0,BV53,0,0,0,~
0,0,0,0,0,0,0,0,0,0,0,0)';$S;
    'VCCIN147':'(0,0,0,0,0,0,0,0,0,0,0,0,0,0,0,0,0,0,0,0,0,0,0,0,0,0,BV51,0,0,0,~
0,0,0,0,0,0,0,0,0,0,0,0)';$S;
    'VCCIN146':'(0,0,0,0,0,0,0,0,0,0,0,0,0,0,0,0,0,0,0,0,0,0,0,0,0,0,BV49,0,0,0,~
0,0,0,0,0,0,0,0,0,0,0,0)';$S;
    'VCCIN145':'(0,0,0,0,0,0,0,0,0,0,0,0,0,0,0,0,0,0,0,0,0,0,0,0,0,0,BV47,0,0,0,~
0,0,0,0,0,0,0,0,0,0,0,0)';$S;
    'VCCIN144':'(0,0,0,0,0,0,0,0,0,0,0,0,0,0,0,0,0,0,0,0,0,0,0,0,0,0,BV44,0,0,0,~
0,0,0,0,0,0,0,0,0,0,0,0)';$S;
    'VCCIN143':'(0,0,0,0,0,0,0,0,0,0,0,0,0,0,0,0,0,0,0,0,0,0,0,0,0,0,BV42,0,0,0,~
0,0,0,0,0,0,0,0,0,0,0,0)';$S;
    'VCCIN142':'(0,0,0,0,0,0,0,0,0,0,0,0,0,0,0,0,0,0,0,0,0,0,0,0,0,0,BV40,0,0,0,~
0,0,0,0,0,0,0,0,0,0,0,0)';$S;
    'VCCIN141':'(0,0,0,0,0,0,0,0,0,0,0,0,0,0,0,0,0,0,0,0,0,0,0,0,0,0,BV38,0,0,0,~
0,0,0,0,0,0,0,0,0,0,0,0)';$S;
    'VCCIN140':'(0,0,0,0,0,0,0,0,0,0,0,0,0,0,0,0,0,0,0,0,0,0,0,0,0,0,BV36,0,0,0,~
0,0,0,0,0,0,0,0,0,0,0,0)';$S;
    'VCCIN139':'(0,0,0,0,0,0,0,0,0,0,0,0,0,0,0,0,0,0,0,0,0,0,0,0,0,0,BV34,0,0,0,~
0,0,0,0,0,0,0,0,0,0,0,0)';$S;
    'VCCIN138':'(0,0,0,0,0,0,0,0,0,0,0,0,0,0,0,0,0,0,0,0,0,0,0,0,0,0,BV32,0,0,0,~
0,0,0,0,0,0,0,0,0,0,0,0)';$S;
    'VCCIN137':'(0,0,0,0,0,0,0,0,0,0,0,0,0,0,0,0,0,0,0,0,0,0,0,0,0,0,BU90,0,0,0,~
0,0,0,0,0,0,0,0,0,0,0,0)';$S;
    'VCCIN136':'(0,0,0,0,0,0,0,0,0,0,0,0,0,0,0,0,0,0,0,0,0,0,0,0,0,0,BU88,0,0,0,~
0,0,0,0,0,0,0,0,0,0,0,0)';$S;
    'VCCIN135':'(0,0,0,0,0,0,0,0,0,0,0,0,0,0,0,0,0,0,0,0,0,0,0,0,0,0,BU86,0,0,0,~
0,0,0,0,0,0,0,0,0,0,0,0)';$S;
    'VCCIN134':'(0,0,0,0,0,0,0,0,0,0,0,0,0,0,0,0,0,0,0,0,0,0,0,0,0,0,BU84,0,0,0,~
0,0,0,0,0,0,0,0,0,0,0,0)';$S;
    'VCCIN133':'(0,0,0,0,0,0,0,0,0,0,0,0,0,0,0,0,0,0,0,0,0,0,0,0,0,0,BU82,0,0,0,~
0,0,0,0,0,0,0,0,0,0,0,0)';$S;
    'VCCIN132':'(0,0,0,0,0,0,0,0,0,0,0,0,0,0,0,0,0,0,0,0,0,0,0,0,0,0,BU80,0,0,0,~
0,0,0,0,0,0,0,0,0,0,0,0)';$S;
    'VCCIN131':'(0,0,0,0,0,0,0,0,0,0,0,0,0,0,0,0,0,0,0,0,0,0,0,0,0,0,BU78,0,0,0,~
0,0,0,0,0,0,0,0,0,0,0,0)';$S;
    'VCCIN130':'(0,0,0,0,0,0,0,0,0,0,0,0,0,0,0,0,0,0,0,0,0,0,0,0,0,0,BU76,0,0,0,~
0,0,0,0,0,0,0,0,0,0,0,0)';$S;
    'VCCIN129':'(0,0,0,0,0,0,0,0,0,0,0,0,0,0,0,0,0,0,0,0,0,0,0,0,0,0,BU74,0,0,0,~
0,0,0,0,0,0,0,0,0,0,0,0)';$S;
    'VCCIN128':'(0,0,0,0,0,0,0,0,0,0,0,0,0,0,0,0,0,0,0,0,0,0,0,0,0,0,BU72,0,0,0,~
0,0,0,0,0,0,0,0,0,0,0,0)';$S;
    'VCCIN127':'(0,0,0,0,0,0,0,0,0,0,0,0,0,0,0,0,0,0,0,0,0,0,0,0,0,0,BU70,0,0,0,~
0,0,0,0,0,0,0,0,0,0,0,0)';$S;
    'VCCIN126':'(0,0,0,0,0,0,0,0,0,0,0,0,0,0,0,0,0,0,0,0,0,0,0,0,0,0,BU68,0,0,0,~
0,0,0,0,0,0,0,0,0,0,0,0)';$S;
    'VCCIN125':'(0,0,0,0,0,0,0,0,0,0,0,0,0,0,0,0,0,0,0,0,0,0,0,0,0,0,BU66,0,0,0,~
0,0,0,0,0,0,0,0,0,0,0,0)';$S;
    'VCCIN124':'(0,0,0,0,0,0,0,0,0,0,0,0,0,0,0,0,0,0,0,0,0,0,0,0,0,0,BU64,0,0,0,~
0,0,0,0,0,0,0,0,0,0,0,0)';$S;
    'VCCIN123':'(0,0,0,0,0,0,0,0,0,0,0,0,0,0,0,0,0,0,0,0,0,0,0,0,0,0,BU62,0,0,0,~
0,0,0,0,0,0,0,0,0,0,0,0)';$S;
    'VCCIN122':'(0,0,0,0,0,0,0,0,0,0,0,0,0,0,0,0,0,0,0,0,0,0,0,0,0,0,BU60,0,0,0,~
0,0,0,0,0,0,0,0,0,0,0,0)';$S;
    'VCCIN121':'(0,0,0,0,0,0,0,0,0,0,0,0,0,0,0,0,0,0,0,0,0,0,0,0,0,0,BU58,0,0,0,~
0,0,0,0,0,0,0,0,0,0,0,0)';$S;
    'VCCIN120':'(0,0,0,0,0,0,0,0,0,0,0,0,0,0,0,0,0,0,0,0,0,0,0,0,0,0,BU56,0,0,0,~
0,0,0,0,0,0,0,0,0,0,0,0)';$S;
    'VCCIN119':'(0,0,0,0,0,0,0,0,0,0,0,0,0,0,0,0,0,0,0,0,0,0,0,0,0,0,BU54,0,0,0,~
0,0,0,0,0,0,0,0,0,0,0,0)';$S;
    'VCCIN118':'(0,0,0,0,0,0,0,0,0,0,0,0,0,0,0,0,0,0,0,0,0,0,0,0,0,0,BU52,0,0,0,~
0,0,0,0,0,0,0,0,0,0,0,0)';$S;
    'VCCIN117':'(0,0,0,0,0,0,0,0,0,0,0,0,0,0,0,0,0,0,0,0,0,0,0,0,0,0,BU50,0,0,0,~
0,0,0,0,0,0,0,0,0,0,0,0)';$S;
    'VCCIN116':'(0,0,0,0,0,0,0,0,0,0,0,0,0,0,0,0,0,0,0,0,0,0,0,0,0,0,BU48,0,0,0,~
0,0,0,0,0,0,0,0,0,0,0,0)';$S;
    'VCCIN115':'(0,0,0,0,0,0,0,0,0,0,0,0,0,0,0,0,0,0,0,0,0,0,0,0,0,0,BU45,0,0,0,~
0,0,0,0,0,0,0,0,0,0,0,0)';$S;
    'VCCIN114':'(0,0,0,0,0,0,0,0,0,0,0,0,0,0,0,0,0,0,0,0,0,0,0,0,0,0,BU43,0,0,0,~
0,0,0,0,0,0,0,0,0,0,0,0)';$S;
    'VCCIN113':'(0,0,0,0,0,0,0,0,0,0,0,0,0,0,0,0,0,0,0,0,0,0,0,0,0,0,BU41,0,0,0,~
0,0,0,0,0,0,0,0,0,0,0,0)';$S;
    'VCCIN112':'(0,0,0,0,0,0,0,0,0,0,0,0,0,0,0,0,0,0,0,0,0,0,0,0,0,0,BU39,0,0,0,~
0,0,0,0,0,0,0,0,0,0,0,0)';$S;
    'VCCIN111':'(0,0,0,0,0,0,0,0,0,0,0,0,0,0,0,0,0,0,0,0,0,0,0,0,0,0,BU37,0,0,0,~
0,0,0,0,0,0,0,0,0,0,0,0)';$S;
    'VCCIN110':'(0,0,0,0,0,0,0,0,0,0,0,0,0,0,0,0,0,0,0,0,0,0,0,0,0,0,BU35,0,0,0,~
0,0,0,0,0,0,0,0,0,0,0,0)';$S;
    'VCCIN109':'(0,0,0,0,0,0,0,0,0,0,0,0,0,0,0,0,0,0,0,0,0,0,0,0,0,0,BU33,0,0,0,~
0,0,0,0,0,0,0,0,0,0,0,0)';$S;
    'VCCIN108':'(0,0,0,0,0,0,0,0,0,0,0,0,0,0,0,0,0,0,0,0,0,0,0,0,0,0,BT89,0,0,0,~
0,0,0,0,0,0,0,0,0,0,0,0)';$S;
    'VCCIN107':'(0,0,0,0,0,0,0,0,0,0,0,0,0,0,0,0,0,0,0,0,0,0,0,0,0,0,BT87,0,0,0,~
0,0,0,0,0,0,0,0,0,0,0,0)';$S;
    'VCCIN106':'(0,0,0,0,0,0,0,0,0,0,0,0,0,0,0,0,0,0,0,0,0,0,0,0,0,0,BT85,0,0,0,~
0,0,0,0,0,0,0,0,0,0,0,0)';$S;
    'VCCIN105':'(0,0,0,0,0,0,0,0,0,0,0,0,0,0,0,0,0,0,0,0,0,0,0,0,0,0,BT83,0,0,0,~
0,0,0,0,0,0,0,0,0,0,0,0)';$S;
    'VCCIN104':'(0,0,0,0,0,0,0,0,0,0,0,0,0,0,0,0,0,0,0,0,0,0,0,0,0,0,BT81,0,0,0,~
0,0,0,0,0,0,0,0,0,0,0,0)';$S;
    'VCCIN103':'(0,0,0,0,0,0,0,0,0,0,0,0,0,0,0,0,0,0,0,0,0,0,0,0,0,0,BT79,0,0,0,~
0,0,0,0,0,0,0,0,0,0,0,0)';$S;
    'VCCIN102':'(0,0,0,0,0,0,0,0,0,0,0,0,0,0,0,0,0,0,0,0,0,0,0,0,0,0,BT77,0,0,0,~
0,0,0,0,0,0,0,0,0,0,0,0)';$S;
    'VCCIN101':'(0,0,0,0,0,0,0,0,0,0,0,0,0,0,0,0,0,0,0,0,0,0,0,0,0,0,BT75,0,0,0,~
0,0,0,0,0,0,0,0,0,0,0,0)';$S;
    'VCCIN100':'(0,0,0,0,0,0,0,0,0,0,0,0,0,0,0,0,0,0,0,0,0,0,0,0,0,0,BT73,0,0,0,~
0,0,0,0,0,0,0,0,0,0,0,0)';$S;
    'VCCIN99':'(0,0,0,0,0,0,0,0,0,0,0,0,0,0,0,0,0,0,0,0,0,0,0,0,0,0,BT71,0,0,0,0~
,0,0,0,0,0,0,0,0,0,0,0)';$S;
    'VCCIN98':'(0,0,0,0,0,0,0,0,0,0,0,0,0,0,0,0,0,0,0,0,0,0,0,0,0,0,BT69,0,0,0,0~
,0,0,0,0,0,0,0,0,0,0,0)';$S;
    'VCCIN97':'(0,0,0,0,0,0,0,0,0,0,0,0,0,0,0,0,0,0,0,0,0,0,0,0,0,0,BT67,0,0,0,0~
,0,0,0,0,0,0,0,0,0,0,0)';$S;
    'VCCIN96':'(0,0,0,0,0,0,0,0,0,0,0,0,0,0,0,0,0,0,0,0,0,0,0,0,0,0,BT65,0,0,0,0~
,0,0,0,0,0,0,0,0,0,0,0)';$S;
    'VCCIN95':'(0,0,0,0,0,0,0,0,0,0,0,0,0,0,0,0,0,0,0,0,0,0,0,0,0,0,BT63,0,0,0,0~
,0,0,0,0,0,0,0,0,0,0,0)';$S;
    'VCCIN94':'(0,0,0,0,0,0,0,0,0,0,0,0,0,0,0,0,0,0,0,0,0,0,0,0,0,0,BT61,0,0,0,0~
,0,0,0,0,0,0,0,0,0,0,0)';$S;
    'VCCIN93':'(0,0,0,0,0,0,0,0,0,0,0,0,0,0,0,0,0,0,0,0,0,0,0,0,0,0,BT59,0,0,0,0~
,0,0,0,0,0,0,0,0,0,0,0)';$S;
    'VCCIN92':'(0,0,0,0,0,0,0,0,0,0,0,0,0,0,0,0,0,0,0,0,0,0,0,0,0,0,BT57,0,0,0,0~
,0,0,0,0,0,0,0,0,0,0,0)';$S;
    'VCCIN91':'(0,0,0,0,0,0,0,0,0,0,0,0,0,0,0,0,0,0,0,0,0,0,0,0,0,0,BT55,0,0,0,0~
,0,0,0,0,0,0,0,0,0,0,0)';$S;
    'VCCIN90':'(0,0,0,0,0,0,0,0,0,0,0,0,0,0,0,0,0,0,0,0,0,0,0,0,0,0,BT53,0,0,0,0~
,0,0,0,0,0,0,0,0,0,0,0)';$S;
    'VCCIN89':'(0,0,0,0,0,0,0,0,0,0,0,0,0,0,0,0,0,0,0,0,0,0,0,0,0,0,BT51,0,0,0,0~
,0,0,0,0,0,0,0,0,0,0,0)';$S;
    'VCCIN88':'(0,0,0,0,0,0,0,0,0,0,0,0,0,0,0,0,0,0,0,0,0,0,0,0,0,0,BT49,0,0,0,0~
,0,0,0,0,0,0,0,0,0,0,0)';$S;
    'VCCIN87':'(0,0,0,0,0,0,0,0,0,0,0,0,0,0,0,0,0,0,0,0,0,0,0,0,0,0,BT47,0,0,0,0~
,0,0,0,0,0,0,0,0,0,0,0)';$S;
    'VCCIN86':'(0,0,0,0,0,0,0,0,0,0,0,0,0,0,0,0,0,0,0,0,0,0,0,0,0,0,BT44,0,0,0,0~
,0,0,0,0,0,0,0,0,0,0,0)';$S;
    'VCCIN85':'(0,0,0,0,0,0,0,0,0,0,0,0,0,0,0,0,0,0,0,0,0,0,0,0,0,0,BT42,0,0,0,0~
,0,0,0,0,0,0,0,0,0,0,0)';$S;
    'VCCIN84':'(0,0,0,0,0,0,0,0,0,0,0,0,0,0,0,0,0,0,0,0,0,0,0,0,0,0,BT40,0,0,0,0~
,0,0,0,0,0,0,0,0,0,0,0)';$S;
    'VCCIN83':'(0,0,0,0,0,0,0,0,0,0,0,0,0,0,0,0,0,0,0,0,0,0,0,0,0,0,BT38,0,0,0,0~
,0,0,0,0,0,0,0,0,0,0,0)';$S;
    'VCCIN82':'(0,0,0,0,0,0,0,0,0,0,0,0,0,0,0,0,0,0,0,0,0,0,0,0,0,0,BT36,0,0,0,0~
,0,0,0,0,0,0,0,0,0,0,0)';$S;
    'VCCIN81':'(0,0,0,0,0,0,0,0,0,0,0,0,0,0,0,0,0,0,0,0,0,0,0,0,0,0,BT34,0,0,0,0~
,0,0,0,0,0,0,0,0,0,0,0)';$S;
    'VCCIN80':'(0,0,0,0,0,0,0,0,0,0,0,0,0,0,0,0,0,0,0,0,0,0,0,0,0,0,BT32,0,0,0,0~
,0,0,0,0,0,0,0,0,0,0,0)';$S;
    'VCCIN79':'(0,0,0,0,0,0,0,0,0,0,0,0,0,0,0,0,0,0,0,0,0,0,0,0,0,0,BR78,0,0,0,0~
,0,0,0,0,0,0,0,0,0,0,0)';$S;
    'VCCIN78':'(0,0,0,0,0,0,0,0,0,0,0,0,0,0,0,0,0,0,0,0,0,0,0,0,0,0,BR62,0,0,0,0~
,0,0,0,0,0,0,0,0,0,0,0)';$S;
    'VCCIN77':'(0,0,0,0,0,0,0,0,0,0,0,0,0,0,0,0,0,0,0,0,0,0,0,0,0,0,BR60,0,0,0,0~
,0,0,0,0,0,0,0,0,0,0,0)';$S;
    'VCCIN76':'(0,0,0,0,0,0,0,0,0,0,0,0,0,0,0,0,0,0,0,0,0,0,0,0,0,0,BP89,0,0,0,0~
,0,0,0,0,0,0,0,0,0,0,0)';$S;
    'VCCIN75':'(0,0,0,0,0,0,0,0,0,0,0,0,0,0,0,0,0,0,0,0,0,0,0,0,0,0,BP87,0,0,0,0~
,0,0,0,0,0,0,0,0,0,0,0)';$S;
    'VCCIN74':'(0,0,0,0,0,0,0,0,0,0,0,0,0,0,0,0,0,0,0,0,0,0,0,0,0,0,BP85,0,0,0,0~
,0,0,0,0,0,0,0,0,0,0,0)';$S;
    'VCCIN73':'(0,0,0,0,0,0,0,0,0,0,0,0,0,0,0,0,0,0,0,0,0,0,0,0,0,0,BP83,0,0,0,0~
,0,0,0,0,0,0,0,0,0,0,0)';$S;
    'VCCIN72':'(0,0,0,0,0,0,0,0,0,0,0,0,0,0,0,0,0,0,0,0,0,0,0,0,0,0,BP81,0,0,0,0~
,0,0,0,0,0,0,0,0,0,0,0)';$S;
    'VCCIN71':'(0,0,0,0,0,0,0,0,0,0,0,0,0,0,0,0,0,0,0,0,0,0,0,0,0,0,BP79,0,0,0,0~
,0,0,0,0,0,0,0,0,0,0,0)';$S;
    'VCCIN70':'(0,0,0,0,0,0,0,0,0,0,0,0,0,0,0,0,0,0,0,0,0,0,0,0,0,0,BP61,0,0,0,0~
,0,0,0,0,0,0,0,0,0,0,0)';$S;
    'VCCIN69':'(0,0,0,0,0,0,0,0,0,0,0,0,0,0,0,0,0,0,0,0,0,0,0,0,0,0,BP59,0,0,0,0~
,0,0,0,0,0,0,0,0,0,0,0)';$S;
    'VCCIN68':'(0,0,0,0,0,0,0,0,0,0,0,0,0,0,0,0,0,0,0,0,0,0,0,0,0,0,BP57,0,0,0,0~
,0,0,0,0,0,0,0,0,0,0,0)';$S;
    'VCCIN67':'(0,0,0,0,0,0,0,0,0,0,0,0,0,0,0,0,0,0,0,0,0,0,0,0,0,0,BP55,0,0,0,0~
,0,0,0,0,0,0,0,0,0,0,0)';$S;
    'VCCIN66':'(0,0,0,0,0,0,0,0,0,0,0,0,0,0,0,0,0,0,0,0,0,0,0,0,0,0,BP53,0,0,0,0~
,0,0,0,0,0,0,0,0,0,0,0)';$S;
    'VCCIN65':'(0,0,0,0,0,0,0,0,0,0,0,0,0,0,0,0,0,0,0,0,0,0,0,0,0,0,BP51,0,0,0,0~
,0,0,0,0,0,0,0,0,0,0,0)';$S;
    'VCCIN64':'(0,0,0,0,0,0,0,0,0,0,0,0,0,0,0,0,0,0,0,0,0,0,0,0,0,0,BP49,0,0,0,0~
,0,0,0,0,0,0,0,0,0,0,0)';$S;
    'VCCIN63':'(0,0,0,0,0,0,0,0,0,0,0,0,0,0,0,0,0,0,0,0,0,0,0,0,0,0,BP47,0,0,0,0~
,0,0,0,0,0,0,0,0,0,0,0)';$S;
    'VCCIN62':'(0,0,0,0,0,0,0,0,0,0,0,0,0,0,0,0,0,0,0,0,0,0,0,0,0,0,BP44,0,0,0,0~
,0,0,0,0,0,0,0,0,0,0,0)';$S;
    'VCCIN61':'(0,0,0,0,0,0,0,0,0,0,0,0,0,0,0,0,0,0,0,0,0,0,0,0,0,0,BP42,0,0,0,0~
,0,0,0,0,0,0,0,0,0,0,0)';$S;
    'VCCIN60':'(0,0,0,0,0,0,0,0,0,0,0,0,0,0,0,0,0,0,0,0,0,0,0,0,0,0,BP40,0,0,0,0~
,0,0,0,0,0,0,0,0,0,0,0)';$S;
    'VCCIN59':'(0,0,0,0,0,0,0,0,0,0,0,0,0,0,0,0,0,0,0,0,0,0,0,0,0,0,BP38,0,0,0,0~
,0,0,0,0,0,0,0,0,0,0,0)';$S;
    'VCCIN58':'(0,0,0,0,0,0,0,0,0,0,0,0,0,0,0,0,0,0,0,0,0,0,0,0,0,0,BP36,0,0,0,0~
,0,0,0,0,0,0,0,0,0,0,0)';$S;
    'VCCIN57':'(0,0,0,0,0,0,0,0,0,0,0,0,0,0,0,0,0,0,0,0,0,0,0,0,0,0,BP34,0,0,0,0~
,0,0,0,0,0,0,0,0,0,0,0)';$S;
    'VCCIN56':'(0,0,0,0,0,0,0,0,0,0,0,0,0,0,0,0,0,0,0,0,0,0,0,0,0,0,BP32,0,0,0,0~
,0,0,0,0,0,0,0,0,0,0,0)';$S;
    'VCCIN55':'(0,0,0,0,0,0,0,0,0,0,0,0,0,0,0,0,0,0,0,0,0,0,0,0,0,0,BN90,0,0,0,0~
,0,0,0,0,0,0,0,0,0,0,0)';$S;
    'VCCIN54':'(0,0,0,0,0,0,0,0,0,0,0,0,0,0,0,0,0,0,0,0,0,0,0,0,0,0,BN88,0,0,0,0~
,0,0,0,0,0,0,0,0,0,0,0)';$S;
    'VCCIN53':'(0,0,0,0,0,0,0,0,0,0,0,0,0,0,0,0,0,0,0,0,0,0,0,0,0,0,BN86,0,0,0,0~
,0,0,0,0,0,0,0,0,0,0,0)';$S;
    'VCCIN52':'(0,0,0,0,0,0,0,0,0,0,0,0,0,0,0,0,0,0,0,0,0,0,0,0,0,0,BN84,0,0,0,0~
,0,0,0,0,0,0,0,0,0,0,0)';$S;
    'VCCIN51':'(0,0,0,0,0,0,0,0,0,0,0,0,0,0,0,0,0,0,0,0,0,0,0,0,0,0,BN82,0,0,0,0~
,0,0,0,0,0,0,0,0,0,0,0)';$S;
    'VCCIN50':'(0,0,0,0,0,0,0,0,0,0,0,0,0,0,0,0,0,0,0,0,0,0,0,0,0,0,BN80,0,0,0,0~
,0,0,0,0,0,0,0,0,0,0,0)';$S;
    'VCCIN49':'(0,0,0,0,0,0,0,0,0,0,0,0,0,0,0,0,0,0,0,0,0,0,0,0,0,0,BN78,0,0,0,0~
,0,0,0,0,0,0,0,0,0,0,0)';$S;
    'VCCIN48':'(0,0,0,0,0,0,0,0,0,0,0,0,0,0,0,0,0,0,0,0,0,0,0,0,0,0,BN60,0,0,0,0~
,0,0,0,0,0,0,0,0,0,0,0)';$S;
    'VCCIN47':'(0,0,0,0,0,0,0,0,0,0,0,0,0,0,0,0,0,0,0,0,0,0,0,0,0,0,BN58,0,0,0,0~
,0,0,0,0,0,0,0,0,0,0,0)';$S;
    'VCCIN46':'(0,0,0,0,0,0,0,0,0,0,0,0,0,0,0,0,0,0,0,0,0,0,0,0,0,0,BN56,0,0,0,0~
,0,0,0,0,0,0,0,0,0,0,0)';$S;
    'VCCIN45':'(0,0,0,0,0,0,0,0,0,0,0,0,0,0,0,0,0,0,0,0,0,0,0,0,0,0,BN54,0,0,0,0~
,0,0,0,0,0,0,0,0,0,0,0)';$S;
    'VCCIN44':'(0,0,0,0,0,0,0,0,0,0,0,0,0,0,0,0,0,0,0,0,0,0,0,0,0,0,BN52,0,0,0,0~
,0,0,0,0,0,0,0,0,0,0,0)';$S;
    'VCCIN43':'(0,0,0,0,0,0,0,0,0,0,0,0,0,0,0,0,0,0,0,0,0,0,0,0,0,0,BN50,0,0,0,0~
,0,0,0,0,0,0,0,0,0,0,0)';$S;
    'VCCIN42':'(0,0,0,0,0,0,0,0,0,0,0,0,0,0,0,0,0,0,0,0,0,0,0,0,0,0,BN48,0,0,0,0~
,0,0,0,0,0,0,0,0,0,0,0)';$S;
    'VCCIN41':'(0,0,0,0,0,0,0,0,0,0,0,0,0,0,0,0,0,0,0,0,0,0,0,0,0,0,BN45,0,0,0,0~
,0,0,0,0,0,0,0,0,0,0,0)';$S;
    'VCCIN40':'(0,0,0,0,0,0,0,0,0,0,0,0,0,0,0,0,0,0,0,0,0,0,0,0,0,0,BN43,0,0,0,0~
,0,0,0,0,0,0,0,0,0,0,0)';$S;
    'VCCIN39':'(0,0,0,0,0,0,0,0,0,0,0,0,0,0,0,0,0,0,0,0,0,0,0,0,0,0,0,BN41,0,0,0~
,0,0,0,0,0,0,0,0,0,0,0)';$S;
    'VCCIN38':'(0,0,0,0,0,0,0,0,0,0,0,0,0,0,0,0,0,0,0,0,0,0,0,0,0,0,0,BN39,0,0,0~
,0,0,0,0,0,0,0,0,0,0,0)';$S;
    'VCCIN37':'(0,0,0,0,0,0,0,0,0,0,0,0,0,0,0,0,0,0,0,0,0,0,0,0,0,0,0,BN37,0,0,0~
,0,0,0,0,0,0,0,0,0,0,0)';$S;
    'VCCIN36':'(0,0,0,0,0,0,0,0,0,0,0,0,0,0,0,0,0,0,0,0,0,0,0,0,0,0,0,BN35,0,0,0~
,0,0,0,0,0,0,0,0,0,0,0)';$S;
    'VCCIN35':'(0,0,0,0,0,0,0,0,0,0,0,0,0,0,0,0,0,0,0,0,0,0,0,0,0,0,0,BN33,0,0,0~
,0,0,0,0,0,0,0,0,0,0,0)';$S;
    'VCCIN34':'(0,0,0,0,0,0,0,0,0,0,0,0,0,0,0,0,0,0,0,0,0,0,0,0,0,0,0,BM91,0,0,0~
,0,0,0,0,0,0,0,0,0,0,0)';$S;
    'VCCIN33':'(0,0,0,0,0,0,0,0,0,0,0,0,0,0,0,0,0,0,0,0,0,0,0,0,0,0,0,BM89,0,0,0~
,0,0,0,0,0,0,0,0,0,0,0)';$S;
    'VCCIN32':'(0,0,0,0,0,0,0,0,0,0,0,0,0,0,0,0,0,0,0,0,0,0,0,0,0,0,0,BM87,0,0,0~
,0,0,0,0,0,0,0,0,0,0,0)';$S;
    'VCCIN31':'(0,0,0,0,0,0,0,0,0,0,0,0,0,0,0,0,0,0,0,0,0,0,0,0,0,0,0,BM85,0,0,0~
,0,0,0,0,0,0,0,0,0,0,0)';$S;
    'VCCIN30':'(0,0,0,0,0,0,0,0,0,0,0,0,0,0,0,0,0,0,0,0,0,0,0,0,0,0,0,BM83,0,0,0~
,0,0,0,0,0,0,0,0,0,0,0)';$S;
    'VCCIN29':'(0,0,0,0,0,0,0,0,0,0,0,0,0,0,0,0,0,0,0,0,0,0,0,0,0,0,0,BM81,0,0,0~
,0,0,0,0,0,0,0,0,0,0,0)';$S;
    'VCCIN28':'(0,0,0,0,0,0,0,0,0,0,0,0,0,0,0,0,0,0,0,0,0,0,0,0,0,0,0,BM79,0,0,0~
,0,0,0,0,0,0,0,0,0,0,0)';$S;
    'VCCIN27':'(0,0,0,0,0,0,0,0,0,0,0,0,0,0,0,0,0,0,0,0,0,0,0,0,0,0,0,BL90,0,0,0~
,0,0,0,0,0,0,0,0,0,0,0)';$S;
    'VCCIN26':'(0,0,0,0,0,0,0,0,0,0,0,0,0,0,0,0,0,0,0,0,0,0,0,0,0,0,0,BL88,0,0,0~
,0,0,0,0,0,0,0,0,0,0,0)';$S;
    'VCCIN25':'(0,0,0,0,0,0,0,0,0,0,0,0,0,0,0,0,0,0,0,0,0,0,0,0,0,0,0,BL86,0,0,0~
,0,0,0,0,0,0,0,0,0,0,0)';$S;
    'VCCIN24':'(0,0,0,0,0,0,0,0,0,0,0,0,0,0,0,0,0,0,0,0,0,0,0,0,0,0,0,BL84,0,0,0~
,0,0,0,0,0,0,0,0,0,0,0)';$S;
    'VCCIN23':'(0,0,0,0,0,0,0,0,0,0,0,0,0,0,0,0,0,0,0,0,0,0,0,0,0,0,0,BL82,0,0,0~
,0,0,0,0,0,0,0,0,0,0,0)';$S;
    'VCCIN22':'(0,0,0,0,0,0,0,0,0,0,0,0,0,0,0,0,0,0,0,0,0,0,0,0,0,0,0,BL80,0,0,0~
,0,0,0,0,0,0,0,0,0,0,0)';$S;
    'VCCIN21':'(0,0,0,0,0,0,0,0,0,0,0,0,0,0,0,0,0,0,0,0,0,0,0,0,0,0,0,BK91,0,0,0~
,0,0,0,0,0,0,0,0,0,0,0)';$S;
    'VCCIN20':'(0,0,0,0,0,0,0,0,0,0,0,0,0,0,0,0,0,0,0,0,0,0,0,0,0,0,0,BK89,0,0,0~
,0,0,0,0,0,0,0,0,0,0,0)';$S;
    'VCCIN19':'(0,0,0,0,0,0,0,0,0,0,0,0,0,0,0,0,0,0,0,0,0,0,0,0,0,0,0,BK87,0,0,0~
,0,0,0,0,0,0,0,0,0,0,0)';$S;
    'VCCIN18':'(0,0,0,0,0,0,0,0,0,0,0,0,0,0,0,0,0,0,0,0,0,0,0,0,0,0,0,BK85,0,0,0~
,0,0,0,0,0,0,0,0,0,0,0)';$S;
    'VCCIN17':'(0,0,0,0,0,0,0,0,0,0,0,0,0,0,0,0,0,0,0,0,0,0,0,0,0,0,0,BK83,0,0,0~
,0,0,0,0,0,0,0,0,0,0,0)';$S;
    'VCCIN16':'(0,0,0,0,0,0,0,0,0,0,0,0,0,0,0,0,0,0,0,0,0,0,0,0,0,0,0,BK81,0,0,0~
,0,0,0,0,0,0,0,0,0,0,0)';$S;
    'VCCIN15':'(0,0,0,0,0,0,0,0,0,0,0,0,0,0,0,0,0,0,0,0,0,0,0,0,0,0,0,BH91,0,0,0~
,0,0,0,0,0,0,0,0,0,0,0)';$S;
    'VCCIN14':'(0,0,0,0,0,0,0,0,0,0,0,0,0,0,0,0,0,0,0,0,0,0,0,0,0,0,0,BH89,0,0,0~
,0,0,0,0,0,0,0,0,0,0,0)';$S;
    'VCCIN13':'(0,0,0,0,0,0,0,0,0,0,0,0,0,0,0,0,0,0,0,0,0,0,0,0,0,0,0,BH87,0,0,0~
,0,0,0,0,0,0,0,0,0,0,0)';$S;
    'VCCIN12':'(0,0,0,0,0,0,0,0,0,0,0,0,0,0,0,0,0,0,0,0,0,0,0,0,0,0,0,BH85,0,0,0~
,0,0,0,0,0,0,0,0,0,0,0)';$S;
    'VCCIN11':'(0,0,0,0,0,0,0,0,0,0,0,0,0,0,0,0,0,0,0,0,0,0,0,0,0,0,0,BG90,0,0,0~
,0,0,0,0,0,0,0,0,0,0,0)';$S;
    'VCCIN10':'(0,0,0,0,0,0,0,0,0,0,0,0,0,0,0,0,0,0,0,0,0,0,0,0,0,0,0,BG88,0,0,0~
,0,0,0,0,0,0,0,0,0,0,0)';$S;
    'VCCIN9':'(0,0,0,0,0,0,0,0,0,0,0,0,0,0,0,0,0,0,0,0,0,0,0,0,0,0,0,BG86,0,0,0,~
0,0,0,0,0,0,0,0,0,0,0)';$S;
    'VCCIN8':'(0,0,0,0,0,0,0,0,0,0,0,0,0,0,0,0,0,0,0,0,0,0,0,0,0,0,0,BG84,0,0,0,~
0,0,0,0,0,0,0,0,0,0,0)';$S;
    'VCCIN7':'(0,0,0,0,0,0,0,0,0,0,0,0,0,0,0,0,0,0,0,0,0,0,0,0,0,0,0,BF91,0,0,0,~
0,0,0,0,0,0,0,0,0,0,0)';$S;
    'VCCIN6':'(0,0,0,0,0,0,0,0,0,0,0,0,0,0,0,0,0,0,0,0,0,0,0,0,0,0,0,BF89,0,0,0,~
0,0,0,0,0,0,0,0,0,0,0)';$S;
    'VCCIN5':'(0,0,0,0,0,0,0,0,0,0,0,0,0,0,0,0,0,0,0,0,0,0,0,0,0,0,0,BF87,0,0,0,~
0,0,0,0,0,0,0,0,0,0,0)';$S;
    'VCCIN4':'(0,0,0,0,0,0,0,0,0,0,0,0,0,0,0,0,0,0,0,0,0,0,0,0,0,0,0,BF85,0,0,0,~
0,0,0,0,0,0,0,0,0,0,0)';$S;
    'VCCIN3':'(0,0,0,0,0,0,0,0,0,0,0,0,0,0,0,0,0,0,0,0,0,0,0,0,0,0,0,BE90,0,0,0,~
0,0,0,0,0,0,0,0,0,0,0)';$S;
    'VCCIN2':'(0,0,0,0,0,0,0,0,0,0,0,0,0,0,0,0,0,0,0,0,0,0,0,0,0,0,0,BE88,0,0,0,~
0,0,0,0,0,0,0,0,0,0,0)';$S;
    'VCCIN1':'(0,0,0,0,0,0,0,0,0,0,0,0,0,0,0,0,0,0,0,0,0,0,0,0,0,0,0,BE86,0,0,0,~
0,0,0,0,0,0,0,0,0,0,0)';$S;
    'VCCIN0':'(0,0,0,0,0,0,0,0,0,0,0,0,0,0,0,0,0,0,0,0,0,0,0,0,0,0,0,BD91,0,0,0,~
0,0,0,0,0,0,0,0,0,0,0)';$S;
    'VCCINFAON53':'(0,0,0,0,0,0,0,0,0,0,0,0,0,0,0,0,0,0,0,0,0,0,0,0,0,0,0,DA21,0~
,0,0,0,0,0,0,0,0,0,0,0,0,0)';$S;
    'VCCINFAON52':'(0,0,0,0,0,0,0,0,0,0,0,0,0,0,0,0,0,0,0,0,0,0,0,0,0,0,0,CW62,0~
,0,0,0,0,0,0,0,0,0,0,0,0,0)';$S;
    'VCCINFAON51':'(0,0,0,0,0,0,0,0,0,0,0,0,0,0,0,0,0,0,0,0,0,0,0,0,0,0,0,CV63,0~
,0,0,0,0,0,0,0,0,0,0,0,0,0)';$S;
    'VCCINFAON50':'(0,0,0,0,0,0,0,0,0,0,0,0,0,0,0,0,0,0,0,0,0,0,0,0,0,0,0,CV61,0~
,0,0,0,0,0,0,0,0,0,0,0,0,0)';$S;
    'VCCINFAON49':'(0,0,0,0,0,0,0,0,0,0,0,0,0,0,0,0,0,0,0,0,0,0,0,0,0,0,0,CT63,0~
,0,0,0,0,0,0,0,0,0,0,0,0,0)';$S;
    'VCCINFAON48':'(0,0,0,0,0,0,0,0,0,0,0,0,0,0,0,0,0,0,0,0,0,0,0,0,0,0,0,CP63,0~
,0,0,0,0,0,0,0,0,0,0,0,0,0)';$S;
    'VCCINFAON47':'(0,0,0,0,0,0,0,0,0,0,0,0,0,0,0,0,0,0,0,0,0,0,0,0,0,0,0,CN19,0~
,0,0,0,0,0,0,0,0,0,0,0,0,0)';$S;
    'VCCINFAON46':'(0,0,0,0,0,0,0,0,0,0,0,0,0,0,0,0,0,0,0,0,0,0,0,0,0,0,0,CJ19,0~
,0,0,0,0,0,0,0,0,0,0,0,0,0)';$S;
    'VCCINFAON45':'(0,0,0,0,0,0,0,0,0,0,0,0,0,0,0,0,0,0,0,0,0,0,0,0,0,0,0,CJ11,0~
,0,0,0,0,0,0,0,0,0,0,0,0,0)';$S;
    'VCCINFAON44':'(0,0,0,0,0,0,0,0,0,0,0,0,0,0,0,0,0,0,0,0,0,0,0,0,0,0,0,CE19,0~
,0,0,0,0,0,0,0,0,0,0,0,0,0)';$S;
    'VCCINFAON43':'(0,0,0,0,0,0,0,0,0,0,0,0,0,0,0,0,0,0,0,0,0,0,0,0,0,0,0,CA15,0~
,0,0,0,0,0,0,0,0,0,0,0,0,0)';$S;
    'VCCINFAON42':'(0,0,0,0,0,0,0,0,0,0,0,0,0,0,0,0,0,0,0,0,0,0,0,0,0,0,0,BN15,0~
,0,0,0,0,0,0,0,0,0,0,0,0,0)';$S;
    'VCCINFAON41':'(0,0,0,0,0,0,0,0,0,0,0,0,0,0,0,0,0,0,0,0,0,0,0,0,0,0,0,BK61,0~
,0,0,0,0,0,0,0,0,0,0,0,0,0)';$S;
    'VCCINFAON40':'(0,0,0,0,0,0,0,0,0,0,0,0,0,0,0,0,0,0,0,0,0,0,0,0,0,0,0,BJ60,0~
,0,0,0,0,0,0,0,0,0,0,0,0,0)';$S;
    'VCCINFAON39':'(0,0,0,0,0,0,0,0,0,0,0,0,0,0,0,0,0,0,0,0,0,0,0,0,0,0,0,BJ15,0~
,0,0,0,0,0,0,0,0,0,0,0,0,0)';$S;
    'VCCINFAON38':'(0,0,0,0,0,0,0,0,0,0,0,0,0,0,0,0,0,0,0,0,0,0,0,0,0,0,0,BG60,0~
,0,0,0,0,0,0,0,0,0,0,0,0,0)';$S;
    'VCCINFAON37':'(0,0,0,0,0,0,0,0,0,0,0,0,0,0,0,0,0,0,0,0,0,0,0,0,0,0,0,BE60,0~
,0,0,0,0,0,0,0,0,0,0,0,0,0)';$S;
    'VCCINFAON36':'(0,0,0,0,0,0,0,0,0,0,0,0,0,0,0,0,0,0,0,0,0,0,0,0,0,0,0,BE15,0~
,0,0,0,0,0,0,0,0,0,0,0,0,0)';$S;
    'VCCINFAON35':'(0,0,0,0,0,0,0,0,0,0,0,0,0,0,0,0,0,0,0,0,0,0,0,0,0,0,0,BC60,0~
,0,0,0,0,0,0,0,0,0,0,0,0,0)';$S;
    'VCCINFAON34':'(0,0,0,0,0,0,0,0,0,0,0,0,0,0,0,0,0,0,0,0,0,0,0,0,0,0,0,BA15,0~
,0,0,0,0,0,0,0,0,0,0,0,0,0)';$S;
    'VCCINFAON33':'(0,0,0,0,0,0,0,0,0,0,0,0,0,0,0,0,0,0,0,0,0,0,0,0,0,0,0,AY18,0~
,0,0,0,0,0,0,0,0,0,0,0,0,0)';$S;
    'VCC_3P3_AUX0':'(0,0,0,0,0,0,0,0,0,0,0,0,0,0,0,0,0,0,0,0,0,0,0,0,0,0,0,0,BC2~
1,0,0,0,0,0,0,0,0,0,0,0,0,0)';$S;
    'VCC_3P3_AUX1':'(0,0,0,0,0,0,0,0,0,0,0,0,0,0,0,0,0,0,0,0,0,0,0,0,0,0,0,0,BA2~
1,0,0,0,0,0,0,0,0,0,0,0,0,0)';$S;
    'VCCD_HV28':'(0,0,0,0,0,0,0,0,0,0,0,0,0,0,0,0,0,0,0,0,0,0,0,0,0,0,0,0,CY53,0~
,0,0,0,0,0,0,0,0,0,0,0,0)';$S;
    'VCCD_HV27':'(0,0,0,0,0,0,0,0,0,0,0,0,0,0,0,0,0,0,0,0,0,0,0,0,0,0,0,0,CY36,0~
,0,0,0,0,0,0,0,0,0,0,0,0)';$S;
    'VCCD_HV24':'(0,0,0,0,0,0,0,0,0,0,0,0,0,0,0,0,0,0,0,0,0,0,0,0,0,0,0,0,CW54,0~
,0,0,0,0,0,0,0,0,0,0,0,0)';$S;
    'VCCD_HV26':'(0,0,0,0,0,0,0,0,0,0,0,0,0,0,0,0,0,0,0,0,0,0,0,0,0,0,0,0,CY34,0~
,0,0,0,0,0,0,0,0,0,0,0,0)';$S;
    'VCCD_HV25':'(0,0,0,0,0,0,0,0,0,0,0,0,0,0,0,0,0,0,0,0,0,0,0,0,0,0,0,0,CW56,0~
,0,0,0,0,0,0,0,0,0,0,0,0)';$S;
    'VCCD_HV23':'(0,0,0,0,0,0,0,0,0,0,0,0,0,0,0,0,0,0,0,0,0,0,0,0,0,0,0,0,CW52,0~
,0,0,0,0,0,0,0,0,0,0,0,0)';$S;
    'VCCD_HV22':'(0,0,0,0,0,0,0,0,0,0,0,0,0,0,0,0,0,0,0,0,0,0,0,0,0,0,0,0,CW37,0~
,0,0,0,0,0,0,0,0,0,0,0,0)';$S;
    'VCCD_HV21':'(0,0,0,0,0,0,0,0,0,0,0,0,0,0,0,0,0,0,0,0,0,0,0,0,0,0,0,0,CW35,0~
,0,0,0,0,0,0,0,0,0,0,0,0)';$S;
    'VCCD_HV20':'(0,0,0,0,0,0,0,0,0,0,0,0,0,0,0,0,0,0,0,0,0,0,0,0,0,0,0,0,CE7,0,~
0,0,0,0,0,0,0,0,0,0,0,0)';$S;
    'VCCD_HV19':'(0,0,0,0,0,0,0,0,0,0,0,0,0,0,0,0,0,0,0,0,0,0,0,0,0,0,0,0,CA7,0,~
0,0,0,0,0,0,0,0,0,0,0,0)';$S;
    'VCCD_HV18':'(0,0,0,0,0,0,0,0,0,0,0,0,0,0,0,0,0,0,0,0,0,0,0,0,0,0,0,0,BN7,0,~
0,0,0,0,0,0,0,0,0,0,0,0)';$S;
    'VCCD_HV17':'(0,0,0,0,0,0,0,0,0,0,0,0,0,0,0,0,0,0,0,0,0,0,0,0,0,0,0,0,BJ7,0,~
0,0,0,0,0,0,0,0,0,0,0,0)';$S;
    'VCCD_HV16':'(0,0,0,0,0,0,0,0,0,0,0,0,0,0,0,0,0,0,0,0,0,0,0,0,0,0,0,0,BJ3,0,~
0,0,0,0,0,0,0,0,0,0,0,0)';$S;
    'VCCD_HV15':'(0,0,0,0,0,0,0,0,0,0,0,0,0,0,0,0,0,0,0,0,0,0,0,0,0,0,0,0,BJ11,0~
,0,0,0,0,0,0,0,0,0,0,0,0)';$S;
    'VCCD_HV14':'(0,0,0,0,0,0,0,0,0,0,0,0,0,0,0,0,0,0,0,0,0,0,0,0,0,0,0,0,BE7,0,~
0,0,0,0,0,0,0,0,0,0,0,0)';$S;
    'VCCD_HV13':'(0,0,0,0,0,0,0,0,0,0,0,0,0,0,0,0,0,0,0,0,0,0,0,0,0,0,0,0,BE3,0,~
0,0,0,0,0,0,0,0,0,0,0,0)';$S;
    'VCCD_HV12':'(0,0,0,0,0,0,0,0,0,0,0,0,0,0,0,0,0,0,0,0,0,0,0,0,0,0,0,0,BE11,0~
,0,0,0,0,0,0,0,0,0,0,0,0)';$S;
    'VCCD_HV11':'(0,0,0,0,0,0,0,0,0,0,0,0,0,0,0,0,0,0,0,0,0,0,0,0,0,0,0,0,BA7,0,~
0,0,0,0,0,0,0,0,0,0,0,0)';$S;
    'VCCD_HV10':'(0,0,0,0,0,0,0,0,0,0,0,0,0,0,0,0,0,0,0,0,0,0,0,0,0,0,0,0,BA3,0,~
0,0,0,0,0,0,0,0,0,0,0,0)';$S;
    'VCCD_HV9':'(0,0,0,0,0,0,0,0,0,0,0,0,0,0,0,0,0,0,0,0,0,0,0,0,0,0,0,0,AV55,0,~
0,0,0,0,0,0,0,0,0,0,0,0)';$S;
    'VCCD_HV8':'(0,0,0,0,0,0,0,0,0,0,0,0,0,0,0,0,0,0,0,0,0,0,0,0,0,0,0,0,AV53,0,~
0,0,0,0,0,0,0,0,0,0,0,0)';$S;
    'VCCD_HV7':'(0,0,0,0,0,0,0,0,0,0,0,0,0,0,0,0,0,0,0,0,0,0,0,0,0,0,0,0,AV36,0,~
0,0,0,0,0,0,0,0,0,0,0,0)';$S;
    'VCCD_HV6':'(0,0,0,0,0,0,0,0,0,0,0,0,0,0,0,0,0,0,0,0,0,0,0,0,0,0,0,0,AV34,0,~
0,0,0,0,0,0,0,0,0,0,0,0)';$S;
    'VCCD_HV5':'(0,0,0,0,0,0,0,0,0,0,0,0,0,0,0,0,0,0,0,0,0,0,0,0,0,0,0,0,AU7,0,0~
,0,0,0,0,0,0,0,0,0,0,0)';$S;
    'VCCD_HV4':'(0,0,0,0,0,0,0,0,0,0,0,0,0,0,0,0,0,0,0,0,0,0,0,0,0,0,0,0,AU54,0,~
0,0,0,0,0,0,0,0,0,0,0,0)';$S;
    'VCCD_HV3':'(0,0,0,0,0,0,0,0,0,0,0,0,0,0,0,0,0,0,0,0,0,0,0,0,0,0,0,0,AU35,0,~
0,0,0,0,0,0,0,0,0,0,0,0)';$S;
    'VCCD_HV2':'(0,0,0,0,0,0,0,0,0,0,0,0,0,0,0,0,0,0,0,0,0,0,0,0,0,0,0,0,AU3,0,0~
,0,0,0,0,0,0,0,0,0,0,0)';$S;
    'VCCD_HV1':'(0,0,0,0,0,0,0,0,0,0,0,0,0,0,0,0,0,0,0,0,0,0,0,0,0,0,0,0,AT55,0,~
0,0,0,0,0,0,0,0,0,0,0,0)';$S;
    'VCCD_HV0':'(0,0,0,0,0,0,0,0,0,0,0,0,0,0,0,0,0,0,0,0,0,0,0,0,0,0,0,0,AT36,0,~
0,0,0,0,0,0,0,0,0,0,0,0)';$S;
    'VCCFA_EHV8':'(0,0,0,0,0,0,0,0,0,0,0,0,0,0,0,0,0,0,0,0,0,0,0,0,0,0,0,0,N3,0,~
0,0,0,0,0,0,0,0,0,0,0,0)';$S;
    'VCCFA_EHV9':'(0,0,0,0,0,0,0,0,0,0,0,0,0,0,0,0,0,0,0,0,0,0,0,0,0,0,0,0,U3,0,~
0,0,0,0,0,0,0,0,0,0,0,0)';$S;
    'VCCFA_EHV7':'(0,0,0,0,0,0,0,0,0,0,0,0,0,0,0,0,0,0,0,0,0,0,0,0,0,0,0,0,AW60,~
0,0,0,0,0,0,0,0,0,0,0,0,0)';$S;
    'VCCFA_EHV6':'(0,0,0,0,0,0,0,0,0,0,0,0,0,0,0,0,0,0,0,0,0,0,0,0,0,0,0,0,AV61,~
0,0,0,0,0,0,0,0,0,0,0,0,0)';$S;
    'VCCFA_EHV5':'(0,0,0,0,0,0,0,0,0,0,0,0,0,0,0,0,0,0,0,0,0,0,0,0,0,0,0,0,AU60,~
0,0,0,0,0,0,0,0,0,0,0,0,0)';$S;
    'VCCFA_EHV4':'(0,0,0,0,0,0,0,0,0,0,0,0,0,0,0,0,0,0,0,0,0,0,0,0,0,0,0,0,AT61,~
0,0,0,0,0,0,0,0,0,0,0,0,0)';$S;
    'VCCFA_EHV3':'(0,0,0,0,0,0,0,0,0,0,0,0,0,0,0,0,0,0,0,0,0,0,0,0,0,0,0,0,AN3,0~
,0,0,0,0,0,0,0,0,0,0,0,0)';$S;
    'VCCFA_EHV2':'(0,0,0,0,0,0,0,0,0,0,0,0,0,0,0,0,0,0,0,0,0,0,0,0,0,0,0,0,AJ3,0~
,0,0,0,0,0,0,0,0,0,0,0,0)';$S;
    'VCCFA_EHV1':'(0,0,0,0,0,0,0,0,0,0,0,0,0,0,0,0,0,0,0,0,0,0,0,0,0,0,0,0,AE3,0~
,0,0,0,0,0,0,0,0,0,0,0,0)';$S;
    'VCCFA_EHV0':'(0,0,0,0,0,0,0,0,0,0,0,0,0,0,0,0,0,0,0,0,0,0,0,0,0,0,0,0,AA3,0~
,0,0,0,0,0,0,0,0,0,0,0,0)';$S;
    'VCCINFAON59':'(0,0,0,0,0,0,0,0,0,0,0,0,0,0,0,0,0,0,0,0,0,0,0,0,0,0,0,0,DJ11~
,0,0,0,0,0,0,0,0,0,0,0,0,0)';$S;
    'VCCINFAON58':'(0,0,0,0,0,0,0,0,0,0,0,0,0,0,0,0,0,0,0,0,0,0,0,0,0,0,0,0,DE7,~
0,0,0,0,0,0,0,0,0,0,0,0,0)';$S;
    'VCCINFAON57':'(0,0,0,0,0,0,0,0,0,0,0,0,0,0,0,0,0,0,0,0,0,0,0,0,0,0,0,0,DA7,~
0,0,0,0,0,0,0,0,0,0,0,0,0)';$S;
    'VCCINFAON56':'(0,0,0,0,0,0,0,0,0,0,0,0,0,0,0,0,0,0,0,0,0,0,0,0,0,0,0,0,DA3,~
0,0,0,0,0,0,0,0,0,0,0,0,0)';$S;
    'VCCINFAON55':'(0,0,0,0,0,0,0,0,0,0,0,0,0,0,0,0,0,0,0,0,0,0,0,0,0,0,0,0,CW64~
,0,0,0,0,0,0,0,0,0,0,0,0,0)';$S;
    'VCCINFAON54':'(0,0,0,0,0,0,0,0,0,0,0,0,0,0,0,0,0,0,0,0,0,0,0,0,0,0,0,0,CR66~
,0,0,0,0,0,0,0,0,0,0,0,0,0)';$S;
    'VCCINFAON32':'(0,0,0,0,0,0,0,0,0,0,0,0,0,0,0,0,0,0,0,0,0,0,0,0,0,0,0,0,DJ7,~
0,0,0,0,0,0,0,0,0,0,0,0,0)';$S;
    'VCCINFAON31':'(0,0,0,0,0,0,0,0,0,0,0,0,0,0,0,0,0,0,0,0,0,0,0,0,0,0,0,0,DJ3,~
0,0,0,0,0,0,0,0,0,0,0,0,0)';$S;
    'VCCINFAON30':'(0,0,0,0,0,0,0,0,0,0,0,0,0,0,0,0,0,0,0,0,0,0,0,0,0,0,0,0,DJ15~
,0,0,0,0,0,0,0,0,0,0,0,0,0)';$S;
    'VCCINFAON29':'(0,0,0,0,0,0,0,0,0,0,0,0,0,0,0,0,0,0,0,0,0,0,0,0,0,0,0,0,DE3,~
0,0,0,0,0,0,0,0,0,0,0,0,0)';$S;
    'VCCINFAON28':'(0,0,0,0,0,0,0,0,0,0,0,0,0,0,0,0,0,0,0,0,0,0,0,0,0,0,0,0,DE15~
,0,0,0,0,0,0,0,0,0,0,0,0,0)';$S;
    'VCCINFAON27':'(0,0,0,0,0,0,0,0,0,0,0,0,0,0,0,0,0,0,0,0,0,0,0,0,0,0,0,0,DE11~
,0,0,0,0,0,0,0,0,0,0,0,0,0)';$S;
    'VCCINFAON26':'(0,0,0,0,0,0,0,0,0,0,0,0,0,0,0,0,0,0,0,0,0,0,0,0,0,0,0,0,DA64~
,0,0,0,0,0,0,0,0,0,0,0,0,0)';$S;
    'VCCINFAON25':'(0,0,0,0,0,0,0,0,0,0,0,0,0,0,0,0,0,0,0,0,0,0,0,0,0,0,0,0,DA15~
,0,0,0,0,0,0,0,0,0,0,0,0,0)';$S;
    'VCCINFAON24':'(0,0,0,0,0,0,0,0,0,0,0,0,0,0,0,0,0,0,0,0,0,0,0,0,0,0,0,0,DA11~
,0,0,0,0,0,0,0,0,0,0,0,0,0)';$S;
    'VCCINFAON23':'(0,0,0,0,0,0,0,0,0,0,0,0,0,0,0,0,0,0,0,0,0,0,0,0,0,0,0,0,CY67~
,0,0,0,0,0,0,0,0,0,0,0,0,0)';$S;
    'VCCINFAON22':'(0,0,0,0,0,0,0,0,0,0,0,0,0,0,0,0,0,0,0,0,0,0,0,0,0,0,0,0,CY65~
,0,0,0,0,0,0,0,0,0,0,0,0,0)';$S;
    'VCCINFAON21':'(0,0,0,0,0,0,0,0,0,0,0,0,0,0,0,0,0,0,0,0,0,0,0,0,0,0,0,0,CW66~
,0,0,0,0,0,0,0,0,0,0,0,0,0)';$S;
    'VCCINFAON20':'(0,0,0,0,0,0,0,0,0,0,0,0,0,0,0,0,0,0,0,0,0,0,0,0,0,0,0,0,CV67~
,0,0,0,0,0,0,0,0,0,0,0,0,0)';$S;
    'VCCINFAON19':'(0,0,0,0,0,0,0,0,0,0,0,0,0,0,0,0,0,0,0,0,0,0,0,0,0,0,0,0,CV65~
,0,0,0,0,0,0,0,0,0,0,0,0,0)';$S;
    'VCCINFAON18':'(0,0,0,0,0,0,0,0,0,0,0,0,0,0,0,0,0,0,0,0,0,0,0,0,0,0,0,0,CU7,~
0,0,0,0,0,0,0,0,0,0,0,0,0)';$S;
    'VCCINFAON17':'(0,0,0,0,0,0,0,0,0,0,0,0,0,0,0,0,0,0,0,0,0,0,0,0,0,0,0,0,CU64~
,0,0,0,0,0,0,0,0,0,0,0,0,0)';$S;
    'VCCINFAON16':'(0,0,0,0,0,0,0,0,0,0,0,0,0,0,0,0,0,0,0,0,0,0,0,0,0,0,0,0,CU3,~
0,0,0,0,0,0,0,0,0,0,0,0,0)';$S;
    'VCCINFAON15':'(0,0,0,0,0,0,0,0,0,0,0,0,0,0,0,0,0,0,0,0,0,0,0,0,0,0,0,0,CU15~
,0,0,0,0,0,0,0,0,0,0,0,0,0)';$S;
    'VCCINFAON14':'(0,0,0,0,0,0,0,0,0,0,0,0,0,0,0,0,0,0,0,0,0,0,0,0,0,0,0,0,CU11~
,0,0,0,0,0,0,0,0,0,0,0,0,0)';$S;
    'VCCINFAON13':'(0,0,0,0,0,0,0,0,0,0,0,0,0,0,0,0,0,0,0,0,0,0,0,0,0,0,0,0,CT67~
,0,0,0,0,0,0,0,0,0,0,0,0,0)';$S;
    'VCCINFAON12':'(0,0,0,0,0,0,0,0,0,0,0,0,0,0,0,0,0,0,0,0,0,0,0,0,0,0,0,0,CT65~
,0,0,0,0,0,0,0,0,0,0,0,0,0)';$S;
    'VCCINFAON11':'(0,0,0,0,0,0,0,0,0,0,0,0,0,0,0,0,0,0,0,0,0,0,0,0,0,0,0,0,CP67~
,0,0,0,0,0,0,0,0,0,0,0,0,0)';$S;
    'VCCINFAON10':'(0,0,0,0,0,0,0,0,0,0,0,0,0,0,0,0,0,0,0,0,0,0,0,0,0,0,0,0,CP65~
,0,0,0,0,0,0,0,0,0,0,0,0,0)';$S;
    'VCCINFAON9':'(0,0,0,0,0,0,0,0,0,0,0,0,0,0,0,0,0,0,0,0,0,0,0,0,0,0,0,0,CN7,0~
,0,0,0,0,0,0,0,0,0,0,0,0)';$S;
    'VCCINFAON8':'(0,0,0,0,0,0,0,0,0,0,0,0,0,0,0,0,0,0,0,0,0,0,0,0,0,0,0,0,CN66,~
0,0,0,0,0,0,0,0,0,0,0,0,0)';$S;
    'VCCINFAON7':'(0,0,0,0,0,0,0,0,0,0,0,0,0,0,0,0,0,0,0,0,0,0,0,0,0,0,0,0,CN64,~
0,0,0,0,0,0,0,0,0,0,0,0,0)';$S;
    'VCCINFAON6':'(0,0,0,0,0,0,0,0,0,0,0,0,0,0,0,0,0,0,0,0,0,0,0,0,0,0,0,0,CN3,0~
,0,0,0,0,0,0,0,0,0,0,0,0)';$S;
    'VCCINFAON5':'(0,0,0,0,0,0,0,0,0,0,0,0,0,0,0,0,0,0,0,0,0,0,0,0,0,0,0,0,CN15,~
0,0,0,0,0,0,0,0,0,0,0,0,0)';$S;
    'VCCINFAON4':'(0,0,0,0,0,0,0,0,0,0,0,0,0,0,0,0,0,0,0,0,0,0,0,0,0,0,0,0,CN11,~
0,0,0,0,0,0,0,0,0,0,0,0,0)';$S;
    'VCCINFAON3':'(0,0,0,0,0,0,0,0,0,0,0,0,0,0,0,0,0,0,0,0,0,0,0,0,0,0,0,0,CJ7,0~
,0,0,0,0,0,0,0,0,0,0,0,0)';$S;
    'VCCINFAON2':'(0,0,0,0,0,0,0,0,0,0,0,0,0,0,0,0,0,0,0,0,0,0,0,0,0,0,0,0,CJ3,0~
,0,0,0,0,0,0,0,0,0,0,0,0)';$S;
    'VCCINFAON1':'(0,0,0,0,0,0,0,0,0,0,0,0,0,0,0,0,0,0,0,0,0,0,0,0,0,0,0,0,CJ15,~
0,0,0,0,0,0,0,0,0,0,0,0,0)';$S;
    'VCCINFAON0':'(0,0,0,0,0,0,0,0,0,0,0,0,0,0,0,0,0,0,0,0,0,0,0,0,0,0,0,0,CE15,~
0,0,0,0,0,0,0,0,0,0,0,0,0)';$S;
    'VCCVNN3':'(0,0,0,0,0,0,0,0,0,0,0,0,0,0,0,0,0,0,0,0,0,0,0,0,0,0,0,0,BN19,0,0~
,0,0,0,0,0,0,0,0,0,0,0)';$S;
    'VCCVNN2':'(0,0,0,0,0,0,0,0,0,0,0,0,0,0,0,0,0,0,0,0,0,0,0,0,0,0,0,0,BJ19,0,0~
,0,0,0,0,0,0,0,0,0,0,0)';$S;
    'VCCVNN1':'(0,0,0,0,0,0,0,0,0,0,0,0,0,0,0,0,0,0,0,0,0,0,0,0,0,0,0,0,BE19,0,0~
,0,0,0,0,0,0,0,0,0,0,0)';$S;
    'VCCVNN0':'(0,0,0,0,0,0,0,0,0,0,0,0,0,0,0,0,0,0,0,0,0,0,0,0,0,0,0,0,BA19,0,0~
,0,0,0,0,0,0,0,0,0,0,0)';$S;
    'VPP_HBM':'(0,0,0,0,0,0,0,0,0,0,0,0,0,0,0,0,0,0,0,0,0,0,0,0,0,0,0,0,CG68,0,0~
,0,0,0,0,0,0,0,0,0,0,0)';$S;
    'VPP_HBM1':'(0,0,0,0,0,0,0,0,0,0,0,0,0,0,0,0,0,0,0,0,0,0,0,0,0,0,0,0,CF67,0,~
0,0,0,0,0,0,0,0,0,0,0,0)';$S;
    'VPP_HBM2':'(0,0,0,0,0,0,0,0,0,0,0,0,0,0,0,0,0,0,0,0,0,0,0,0,0,0,0,0,CE68,0,~
0,0,0,0,0,0,0,0,0,0,0,0)';$S;
    'VPP_HBM3':'(0,0,0,0,0,0,0,0,0,0,0,0,0,0,0,0,0,0,0,0,0,0,0,0,0,0,0,0,CD67,0,~
0,0,0,0,0,0,0,0,0,0,0,0)';$S;
    'VPP_HBM4':'(0,0,0,0,0,0,0,0,0,0,0,0,0,0,0,0,0,0,0,0,0,0,0,0,0,0,0,0,CC68,0,~
0,0,0,0,0,0,0,0,0,0,0,0)';$S;
    'VCCFA_EHV_FIVRA104':'(0,0,0,0,0,0,0,0,0,0,0,0,0,0,0,0,0,0,0,0,0,0,0,0,0,0,0~
,0,0,Y89,0,0,0,0,0,0,0,0,0,0,0,0)';$S;
    'VCCFA_EHV_FIVRA103':'(0,0,0,0,0,0,0,0,0,0,0,0,0,0,0,0,0,0,0,0,0,0,0,0,0,0,0~
,0,0,Y85,0,0,0,0,0,0,0,0,0,0,0,0)';$S;
    'VCCFA_EHV_FIVRA102':'(0,0,0,0,0,0,0,0,0,0,0,0,0,0,0,0,0,0,0,0,0,0,0,0,0,0,0~
,0,0,Y79,0,0,0,0,0,0,0,0,0,0,0,0)';$S;
    'VCCFA_EHV_FIVRA101':'(0,0,0,0,0,0,0,0,0,0,0,0,0,0,0,0,0,0,0,0,0,0,0,0,0,0,0~
,0,0,W80,0,0,0,0,0,0,0,0,0,0,0,0)';$S;
    'VCCFA_EHV_FIVRA100':'(0,0,0,0,0,0,0,0,0,0,0,0,0,0,0,0,0,0,0,0,0,0,0,0,0,0,0~
,0,0,U7,0,0,0,0,0,0,0,0,0,0,0,0)';$S;
    'VCCFA_EHV_FIVRA99':'(0,0,0,0,0,0,0,0,0,0,0,0,0,0,0,0,0,0,0,0,0,0,0,0,0,0,0,~
0,0,U15,0,0,0,0,0,0,0,0,0,0,0,0)';$S;
    'VCCFA_EHV_FIVRA98':'(0,0,0,0,0,0,0,0,0,0,0,0,0,0,0,0,0,0,0,0,0,0,0,0,0,0,0,~
0,0,U11,0,0,0,0,0,0,0,0,0,0,0,0)';$S;
    'VCCFA_EHV_FIVRA97':'(0,0,0,0,0,0,0,0,0,0,0,0,0,0,0,0,0,0,0,0,0,0,0,0,0,0,0,~
0,0,T89,0,0,0,0,0,0,0,0,0,0,0,0)';$S;
    'VCCFA_EHV_FIVRA96':'(0,0,0,0,0,0,0,0,0,0,0,0,0,0,0,0,0,0,0,0,0,0,0,0,0,0,0,~
0,0,T85,0,0,0,0,0,0,0,0,0,0,0,0)';$S;
    'VCCFA_EHV_FIVRA95':'(0,0,0,0,0,0,0,0,0,0,0,0,0,0,0,0,0,0,0,0,0,0,0,0,0,0,0,~
0,0,R80,0,0,0,0,0,0,0,0,0,0,0,0)';$S;
    'VCCFA_EHV_FIVRA94':'(0,0,0,0,0,0,0,0,0,0,0,0,0,0,0,0,0,0,0,0,0,0,0,0,0,0,0,~
0,0,P79,0,0,0,0,0,0,0,0,0,0,0,0)';$S;
    'VCCFA_EHV_FIVRA93':'(0,0,0,0,0,0,0,0,0,0,0,0,0,0,0,0,0,0,0,0,0,0,0,0,0,0,0,~
0,0,N7,0,0,0,0,0,0,0,0,0,0,0,0)';$S;
    'VCCFA_EHV_FIVRA92':'(0,0,0,0,0,0,0,0,0,0,0,0,0,0,0,0,0,0,0,0,0,0,0,0,0,0,0,~
0,0,N11,0,0,0,0,0,0,0,0,0,0,0,0)';$S;
    'VCCFA_EHV_FIVRA91':'(0,0,0,0,0,0,0,0,0,0,0,0,0,0,0,0,0,0,0,0,0,0,0,0,0,0,0,~
0,0,M89,0,0,0,0,0,0,0,0,0,0,0,0)';$S;
    'VCCFA_EHV_FIVRA90':'(0,0,0,0,0,0,0,0,0,0,0,0,0,0,0,0,0,0,0,0,0,0,0,0,0,0,0,~
0,0,M85,0,0,0,0,0,0,0,0,0,0,0,0)';$S;
    'VCCFA_EHV_FIVRA89':'(0,0,0,0,0,0,0,0,0,0,0,0,0,0,0,0,0,0,0,0,0,0,0,0,0,0,0,~
0,0,L84,0,0,0,0,0,0,0,0,0,0,0,0)';$S;
    'VCCFA_EHV_FIVRA88':'(0,0,0,0,0,0,0,0,0,0,0,0,0,0,0,0,0,0,0,0,0,0,0,0,0,0,0,~
0,0,K87,0,0,0,0,0,0,0,0,0,0,0,0)';$S;
    'VCCFA_EHV_FIVRA87':'(0,0,0,0,0,0,0,0,0,0,0,0,0,0,0,0,0,0,0,0,0,0,0,0,0,0,0,~
0,0,J80,0,0,0,0,0,0,0,0,0,0,0,0)';$S;
    'VCCFA_EHV_FIVRA86':'(0,0,0,0,0,0,0,0,0,0,0,0,0,0,0,0,0,0,0,0,0,0,0,0,0,0,0,~
0,0,J7,0,0,0,0,0,0,0,0,0,0,0,0)';$S;
    'VCCFA_EHV_FIVRA85':'(0,0,0,0,0,0,0,0,0,0,0,0,0,0,0,0,0,0,0,0,0,0,0,0,0,0,0,~
0,0,J11,0,0,0,0,0,0,0,0,0,0,0,0)';$S;
    'VCCFA_EHV_FIVRA84':'(0,0,0,0,0,0,0,0,0,0,0,0,0,0,0,0,0,0,0,0,0,0,0,0,0,0,0,~
0,0,H89,0,0,0,0,0,0,0,0,0,0,0,0)';$S;
    'VCCFA_EHV_FIVRA83':'(0,0,0,0,0,0,0,0,0,0,0,0,0,0,0,0,0,0,0,0,0,0,0,0,0,0,0,~
0,0,EN84,0,0,0,0,0,0,0,0,0,0,0,0)';$S;
    'VCCFA_EHV_FIVRA82':'(0,0,0,0,0,0,0,0,0,0,0,0,0,0,0,0,0,0,0,0,0,0,0,0,0,0,0,~
0,0,EJ84,0,0,0,0,0,0,0,0,0,0,0,0)';$S;
    'VCCFA_EHV_FIVRA81':'(0,0,0,0,0,0,0,0,0,0,0,0,0,0,0,0,0,0,0,0,0,0,0,0,0,0,0,~
0,0,EJ15,0,0,0,0,0,0,0,0,0,0,0,0)';$S;
    'VCCFA_EHV_FIVRA80':'(0,0,0,0,0,0,0,0,0,0,0,0,0,0,0,0,0,0,0,0,0,0,0,0,0,0,0,~
0,0,EG80,0,0,0,0,0,0,0,0,0,0,0,0)';$S;
    'VCCFA_EHV_FIVRA79':'(0,0,0,0,0,0,0,0,0,0,0,0,0,0,0,0,0,0,0,0,0,0,0,0,0,0,0,~
0,0,EF79,0,0,0,0,0,0,0,0,0,0,0,0)';$S;
    'VCCFA_EHV_FIVRA78':'(0,0,0,0,0,0,0,0,0,0,0,0,0,0,0,0,0,0,0,0,0,0,0,0,0,0,0,~
0,0,EE84,0,0,0,0,0,0,0,0,0,0,0,0)';$S;
    'VCCFA_EHV_FIVRA77':'(0,0,0,0,0,0,0,0,0,0,0,0,0,0,0,0,0,0,0,0,0,0,0,0,0,0,0,~
0,0,EE7,0,0,0,0,0,0,0,0,0,0,0,0)';$S;
    'VCCFA_EHV_FIVRA76':'(0,0,0,0,0,0,0,0,0,0,0,0,0,0,0,0,0,0,0,0,0,0,0,0,0,0,0,~
0,0,EE15,0,0,0,0,0,0,0,0,0,0,0,0)';$S;
    'VCCFA_EHV_FIVRA75':'(0,0,0,0,0,0,0,0,0,0,0,0,0,0,0,0,0,0,0,0,0,0,0,0,0,0,0,~
0,0,EE11,0,0,0,0,0,0,0,0,0,0,0,0)';$S;
    'VCCFA_EHV_FIVRA74':'(0,0,0,0,0,0,0,0,0,0,0,0,0,0,0,0,0,0,0,0,0,0,0,0,0,0,0,~
0,0,ED89,0,0,0,0,0,0,0,0,0,0,0,0)';$S;
    'VCCFA_EHV_FIVRA73':'(0,0,0,0,0,0,0,0,0,0,0,0,0,0,0,0,0,0,0,0,0,0,0,0,0,0,0,~
0,0,ED85,0,0,0,0,0,0,0,0,0,0,0,0)';$S;
    'VCCFA_EHV_FIVRA72':'(0,0,0,0,0,0,0,0,0,0,0,0,0,0,0,0,0,0,0,0,0,0,0,0,0,0,0,~
0,0,ED79,0,0,0,0,0,0,0,0,0,0,0,0)';$S;
    'VCCFA_EHV_FIVRA71':'(0,0,0,0,0,0,0,0,0,0,0,0,0,0,0,0,0,0,0,0,0,0,0,0,0,0,0,~
0,0,EC78,0,0,0,0,0,0,0,0,0,0,0,0)';$S;
    'VCCFA_EHV_FIVRA70':'(0,0,0,0,0,0,0,0,0,0,0,0,0,0,0,0,0,0,0,0,0,0,0,0,0,0,0,~
0,0,EA7,0,0,0,0,0,0,0,0,0,0,0,0)';$S;
    'VCCFA_EHV_FIVRA69':'(0,0,0,0,0,0,0,0,0,0,0,0,0,0,0,0,0,0,0,0,0,0,0,0,0,0,0,~
0,0,EA3,0,0,0,0,0,0,0,0,0,0,0,0)';$S;
    'VCCFA_EHV_FIVRA68':'(0,0,0,0,0,0,0,0,0,0,0,0,0,0,0,0,0,0,0,0,0,0,0,0,0,0,0,~
0,0,EA15,0,0,0,0,0,0,0,0,0,0,0,0)';$S;
    'VCCFA_EHV_FIVRA67':'(0,0,0,0,0,0,0,0,0,0,0,0,0,0,0,0,0,0,0,0,0,0,0,0,0,0,0,~
0,0,EA11,0,0,0,0,0,0,0,0,0,0,0,0)';$S;
    'VCCFA_EHV_FIVRA66':'(0,0,0,0,0,0,0,0,0,0,0,0,0,0,0,0,0,0,0,0,0,0,0,0,0,0,0,~
0,0,DY89,0,0,0,0,0,0,0,0,0,0,0,0)';$S;
    'VCCFA_EHV_FIVRA65':'(0,0,0,0,0,0,0,0,0,0,0,0,0,0,0,0,0,0,0,0,0,0,0,0,0,0,0,~
0,0,DY85,0,0,0,0,0,0,0,0,0,0,0,0)';$S;
    'VCCFA_EHV_FIVRA64':'(0,0,0,0,0,0,0,0,0,0,0,0,0,0,0,0,0,0,0,0,0,0,0,0,0,0,0,~
0,0,DU7,0,0,0,0,0,0,0,0,0,0,0,0)';$S;
    'VCCFA_EHV_FIVRA63':'(0,0,0,0,0,0,0,0,0,0,0,0,0,0,0,0,0,0,0,0,0,0,0,0,0,0,0,~
0,0,DU3,0,0,0,0,0,0,0,0,0,0,0,0)';$S;
    'VCCFA_EHV_FIVRA62':'(0,0,0,0,0,0,0,0,0,0,0,0,0,0,0,0,0,0,0,0,0,0,0,0,0,0,0,~
0,0,DU15,0,0,0,0,0,0,0,0,0,0,0,0)';$S;
    'VCCFA_EHV_FIVRA61':'(0,0,0,0,0,0,0,0,0,0,0,0,0,0,0,0,0,0,0,0,0,0,0,0,0,0,0,~
0,0,DU11,0,0,0,0,0,0,0,0,0,0,0,0)';$S;
    'VCCFA_EHV_FIVRA60':'(0,0,0,0,0,0,0,0,0,0,0,0,0,0,0,0,0,0,0,0,0,0,0,0,0,0,0,~
0,0,DT89,0,0,0,0,0,0,0,0,0,0,0,0)';$S;
    'VCCFA_EHV_FIVRA59':'(0,0,0,0,0,0,0,0,0,0,0,0,0,0,0,0,0,0,0,0,0,0,0,0,0,0,0,~
0,0,DT85,0,0,0,0,0,0,0,0,0,0,0,0)';$S;
    'VCCFA_EHV_FIVRA58':'(0,0,0,0,0,0,0,0,0,0,0,0,0,0,0,0,0,0,0,0,0,0,0,0,0,0,0,~
0,0,DT79,0,0,0,0,0,0,0,0,0,0,0,0)';$S;
    'VCCFA_EHV_FIVRA57':'(0,0,0,0,0,0,0,0,0,0,0,0,0,0,0,0,0,0,0,0,0,0,0,0,0,0,0,~
0,0,DN7,0,0,0,0,0,0,0,0,0,0,0,0)';$S;
    'VCCFA_EHV_FIVRA56':'(0,0,0,0,0,0,0,0,0,0,0,0,0,0,0,0,0,0,0,0,0,0,0,0,0,0,0,~
0,0,DN3,0,0,0,0,0,0,0,0,0,0,0,0)';$S;
    'VCCFA_EHV_FIVRA55':'(0,0,0,0,0,0,0,0,0,0,0,0,0,0,0,0,0,0,0,0,0,0,0,0,0,0,0,~
0,0,DN15,0,0,0,0,0,0,0,0,0,0,0,0)';$S;
    'VCCFA_EHV_FIVRA54':'(0,0,0,0,0,0,0,0,0,0,0,0,0,0,0,0,0,0,0,0,0,0,0,0,0,0,0,~
0,0,DN11,0,0,0,0,0,0,0,0,0,0,0,0)';$S;
    'VCCFA_EHV_FIVRA53':'(0,0,0,0,0,0,0,0,0,0,0,0,0,0,0,0,0,0,0,0,0,0,0,0,0,0,0,~
0,0,DM89,0,0,0,0,0,0,0,0,0,0,0,0)';$S;
    'VCCFA_EHV_FIVRA52':'(0,0,0,0,0,0,0,0,0,0,0,0,0,0,0,0,0,0,0,0,0,0,0,0,0,0,0,~
0,0,DM85,0,0,0,0,0,0,0,0,0,0,0,0)';$S;
    'VCCFA_EHV_FIVRA51':'(0,0,0,0,0,0,0,0,0,0,0,0,0,0,0,0,0,0,0,0,0,0,0,0,0,0,0,~
0,0,DM83,0,0,0,0,0,0,0,0,0,0,0,0)';$S;
    'VCCFA_EHV_FIVRA50':'(0,0,0,0,0,0,0,0,0,0,0,0,0,0,0,0,0,0,0,0,0,0,0,0,0,0,0,~
0,0,DH89,0,0,0,0,0,0,0,0,0,0,0,0)';$S;
    'VCCFA_EHV_FIVRA49':'(0,0,0,0,0,0,0,0,0,0,0,0,0,0,0,0,0,0,0,0,0,0,0,0,0,0,0,~
0,0,DD89,0,0,0,0,0,0,0,0,0,0,0,0)';$S;
    'VCCFA_EHV_FIVRA48':'(0,0,0,0,0,0,0,0,0,0,0,0,0,0,0,0,0,0,0,0,0,0,0,0,0,0,0,~
0,0,DD85,0,0,0,0,0,0,0,0,0,0,0,0)';$S;
    'VCCFA_EHV_FIVRA47':'(0,0,0,0,0,0,0,0,0,0,0,0,0,0,0,0,0,0,0,0,0,0,0,0,0,0,0,~
0,0,DD83,0,0,0,0,0,0,0,0,0,0,0,0)';$S;
    'VCCFA_EHV_FIVRA46':'(0,0,0,0,0,0,0,0,0,0,0,0,0,0,0,0,0,0,0,0,0,0,0,0,0,0,0,~
0,0,DD77,0,0,0,0,0,0,0,0,0,0,0,0)';$S;
    'VCCFA_EHV_FIVRA45':'(0,0,0,0,0,0,0,0,0,0,0,0,0,0,0,0,0,0,0,0,0,0,0,0,0,0,0,~
0,0,CY89,0,0,0,0,0,0,0,0,0,0,0,0)';$S;
    'VCCFA_EHV_FIVRA44':'(0,0,0,0,0,0,0,0,0,0,0,0,0,0,0,0,0,0,0,0,0,0,0,0,0,0,0,~
0,0,CY85,0,0,0,0,0,0,0,0,0,0,0,0)';$S;
    'VCCFA_EHV_FIVRA43':'(0,0,0,0,0,0,0,0,0,0,0,0,0,0,0,0,0,0,0,0,0,0,0,0,0,0,0,~
0,0,CY79,0,0,0,0,0,0,0,0,0,0,0,0)';$S;
    'VCCFA_EHV_FIVRA42':'(0,0,0,0,0,0,0,0,0,0,0,0,0,0,0,0,0,0,0,0,0,0,0,0,0,0,0,~
0,0,CY75,0,0,0,0,0,0,0,0,0,0,0,0)';$S;
    'VCCFA_EHV_FIVRA41':'(0,0,0,0,0,0,0,0,0,0,0,0,0,0,0,0,0,0,0,0,0,0,0,0,0,0,0,~
0,0,CT85,0,0,0,0,0,0,0,0,0,0,0,0)';$S;
    'VCCFA_EHV_FIVRA40':'(0,0,0,0,0,0,0,0,0,0,0,0,0,0,0,0,0,0,0,0,0,0,0,0,0,0,0,~
0,0,CT77,0,0,0,0,0,0,0,0,0,0,0,0)';$S;
    'VCCFA_EHV_FIVRA39':'(0,0,0,0,0,0,0,0,0,0,0,0,0,0,0,0,0,0,0,0,0,0,0,0,0,0,0,~
0,0,CP73,0,0,0,0,0,0,0,0,0,0,0,0)';$S;
    'VCCFA_EHV_FIVRA38':'(0,0,0,0,0,0,0,0,0,0,0,0,0,0,0,0,0,0,0,0,0,0,0,0,0,0,0,~
0,0,CN78,0,0,0,0,0,0,0,0,0,0,0,0)';$S;
    'VCCFA_EHV_FIVRA37':'(0,0,0,0,0,0,0,0,0,0,0,0,0,0,0,0,0,0,0,0,0,0,0,0,0,0,0,~
0,0,CM73,0,0,0,0,0,0,0,0,0,0,0,0)';$S;
    'VCCFA_EHV_FIVRA36':'(0,0,0,0,0,0,0,0,0,0,0,0,0,0,0,0,0,0,0,0,0,0,0,0,0,0,0,~
0,0,CK79,0,0,0,0,0,0,0,0,0,0,0,0)';$S;
    'VCCFA_EHV_FIVRA35':'(0,0,0,0,0,0,0,0,0,0,0,0,0,0,0,0,0,0,0,0,0,0,0,0,0,0,0,~
0,0,CK73,0,0,0,0,0,0,0,0,0,0,0,0)';$S;
    'VCCFA_EHV_FIVRA34':'(0,0,0,0,0,0,0,0,0,0,0,0,0,0,0,0,0,0,0,0,0,0,0,0,0,0,0,~
0,0,CE74,0,0,0,0,0,0,0,0,0,0,0,0)';$S;
    'VCCFA_EHV_FIVRA33':'(0,0,0,0,0,0,0,0,0,0,0,0,0,0,0,0,0,0,0,0,0,0,0,0,0,0,0,~
0,0,C88,0,0,0,0,0,0,0,0,0,0,0,0)';$S;
    'VCCFA_EHV_FIVRA32':'(0,0,0,0,0,0,0,0,0,0,0,0,0,0,0,0,0,0,0,0,0,0,0,0,0,0,0,~
0,0,C84,0,0,0,0,0,0,0,0,0,0,0,0)';$S;
    'VCCFA_EHV_FIVRA31':'(0,0,0,0,0,0,0,0,0,0,0,0,0,0,0,0,0,0,0,0,0,0,0,0,0,0,0,~
0,0,BJ78,0,0,0,0,0,0,0,0,0,0,0,0)';$S;
    'VCCFA_EHV_FIVRA30':'(0,0,0,0,0,0,0,0,0,0,0,0,0,0,0,0,0,0,0,0,0,0,0,0,0,0,0,~
0,0,BJ72,0,0,0,0,0,0,0,0,0,0,0,0)';$S;
    'VCCFA_EHV_FIVRA29':'(0,0,0,0,0,0,0,0,0,0,0,0,0,0,0,0,0,0,0,0,0,0,0,0,0,0,0,~
0,0,BH79,0,0,0,0,0,0,0,0,0,0,0,0)';$S;
    'VCCFA_EHV_FIVRA28':'(0,0,0,0,0,0,0,0,0,0,0,0,0,0,0,0,0,0,0,0,0,0,0,0,0,0,0,~
0,0,BF77,0,0,0,0,0,0,0,0,0,0,0,0)';$S;
    'VCCFA_EHV_FIVRA27':'(0,0,0,0,0,0,0,0,0,0,0,0,0,0,0,0,0,0,0,0,0,0,0,0,0,0,0,~
0,0,BE72,0,0,0,0,0,0,0,0,0,0,0,0)';$S;
    'VCCFA_EHV_FIVRA26':'(0,0,0,0,0,0,0,0,0,0,0,0,0,0,0,0,0,0,0,0,0,0,0,0,0,0,0,~
0,0,AY89,0,0,0,0,0,0,0,0,0,0,0,0)';$S;
    'VCCFA_EHV_FIVRA25':'(0,0,0,0,0,0,0,0,0,0,0,0,0,0,0,0,0,0,0,0,0,0,0,0,0,0,0,~
0,0,AW76,0,0,0,0,0,0,0,0,0,0,0,0)';$S;
    'VCCFA_EHV_FIVRA24':'(0,0,0,0,0,0,0,0,0,0,0,0,0,0,0,0,0,0,0,0,0,0,0,0,0,0,0,~
0,0,AU15,0,0,0,0,0,0,0,0,0,0,0,0)';$S;
    'VCCFA_EHV_FIVRA23':'(0,0,0,0,0,0,0,0,0,0,0,0,0,0,0,0,0,0,0,0,0,0,0,0,0,0,0,~
0,0,AT89,0,0,0,0,0,0,0,0,0,0,0,0)';$S;
    'VCCFA_EHV_FIVRA22':'(0,0,0,0,0,0,0,0,0,0,0,0,0,0,0,0,0,0,0,0,0,0,0,0,0,0,0,~
0,0,AT73,0,0,0,0,0,0,0,0,0,0,0,0)';$S;
    'VCCFA_EHV_FIVRA21':'(0,0,0,0,0,0,0,0,0,0,0,0,0,0,0,0,0,0,0,0,0,0,0,0,0,0,0,~
0,0,AN80,0,0,0,0,0,0,0,0,0,0,0,0)';$S;
    'VCCFA_EHV_FIVRA20':'(0,0,0,0,0,0,0,0,0,0,0,0,0,0,0,0,0,0,0,0,0,0,0,0,0,0,0,~
0,0,AN7,0,0,0,0,0,0,0,0,0,0,0,0)';$S;
    'VCCFA_EHV_FIVRA19':'(0,0,0,0,0,0,0,0,0,0,0,0,0,0,0,0,0,0,0,0,0,0,0,0,0,0,0,~
0,0,AN15,0,0,0,0,0,0,0,0,0,0,0,0)';$S;
    'VCCFA_EHV_FIVRA18':'(0,0,0,0,0,0,0,0,0,0,0,0,0,0,0,0,0,0,0,0,0,0,0,0,0,0,0,~
0,0,AN11,0,0,0,0,0,0,0,0,0,0,0,0)';$S;
    'VCCFA_EHV_FIVRA17':'(0,0,0,0,0,0,0,0,0,0,0,0,0,0,0,0,0,0,0,0,0,0,0,0,0,0,0,~
0,0,AM89,0,0,0,0,0,0,0,0,0,0,0,0)';$S;
    'VCCFA_EHV_FIVRA16':'(0,0,0,0,0,0,0,0,0,0,0,0,0,0,0,0,0,0,0,0,0,0,0,0,0,0,0,~
0,0,AM85,0,0,0,0,0,0,0,0,0,0,0,0)';$S;
    'VCCFA_EHV_FIVRA15':'(0,0,0,0,0,0,0,0,0,0,0,0,0,0,0,0,0,0,0,0,0,0,0,0,0,0,0,~
0,0,AM79,0,0,0,0,0,0,0,0,0,0,0,0)';$S;
    'VCCFA_EHV_FIVRA14':'(0,0,0,0,0,0,0,0,0,0,0,0,0,0,0,0,0,0,0,0,0,0,0,0,0,0,0,~
0,0,AJ7,0,0,0,0,0,0,0,0,0,0,0,0)';$S;
    'VCCFA_EHV_FIVRA13':'(0,0,0,0,0,0,0,0,0,0,0,0,0,0,0,0,0,0,0,0,0,0,0,0,0,0,0,~
0,0,AJ15,0,0,0,0,0,0,0,0,0,0,0,0)';$S;
    'VCCFA_EHV_FIVRA12':'(0,0,0,0,0,0,0,0,0,0,0,0,0,0,0,0,0,0,0,0,0,0,0,0,0,0,0,~
0,0,AJ11,0,0,0,0,0,0,0,0,0,0,0,0)';$S;
    'VCCFA_EHV_FIVRA11':'(0,0,0,0,0,0,0,0,0,0,0,0,0,0,0,0,0,0,0,0,0,0,0,0,0,0,0,~
0,0,AH89,0,0,0,0,0,0,0,0,0,0,0,0)';$S;
    'VCCFA_EHV_FIVRA10':'(0,0,0,0,0,0,0,0,0,0,0,0,0,0,0,0,0,0,0,0,0,0,0,0,0,0,0,~
0,0,AH85,0,0,0,0,0,0,0,0,0,0,0,0)';$S;
    'VCCFA_EHV_FIVRA9':'(0,0,0,0,0,0,0,0,0,0,0,0,0,0,0,0,0,0,0,0,0,0,0,0,0,0,0,0~
,0,AG78,0,0,0,0,0,0,0,0,0,0,0,0)';$S;
    'VCCFA_EHV_FIVRA8':'(0,0,0,0,0,0,0,0,0,0,0,0,0,0,0,0,0,0,0,0,0,0,0,0,0,0,0,0~
,0,AF77,0,0,0,0,0,0,0,0,0,0,0,0)';$S;
    'VCCFA_EHV_FIVRA7':'(0,0,0,0,0,0,0,0,0,0,0,0,0,0,0,0,0,0,0,0,0,0,0,0,0,0,0,0~
,0,AE7,0,0,0,0,0,0,0,0,0,0,0,0)';$S;
    'VCCFA_EHV_FIVRA6':'(0,0,0,0,0,0,0,0,0,0,0,0,0,0,0,0,0,0,0,0,0,0,0,0,0,0,0,0~
,0,AE15,0,0,0,0,0,0,0,0,0,0,0,0)';$S;
    'VCCFA_EHV_FIVRA5':'(0,0,0,0,0,0,0,0,0,0,0,0,0,0,0,0,0,0,0,0,0,0,0,0,0,0,0,0~
,0,AE11,0,0,0,0,0,0,0,0,0,0,0,0)';$S;
    'VCCFA_EHV_FIVRA4':'(0,0,0,0,0,0,0,0,0,0,0,0,0,0,0,0,0,0,0,0,0,0,0,0,0,0,0,0~
,0,AD89,0,0,0,0,0,0,0,0,0,0,0,0)';$S;
    'VCCFA_EHV_FIVRA3':'(0,0,0,0,0,0,0,0,0,0,0,0,0,0,0,0,0,0,0,0,0,0,0,0,0,0,0,0~
,0,AD85,0,0,0,0,0,0,0,0,0,0,0,0)';$S;
    'VCCFA_EHV_FIVRA2':'(0,0,0,0,0,0,0,0,0,0,0,0,0,0,0,0,0,0,0,0,0,0,0,0,0,0,0,0~
,0,AA7,0,0,0,0,0,0,0,0,0,0,0,0)';$S;
    'VCCFA_EHV_FIVRA1':'(0,0,0,0,0,0,0,0,0,0,0,0,0,0,0,0,0,0,0,0,0,0,0,0,0,0,0,0~
,0,AA15,0,0,0,0,0,0,0,0,0,0,0,0)';$S;
    'VCCFA_EHV_FIVRA0':'(0,0,0,0,0,0,0,0,0,0,0,0,0,0,0,0,0,0,0,0,0,0,0,0,0,0,0,0~
,0,AA11,0,0,0,0,0,0,0,0,0,0,0,0)';$S;
    'VSS1834':'(0,0,0,0,0,0,0,0,0,0,0,0,0,0,0,0,0,0,0,0,0,0,0,0,0,0,0,0,0,0,ER41~
,0,0,0,0,0,0,0,0,0,0,0)';$S;
    'VSS1835':'(0,0,0,0,0,0,0,0,0,0,0,0,0,0,0,0,0,0,0,0,0,0,0,0,0,0,0,0,0,0,ER43~
,0,0,0,0,0,0,0,0,0,0,0)';$S;
    'VSS1836':'(0,0,0,0,0,0,0,0,0,0,0,0,0,0,0,0,0,0,0,0,0,0,0,0,0,0,0,0,0,0,ER48~
,0,0,0,0,0,0,0,0,0,0,0)';$S;
    'VSS1837':'(0,0,0,0,0,0,0,0,0,0,0,0,0,0,0,0,0,0,0,0,0,0,0,0,0,0,0,0,0,0,ER50~
,0,0,0,0,0,0,0,0,0,0,0)';$S;
    'VSS1569':'(0,0,0,0,0,0,0,0,0,0,0,0,0,0,0,0,0,0,0,0,0,0,0,0,0,0,0,0,0,0,ET57~
,0,0,0,0,0,0,0,0,0,0,0)';$S;
    'VSS1565':'(0,0,0,0,0,0,0,0,0,0,0,0,0,0,0,0,0,0,0,0,0,0,0,0,0,0,0,0,0,0,ET38~
,0,0,0,0,0,0,0,0,0,0,0)';$S;
    'VSS1563':'(0,0,0,0,0,0,0,0,0,0,0,0,0,0,0,0,0,0,0,0,0,0,0,0,0,0,0,0,0,0,ET34~
,0,0,0,0,0,0,0,0,0,0,0)';$S;
    'VSS1562':'(0,0,0,0,0,0,0,0,0,0,0,0,0,0,0,0,0,0,0,0,0,0,0,0,0,0,0,0,0,0,ET28~
,0,0,0,0,0,0,0,0,0,0,0)';$S;
    'VSS1561':'(0,0,0,0,0,0,0,0,0,0,0,0,0,0,0,0,0,0,0,0,0,0,0,0,0,0,0,0,0,0,ET22~
,0,0,0,0,0,0,0,0,0,0,0)';$S;
    'VSS1559':'(0,0,0,0,0,0,0,0,0,0,0,0,0,0,0,0,0,0,0,0,0,0,0,0,0,0,0,0,0,0,ET16~
,0,0,0,0,0,0,0,0,0,0,0)';$S;
    'VSS1557':'(0,0,0,0,0,0,0,0,0,0,0,0,0,0,0,0,0,0,0,0,0,0,0,0,0,0,0,0,0,0,ET10~
,0,0,0,0,0,0,0,0,0,0,0)';$S;
    'VSS1556':'(0,0,0,0,0,0,0,0,0,0,0,0,0,0,0,0,0,0,0,0,0,0,0,0,0,0,0,0,0,0,ER86~
,0,0,0,0,0,0,0,0,0,0,0)';$S;
    'VSS1555':'(0,0,0,0,0,0,0,0,0,0,0,0,0,0,0,0,0,0,0,0,0,0,0,0,0,0,0,0,0,0,ER84~
,0,0,0,0,0,0,0,0,0,0,0)';$S;
    'VSS1554':'(0,0,0,0,0,0,0,0,0,0,0,0,0,0,0,0,0,0,0,0,0,0,0,0,0,0,0,0,0,0,ER80~
,0,0,0,0,0,0,0,0,0,0,0)';$S;
    'VSS1553':'(0,0,0,0,0,0,0,0,0,0,0,0,0,0,0,0,0,0,0,0,0,0,0,0,0,0,0,0,0,0,ER78~
,0,0,0,0,0,0,0,0,0,0,0)';$S;
    'VSS1552':'(0,0,0,0,0,0,0,0,0,0,0,0,0,0,0,0,0,0,0,0,0,0,0,0,0,0,0,0,0,0,ER74~
,0,0,0,0,0,0,0,0,0,0,0)';$S;
    'VSS1551':'(0,0,0,0,0,0,0,0,0,0,0,0,0,0,0,0,0,0,0,0,0,0,0,0,0,0,0,0,0,0,ER70~
,0,0,0,0,0,0,0,0,0,0,0)';$S;
    'VSS1550':'(0,0,0,0,0,0,0,0,0,0,0,0,0,0,0,0,0,0,0,0,0,0,0,0,0,0,0,0,0,0,ER7,~
0,0,0,0,0,0,0,0,0,0,0)';$S;
    'VSS1549':'(0,0,0,0,0,0,0,0,0,0,0,0,0,0,0,0,0,0,0,0,0,0,0,0,0,0,0,0,0,0,ER5,~
0,0,0,0,0,0,0,0,0,0,0)';$S;
    'VSS1548':'(0,0,0,0,0,0,0,0,0,0,0,0,0,0,0,0,0,0,0,0,0,0,0,0,0,0,0,0,0,0,ER33~
,0,0,0,0,0,0,0,0,0,0,0)';$S;
    'VSS1547':'(0,0,0,0,0,0,0,0,0,0,0,0,0,0,0,0,0,0,0,0,0,0,0,0,0,0,0,0,0,0,ER27~
,0,0,0,0,0,0,0,0,0,0,0)';$S;
    'VSS1545':'(0,0,0,0,0,0,0,0,0,0,0,0,0,0,0,0,0,0,0,0,0,0,0,0,0,0,0,0,0,0,EP83~
,0,0,0,0,0,0,0,0,0,0,0)';$S;
    'VSS1543':'(0,0,0,0,0,0,0,0,0,0,0,0,0,0,0,0,0,0,0,0,0,0,0,0,0,0,0,0,0,0,EP67~
,0,0,0,0,0,0,0,0,0,0,0)';$S;
    'VSS1542':'(0,0,0,0,0,0,0,0,0,0,0,0,0,0,0,0,0,0,0,0,0,0,0,0,0,0,0,0,0,0,EN80~
,0,0,0,0,0,0,0,0,0,0,0)';$S;
    'VSS1541':'(0,0,0,0,0,0,0,0,0,0,0,0,0,0,0,0,0,0,0,0,0,0,0,0,0,0,0,0,0,0,EN78~
,0,0,0,0,0,0,0,0,0,0,0)';$S;
    'VSS1540':'(0,0,0,0,0,0,0,0,0,0,0,0,0,0,0,0,0,0,0,0,0,0,0,0,0,0,0,0,0,0,EN64~
,0,0,0,0,0,0,0,0,0,0,0)';$S;
    'VSS1539':'(0,0,0,0,0,0,0,0,0,0,0,0,0,0,0,0,0,0,0,0,0,0,0,0,0,0,0,0,0,0,EN56~
,0,0,0,0,0,0,0,0,0,0,0)';$S;
    'VSS1537':'(0,0,0,0,0,0,0,0,0,0,0,0,0,0,0,0,0,0,0,0,0,0,0,0,0,0,0,0,0,0,EN54~
,0,0,0,0,0,0,0,0,0,0,0)';$S;
    'VSS1533':'(0,0,0,0,0,0,0,0,0,0,0,0,0,0,0,0,0,0,0,0,0,0,0,0,0,0,0,0,0,0,EN52~
,0,0,0,0,0,0,0,0,0,0,0)';$S;
    'VSS1531':'(0,0,0,0,0,0,0,0,0,0,0,0,0,0,0,0,0,0,0,0,0,0,0,0,0,0,0,0,0,0,EN50~
,0,0,0,0,0,0,0,0,0,0,0)';$S;
    'VSS1530':'(0,0,0,0,0,0,0,0,0,0,0,0,0,0,0,0,0,0,0,0,0,0,0,0,0,0,0,0,0,0,EN48~
,0,0,0,0,0,0,0,0,0,0,0)';$S;
    'VSS1529':'(0,0,0,0,0,0,0,0,0,0,0,0,0,0,0,0,0,0,0,0,0,0,0,0,0,0,0,0,0,0,EN45~
,0,0,0,0,0,0,0,0,0,0,0)';$S;
    'VSS1528':'(0,0,0,0,0,0,0,0,0,0,0,0,0,0,0,0,0,0,0,0,0,0,0,0,0,0,0,0,0,0,EN43~
,0,0,0,0,0,0,0,0,0,0,0)';$S;
    'VSS1526':'(0,0,0,0,0,0,0,0,0,0,0,0,0,0,0,0,0,0,0,0,0,0,0,0,0,0,0,0,0,0,EN41~
,0,0,0,0,0,0,0,0,0,0,0)';$S;
    'VSS1525':'(0,0,0,0,0,0,0,0,0,0,0,0,0,0,0,0,0,0,0,0,0,0,0,0,0,0,0,0,0,0,EN37~
,0,0,0,0,0,0,0,0,0,0,0)';$S;
    'VSS1524':'(0,0,0,0,0,0,0,0,0,0,0,0,0,0,0,0,0,0,0,0,0,0,0,0,0,0,0,0,0,0,EN35~
,0,0,0,0,0,0,0,0,0,0,0)';$S;
    'VSS1522':'(0,0,0,0,0,0,0,0,0,0,0,0,0,0,0,0,0,0,0,0,0,0,0,0,0,0,0,0,0,0,EN33~
,0,0,0,0,0,0,0,0,0,0,0)';$S;
    'VSS1520':'(0,0,0,0,0,0,0,0,0,0,0,0,0,0,0,0,0,0,0,0,0,0,0,0,0,0,0,0,0,0,EN31~
,0,0,0,0,0,0,0,0,0,0,0)';$S;
    'VSS1518':'(0,0,0,0,0,0,0,0,0,0,0,0,0,0,0,0,0,0,0,0,0,0,0,0,0,0,0,0,0,0,EN29~
,0,0,0,0,0,0,0,0,0,0,0)';$S;
    'VSS1517':'(0,0,0,0,0,0,0,0,0,0,0,0,0,0,0,0,0,0,0,0,0,0,0,0,0,0,0,0,0,0,EN27~
,0,0,0,0,0,0,0,0,0,0,0)';$S;
    'VSS1515':'(0,0,0,0,0,0,0,0,0,0,0,0,0,0,0,0,0,0,0,0,0,0,0,0,0,0,0,0,0,0,EN25~
,0,0,0,0,0,0,0,0,0,0,0)';$S;
    'VSS1513':'(0,0,0,0,0,0,0,0,0,0,0,0,0,0,0,0,0,0,0,0,0,0,0,0,0,0,0,0,0,0,EN23~
,0,0,0,0,0,0,0,0,0,0,0)';$S;
    'VSS1512':'(0,0,0,0,0,0,0,0,0,0,0,0,0,0,0,0,0,0,0,0,0,0,0,0,0,0,0,0,0,0,EN21~
,0,0,0,0,0,0,0,0,0,0,0)';$S;
    'VSS1506':'(0,0,0,0,0,0,0,0,0,0,0,0,0,0,0,0,0,0,0,0,0,0,0,0,0,0,0,0,0,0,EN19~
,0,0,0,0,0,0,0,0,0,0,0)';$S;
    'VSS1505':'(0,0,0,0,0,0,0,0,0,0,0,0,0,0,0,0,0,0,0,0,0,0,0,0,0,0,0,0,0,0,EN17~
,0,0,0,0,0,0,0,0,0,0,0)';$S;
    'VSS1503':'(0,0,0,0,0,0,0,0,0,0,0,0,0,0,0,0,0,0,0,0,0,0,0,0,0,0,0,0,0,0,EN15~
,0,0,0,0,0,0,0,0,0,0,0)';$S;
    'VSS1501':'(0,0,0,0,0,0,0,0,0,0,0,0,0,0,0,0,0,0,0,0,0,0,0,0,0,0,0,0,0,0,EN13~
,0,0,0,0,0,0,0,0,0,0,0)';$S;
    'VSS1500':'(0,0,0,0,0,0,0,0,0,0,0,0,0,0,0,0,0,0,0,0,0,0,0,0,0,0,0,0,0,0,EN11~
,0,0,0,0,0,0,0,0,0,0,0)';$S;
    'VSS1499':'(0,0,0,0,0,0,0,0,0,0,0,0,0,0,0,0,0,0,0,0,0,0,0,0,0,0,0,0,0,0,EM83~
,0,0,0,0,0,0,0,0,0,0,0)';$S;
    'VSS1498':'(0,0,0,0,0,0,0,0,0,0,0,0,0,0,0,0,0,0,0,0,0,0,0,0,0,0,0,0,0,0,EM81~
,0,0,0,0,0,0,0,0,0,0,0)';$S;
    'VSS1497':'(0,0,0,0,0,0,0,0,0,0,0,0,0,0,0,0,0,0,0,0,0,0,0,0,0,0,0,0,0,0,EM8,~
0,0,0,0,0,0,0,0,0,0,0)';$S;
    'VSS1496':'(0,0,0,0,0,0,0,0,0,0,0,0,0,0,0,0,0,0,0,0,0,0,0,0,0,0,0,0,0,0,EM73~
,0,0,0,0,0,0,0,0,0,0,0)';$S;
    'VSS1493':'(0,0,0,0,0,0,0,0,0,0,0,0,0,0,0,0,0,0,0,0,0,0,0,0,0,0,0,0,0,0,ET59~
,0,0,0,0,0,0,0,0,0,0,0)';$S;
    'VSS1492':'(0,0,0,0,0,0,0,0,0,0,0,0,0,0,0,0,0,0,0,0,0,0,0,0,0,0,0,0,0,0,EM42~
,0,0,0,0,0,0,0,0,0,0,0)';$S;
    'VSS1491':'(0,0,0,0,0,0,0,0,0,0,0,0,0,0,0,0,0,0,0,0,0,0,0,0,0,0,0,0,0,0,ET53~
,0,0,0,0,0,0,0,0,0,0,0)';$S;
    'VSS1489':'(0,0,0,0,0,0,0,0,0,0,0,0,0,0,0,0,0,0,0,0,0,0,0,0,0,0,0,0,0,0,EL76~
,0,0,0,0,0,0,0,0,0,0,0)';$S;
    'VSS1488':'(0,0,0,0,0,0,0,0,0,0,0,0,0,0,0,0,0,0,0,0,0,0,0,0,0,0,0,0,0,0,EL64~
,0,0,0,0,0,0,0,0,0,0,0)';$S;
    'VSS1486':'(0,0,0,0,0,0,0,0,0,0,0,0,0,0,0,0,0,0,0,0,0,0,0,0,0,0,0,0,0,0,EL5,~
0,0,0,0,0,0,0,0,0,0,0)';$S;
    'VSS1485':'(0,0,0,0,0,0,0,0,0,0,0,0,0,0,0,0,0,0,0,0,0,0,0,0,0,0,0,0,0,0,EL45~
,0,0,0,0,0,0,0,0,0,0,0)';$S;
    'VSS1484':'(0,0,0,0,0,0,0,0,0,0,0,0,0,0,0,0,0,0,0,0,0,0,0,0,0,0,0,0,0,0,ET32~
,0,0,0,0,0,0,0,0,0,0,0)';$S;
    'VSS1483':'(0,0,0,0,0,0,0,0,0,0,0,0,0,0,0,0,0,0,0,0,0,0,0,0,0,0,0,0,0,0,EL39~
,0,0,0,0,0,0,0,0,0,0,0)';$S;
    'VSS1482':'(0,0,0,0,0,0,0,0,0,0,0,0,0,0,0,0,0,0,0,0,0,0,0,0,0,0,0,0,0,0,ET26~
,0,0,0,0,0,0,0,0,0,0,0)';$S;
    'VSS1481':'(0,0,0,0,0,0,0,0,0,0,0,0,0,0,0,0,0,0,0,0,0,0,0,0,0,0,0,0,0,0,EL33~
,0,0,0,0,0,0,0,0,0,0,0)';$S;
    'VSS1480':'(0,0,0,0,0,0,0,0,0,0,0,0,0,0,0,0,0,0,0,0,0,0,0,0,0,0,0,0,0,0,ET20~
,0,0,0,0,0,0,0,0,0,0,0)';$S;
    'VSS1479':'(0,0,0,0,0,0,0,0,0,0,0,0,0,0,0,0,0,0,0,0,0,0,0,0,0,0,0,0,0,0,EL3,~
0,0,0,0,0,0,0,0,0,0,0)';$S;
    'VSS1478':'(0,0,0,0,0,0,0,0,0,0,0,0,0,0,0,0,0,0,0,0,0,0,0,0,0,0,0,0,0,0,ET14~
,0,0,0,0,0,0,0,0,0,0,0)';$S;
    'VSS1477':'(0,0,0,0,0,0,0,0,0,0,0,0,0,0,0,0,0,0,0,0,0,0,0,0,0,0,0,0,0,0,EL27~
,0,0,0,0,0,0,0,0,0,0,0)';$S;
    'VSS1476':'(0,0,0,0,0,0,0,0,0,0,0,0,0,0,0,0,0,0,0,0,0,0,0,0,0,0,0,0,0,0,ER9,~
0,0,0,0,0,0,0,0,0,0,0)';$S;
    'VSS1475':'(0,0,0,0,0,0,0,0,0,0,0,0,0,0,0,0,0,0,0,0,0,0,0,0,0,0,0,0,0,0,EL21~
,0,0,0,0,0,0,0,0,0,0,0)';$S;
    'VSS1474':'(0,0,0,0,0,0,0,0,0,0,0,0,0,0,0,0,0,0,0,0,0,0,0,0,0,0,0,0,0,0,EK75~
,0,0,0,0,0,0,0,0,0,0,0)';$S;
    'VSS1473':'(0,0,0,0,0,0,0,0,0,0,0,0,0,0,0,0,0,0,0,0,0,0,0,0,0,0,0,0,0,0,EK69~
,0,0,0,0,0,0,0,0,0,0,0)';$S;
    'VSS1472':'(0,0,0,0,0,0,0,0,0,0,0,0,0,0,0,0,0,0,0,0,0,0,0,0,0,0,0,0,0,0,EK65~
,0,0,0,0,0,0,0,0,0,0,0)';$S;
    'VSS1471':'(0,0,0,0,0,0,0,0,0,0,0,0,0,0,0,0,0,0,0,0,0,0,0,0,0,0,0,0,0,0,EK57~
,0,0,0,0,0,0,0,0,0,0,0)';$S;
    'VSS1470':'(0,0,0,0,0,0,0,0,0,0,0,0,0,0,0,0,0,0,0,0,0,0,0,0,0,0,0,0,0,0,EK47~
,0,0,0,0,0,0,0,0,0,0,0)';$S;
    'VSS1469':'(0,0,0,0,0,0,0,0,0,0,0,0,0,0,0,0,0,0,0,0,0,0,0,0,0,0,0,0,0,0,EK40~
,0,0,0,0,0,0,0,0,0,0,0)';$S;
    'VSS1468':'(0,0,0,0,0,0,0,0,0,0,0,0,0,0,0,0,0,0,0,0,0,0,0,0,0,0,0,0,0,0,ER64~
,0,0,0,0,0,0,0,0,0,0,0)';$S;
    'VSS1467':'(0,0,0,0,0,0,0,0,0,0,0,0,0,0,0,0,0,0,0,0,0,0,0,0,0,0,0,0,0,0,ER58~
,0,0,0,0,0,0,0,0,0,0,0)';$S;
    'VSS1466':'(0,0,0,0,0,0,0,0,0,0,0,0,0,0,0,0,0,0,0,0,0,0,0,0,0,0,0,0,0,0,EK4,~
0,0,0,0,0,0,0,0,0,0,0)';$S;
    'VSS1465':'(0,0,0,0,0,0,0,0,0,0,0,0,0,0,0,0,0,0,0,0,0,0,0,0,0,0,0,0,0,0,EK38~
,0,0,0,0,0,0,0,0,0,0,0)';$S;
    'VSS1464':'(0,0,0,0,0,0,0,0,0,0,0,0,0,0,0,0,0,0,0,0,0,0,0,0,0,0,0,0,0,0,ER52~
,0,0,0,0,0,0,0,0,0,0,0)';$S;
    'VSS1463':'(0,0,0,0,0,0,0,0,0,0,0,0,0,0,0,0,0,0,0,0,0,0,0,0,0,0,0,0,0,0,EK34~
,0,0,0,0,0,0,0,0,0,0,0)';$S;
    'VSS1462':'(0,0,0,0,0,0,0,0,0,0,0,0,0,0,0,0,0,0,0,0,0,0,0,0,0,0,0,0,0,0,ER39~
,0,0,0,0,0,0,0,0,0,0,0)';$S;
    'VSS1461':'(0,0,0,0,0,0,0,0,0,0,0,0,0,0,0,0,0,0,0,0,0,0,0,0,0,0,0,0,0,0,EK32~
,0,0,0,0,0,0,0,0,0,0,0)';$S;
    'VSS1460':'(0,0,0,0,0,0,0,0,0,0,0,0,0,0,0,0,0,0,0,0,0,0,0,0,0,0,0,0,0,0,EK28~
,0,0,0,0,0,0,0,0,0,0,0)';$S;
    'VSS1459':'(0,0,0,0,0,0,0,0,0,0,0,0,0,0,0,0,0,0,0,0,0,0,0,0,0,0,0,0,0,0,EK22~
,0,0,0,0,0,0,0,0,0,0,0)';$S;
    'VSS1458':'(0,0,0,0,0,0,0,0,0,0,0,0,0,0,0,0,0,0,0,0,0,0,0,0,0,0,0,0,0,0,EK2,~
0,0,0,0,0,0,0,0,0,0,0)';$S;
    'VSS1457':'(0,0,0,0,0,0,0,0,0,0,0,0,0,0,0,0,0,0,0,0,0,0,0,0,0,0,0,0,0,0,ER21~
,0,0,0,0,0,0,0,0,0,0,0)';$S;
    'VSS1456':'(0,0,0,0,0,0,0,0,0,0,0,0,0,0,0,0,0,0,0,0,0,0,0,0,0,0,0,0,0,0,ER15~
,0,0,0,0,0,0,0,0,0,0,0)';$S;
    'VSS1455':'(0,0,0,0,0,0,0,0,0,0,0,0,0,0,0,0,0,0,0,0,0,0,0,0,0,0,0,0,0,0,EK14~
,0,0,0,0,0,0,0,0,0,0,0)';$S;
    'VSS1454':'(0,0,0,0,0,0,0,0,0,0,0,0,0,0,0,0,0,0,0,0,0,0,0,0,0,0,0,0,0,0,EP77~
,0,0,0,0,0,0,0,0,0,0,0)';$S;
    'VSS1453':'(0,0,0,0,0,0,0,0,0,0,0,0,0,0,0,0,0,0,0,0,0,0,0,0,0,0,0,0,0,0,EP71~
,0,0,0,0,0,0,0,0,0,0,0)';$S;
    'VSS1452':'(0,0,0,0,0,0,0,0,0,0,0,0,0,0,0,0,0,0,0,0,0,0,0,0,0,0,0,0,0,0,EP69~
,0,0,0,0,0,0,0,0,0,0,0)';$S;
    'VSS1451':'(0,0,0,0,0,0,0,0,0,0,0,0,0,0,0,0,0,0,0,0,0,0,0,0,0,0,0,0,0,0,EK10~
,0,0,0,0,0,0,0,0,0,0,0)';$S;
    'VSS1450':'(0,0,0,0,0,0,0,0,0,0,0,0,0,0,0,0,0,0,0,0,0,0,0,0,0,0,0,0,0,0,EJ9,~
0,0,0,0,0,0,0,0,0,0,0)';$S;
    'VSS1449':'(0,0,0,0,0,0,0,0,0,0,0,0,0,0,0,0,0,0,0,0,0,0,0,0,0,0,0,0,0,0,EJ88~
,0,0,0,0,0,0,0,0,0,0,0)';$S;
    'VSS1448':'(0,0,0,0,0,0,0,0,0,0,0,0,0,0,0,0,0,0,0,0,0,0,0,0,0,0,0,0,0,0,EJ78~
,0,0,0,0,0,0,0,0,0,0,0)';$S;
    'VSS1447':'(0,0,0,0,0,0,0,0,0,0,0,0,0,0,0,0,0,0,0,0,0,0,0,0,0,0,0,0,0,0,EJ74~
,0,0,0,0,0,0,0,0,0,0,0)';$S;
    'VSS1446':'(0,0,0,0,0,0,0,0,0,0,0,0,0,0,0,0,0,0,0,0,0,0,0,0,0,0,0,0,0,0,EN9,~
0,0,0,0,0,0,0,0,0,0,0)';$S;
    'VSS1445':'(0,0,0,0,0,0,0,0,0,0,0,0,0,0,0,0,0,0,0,0,0,0,0,0,0,0,0,0,0,0,EN88~
,0,0,0,0,0,0,0,0,0,0,0)';$S;
    'VSS1444':'(0,0,0,0,0,0,0,0,0,0,0,0,0,0,0,0,0,0,0,0,0,0,0,0,0,0,0,0,0,0,EJ7,~
0,0,0,0,0,0,0,0,0,0,0)';$S;
    'VSS1443':'(0,0,0,0,0,0,0,0,0,0,0,0,0,0,0,0,0,0,0,0,0,0,0,0,0,0,0,0,0,0,EJ66~
,0,0,0,0,0,0,0,0,0,0,0)';$S;
    'VSS1442':'(0,0,0,0,0,0,0,0,0,0,0,0,0,0,0,0,0,0,0,0,0,0,0,0,0,0,0,0,0,0,EJ60~
,0,0,0,0,0,0,0,0,0,0,0)';$S;
    'VSS1441':'(0,0,0,0,0,0,0,0,0,0,0,0,0,0,0,0,0,0,0,0,0,0,0,0,0,0,0,0,0,0,EN72~
,0,0,0,0,0,0,0,0,0,0,0)';$S;
    'VSS1440':'(0,0,0,0,0,0,0,0,0,0,0,0,0,0,0,0,0,0,0,0,0,0,0,0,0,0,0,0,0,0,EN66~
,0,0,0,0,0,0,0,0,0,0,0)';$S;
    'VSS1439':'(0,0,0,0,0,0,0,0,0,0,0,0,0,0,0,0,0,0,0,0,0,0,0,0,0,0,0,0,0,0,EJ56~
,0,0,0,0,0,0,0,0,0,0,0)';$S;
    'VSS1438':'(0,0,0,0,0,0,0,0,0,0,0,0,0,0,0,0,0,0,0,0,0,0,0,0,0,0,0,0,0,0,EN62~
,0,0,0,0,0,0,0,0,0,0,0)';$S;
    'VSS1437':'(0,0,0,0,0,0,0,0,0,0,0,0,0,0,0,0,0,0,0,0,0,0,0,0,0,0,0,0,0,0,EN60~
,0,0,0,0,0,0,0,0,0,0,0)';$S;
    'VSS1436':'(0,0,0,0,0,0,0,0,0,0,0,0,0,0,0,0,0,0,0,0,0,0,0,0,0,0,0,0,0,0,EN58~
,0,0,0,0,0,0,0,0,0,0,0)';$S;
    'VSS1435':'(0,0,0,0,0,0,0,0,0,0,0,0,0,0,0,0,0,0,0,0,0,0,0,0,0,0,0,0,0,0,EJ50~
,0,0,0,0,0,0,0,0,0,0,0)';$S;
    'VSS1434':'(0,0,0,0,0,0,0,0,0,0,0,0,0,0,0,0,0,0,0,0,0,0,0,0,0,0,0,0,0,0,EJ48~
,0,0,0,0,0,0,0,0,0,0,0)';$S;
    'VSS1433':'(0,0,0,0,0,0,0,0,0,0,0,0,0,0,0,0,0,0,0,0,0,0,0,0,0,0,0,0,0,0,EJ43~
,0,0,0,0,0,0,0,0,0,0,0)';$S;
    'VSS1432':'(0,0,0,0,0,0,0,0,0,0,0,0,0,0,0,0,0,0,0,0,0,0,0,0,0,0,0,0,0,0,EJ41~
,0,0,0,0,0,0,0,0,0,0,0)';$S;
    'VSS1431':'(0,0,0,0,0,0,0,0,0,0,0,0,0,0,0,0,0,0,0,0,0,0,0,0,0,0,0,0,0,0,EJ37~
,0,0,0,0,0,0,0,0,0,0,0)';$S;
    'VSS1430':'(0,0,0,0,0,0,0,0,0,0,0,0,0,0,0,0,0,0,0,0,0,0,0,0,0,0,0,0,0,0,EJ31~
,0,0,0,0,0,0,0,0,0,0,0)';$S;
    'VSS1429':'(0,0,0,0,0,0,0,0,0,0,0,0,0,0,0,0,0,0,0,0,0,0,0,0,0,0,0,0,0,0,EJ29~
,0,0,0,0,0,0,0,0,0,0,0)';$S;
    'VSS1428':'(0,0,0,0,0,0,0,0,0,0,0,0,0,0,0,0,0,0,0,0,0,0,0,0,0,0,0,0,0,0,EJ23~
,0,0,0,0,0,0,0,0,0,0,0)';$S;
    'VSS1427':'(0,0,0,0,0,0,0,0,0,0,0,0,0,0,0,0,0,0,0,0,0,0,0,0,0,0,0,0,0,0,EN39~
,0,0,0,0,0,0,0,0,0,0,0)';$S;
    'VSS1426':'(0,0,0,0,0,0,0,0,0,0,0,0,0,0,0,0,0,0,0,0,0,0,0,0,0,0,0,0,0,0,EJ19~
,0,0,0,0,0,0,0,0,0,0,0)';$S;
    'VSS1425':'(0,0,0,0,0,0,0,0,0,0,0,0,0,0,0,0,0,0,0,0,0,0,0,0,0,0,0,0,0,0,EJ13~
,0,0,0,0,0,0,0,0,0,0,0)';$S;
    'VSS1424':'(0,0,0,0,0,0,0,0,0,0,0,0,0,0,0,0,0,0,0,0,0,0,0,0,0,0,0,0,0,0,EH83~
,0,0,0,0,0,0,0,0,0,0,0)';$S;
    'VSS1423':'(0,0,0,0,0,0,0,0,0,0,0,0,0,0,0,0,0,0,0,0,0,0,0,0,0,0,0,0,0,0,EH81~
,0,0,0,0,0,0,0,0,0,0,0)';$S;
    'VSS1422':'(0,0,0,0,0,0,0,0,0,0,0,0,0,0,0,0,0,0,0,0,0,0,0,0,0,0,0,0,0,0,EH73~
,0,0,0,0,0,0,0,0,0,0,0)';$S;
    'VSS1421':'(0,0,0,0,0,0,0,0,0,0,0,0,0,0,0,0,0,0,0,0,0,0,0,0,0,0,0,0,0,0,EH49~
,0,0,0,0,0,0,0,0,0,0,0)';$S;
    'VSS1419':'(0,0,0,0,0,0,0,0,0,0,0,0,0,0,0,0,0,0,0,0,0,0,0,0,0,0,0,0,0,0,EH36~
,0,0,0,0,0,0,0,0,0,0,0)';$S;
    'VSS1409':'(0,0,0,0,0,0,0,0,0,0,0,0,0,0,0,0,0,0,0,0,0,0,0,0,0,0,0,0,0,0,EM79~
,0,0,0,0,0,0,0,0,0,0,0)';$S;
    'VSS1405':'(0,0,0,0,0,0,0,0,0,0,0,0,0,0,0,0,0,0,0,0,0,0,0,0,0,0,0,0,0,0,EM49~
,0,0,0,0,0,0,0,0,0,0,0)';$S;
    'VSS1401':'(0,0,0,0,0,0,0,0,0,0,0,0,0,0,0,0,0,0,0,0,0,0,0,0,0,0,0,0,0,0,EL9,~
0,0,0,0,0,0,0,0,0,0,0)';$S;
    'VSS1400':'(0,0,0,0,0,0,0,0,0,0,0,0,0,0,0,0,0,0,0,0,0,0,0,0,0,0,0,0,0,0,EL86~
,0,0,0,0,0,0,0,0,0,0,0)';$S;
    'VSS1398':'(0,0,0,0,0,0,0,0,0,0,0,0,0,0,0,0,0,0,0,0,0,0,0,0,0,0,0,0,0,0,EL72~
,0,0,0,0,0,0,0,0,0,0,0)';$S;
    'VSS1397':'(0,0,0,0,0,0,0,0,0,0,0,0,0,0,0,0,0,0,0,0,0,0,0,0,0,0,0,0,0,0,EL70~
,0,0,0,0,0,0,0,0,0,0,0)';$S;
    'VSS1396':'(0,0,0,0,0,0,0,0,0,0,0,0,0,0,0,0,0,0,0,0,0,0,0,0,0,0,0,0,0,0,EL7,~
0,0,0,0,0,0,0,0,0,0,0)';$S;
    'VSS1394':'(0,0,0,0,0,0,0,0,0,0,0,0,0,0,0,0,0,0,0,0,0,0,0,0,0,0,0,0,0,0,EL58~
,0,0,0,0,0,0,0,0,0,0,0)';$S;
    'VSS1391':'(0,0,0,0,0,0,0,0,0,0,0,0,0,0,0,0,0,0,0,0,0,0,0,0,0,0,0,0,0,0,EL52~
,0,0,0,0,0,0,0,0,0,0,0)';$S;
    'VSS1381':'(0,0,0,0,0,0,0,0,0,0,0,0,0,0,0,0,0,0,0,0,0,0,0,0,0,0,0,0,0,0,EL15~
,0,0,0,0,0,0,0,0,0,0,0)';$S;
    'VSS1380':'(0,0,0,0,0,0,0,0,0,0,0,0,0,0,0,0,0,0,0,0,0,0,0,0,0,0,0,0,0,0,EK89~
,0,0,0,0,0,0,0,0,0,0,0)';$S;
    'VSS1379':'(0,0,0,0,0,0,0,0,0,0,0,0,0,0,0,0,0,0,0,0,0,0,0,0,0,0,0,0,0,0,EK83~
,0,0,0,0,0,0,0,0,0,0,0)';$S;
    'VSS1378':'(0,0,0,0,0,0,0,0,0,0,0,0,0,0,0,0,0,0,0,0,0,0,0,0,0,0,0,0,0,0,EK79~
,0,0,0,0,0,0,0,0,0,0,0)';$S;
    'VSS1377':'(0,0,0,0,0,0,0,0,0,0,0,0,0,0,0,0,0,0,0,0,0,0,0,0,0,0,0,0,0,0,EK77~
,0,0,0,0,0,0,0,0,0,0,0)';$S;
    'VSS1375':'(0,0,0,0,0,0,0,0,0,0,0,0,0,0,0,0,0,0,0,0,0,0,0,0,0,0,0,0,0,0,EK71~
,0,0,0,0,0,0,0,0,0,0,0)';$S;
    'VSS1372':'(0,0,0,0,0,0,0,0,0,0,0,0,0,0,0,0,0,0,0,0,0,0,0,0,0,0,0,0,0,0,EK63~
,0,0,0,0,0,0,0,0,0,0,0)';$S;
    'VSS1371':'(0,0,0,0,0,0,0,0,0,0,0,0,0,0,0,0,0,0,0,0,0,0,0,0,0,0,0,0,0,0,EK59~
,0,0,0,0,0,0,0,0,0,0,0)';$S;
    'VSS1369':'(0,0,0,0,0,0,0,0,0,0,0,0,0,0,0,0,0,0,0,0,0,0,0,0,0,0,0,0,0,0,EK53~
,0,0,0,0,0,0,0,0,0,0,0)';$S;
    'VSS1368':'(0,0,0,0,0,0,0,0,0,0,0,0,0,0,0,0,0,0,0,0,0,0,0,0,0,0,0,0,0,0,EK51~
,0,0,0,0,0,0,0,0,0,0,0)';$S;
    'VSS1366':'(0,0,0,0,0,0,0,0,0,0,0,0,0,0,0,0,0,0,0,0,0,0,0,0,0,0,0,0,0,0,EK44~
,0,0,0,0,0,0,0,0,0,0,0)';$S;
    'VSS1359':'(0,0,0,0,0,0,0,0,0,0,0,0,0,0,0,0,0,0,0,0,0,0,0,0,0,0,0,0,0,0,EK26~
,0,0,0,0,0,0,0,0,0,0,0)';$S;
    'VSS1357':'(0,0,0,0,0,0,0,0,0,0,0,0,0,0,0,0,0,0,0,0,0,0,0,0,0,0,0,0,0,0,EK20~
,0,0,0,0,0,0,0,0,0,0,0)';$S;
    'VSS1355':'(0,0,0,0,0,0,0,0,0,0,0,0,0,0,0,0,0,0,0,0,0,0,0,0,0,0,0,0,0,0,EK16~
,0,0,0,0,0,0,0,0,0,0,0)';$S;
    'VSS1347':'(0,0,0,0,0,0,0,0,0,0,0,0,0,0,0,0,0,0,0,0,0,0,0,0,0,0,0,0,0,0,EJ72~
,0,0,0,0,0,0,0,0,0,0,0)';$S;
    'VSS1345':'(0,0,0,0,0,0,0,0,0,0,0,0,0,0,0,0,0,0,0,0,0,0,0,0,0,0,0,0,0,0,EJ68~
,0,0,0,0,0,0,0,0,0,0,0)';$S;
    'VSS1343':'(0,0,0,0,0,0,0,0,0,0,0,0,0,0,0,0,0,0,0,0,0,0,0,0,0,0,0,0,0,0,EJ62~
,0,0,0,0,0,0,0,0,0,0,0)';$S;
    'VSS1340':'(0,0,0,0,0,0,0,0,0,0,0,0,0,0,0,0,0,0,0,0,0,0,0,0,0,0,0,0,0,0,EJ54~
,0,0,0,0,0,0,0,0,0,0,0)';$S;
    'VSS1334':'(0,0,0,0,0,0,0,0,0,0,0,0,0,0,0,0,0,0,0,0,0,0,0,0,0,0,0,0,0,0,EJ35~
,0,0,0,0,0,0,0,0,0,0,0)';$S;
    'VSS1331':'(0,0,0,0,0,0,0,0,0,0,0,0,0,0,0,0,0,0,0,0,0,0,0,0,0,0,0,0,0,0,EJ25~
,0,0,0,0,0,0,0,0,0,0,0)';$S;
    'VSS1328':'(0,0,0,0,0,0,0,0,0,0,0,0,0,0,0,0,0,0,0,0,0,0,0,0,0,0,0,0,0,0,EJ17~
,0,0,0,0,0,0,0,0,0,0,0)';$S;
    'VSS1325':'(0,0,0,0,0,0,0,0,0,0,0,0,0,0,0,0,0,0,0,0,0,0,0,0,0,0,0,0,0,0,EJ11~
,0,0,0,0,0,0,0,0,0,0,0)';$S;
    'VSS1322':'(0,0,0,0,0,0,0,0,0,0,0,0,0,0,0,0,0,0,0,0,0,0,0,0,0,0,0,0,0,0,EH79~
,0,0,0,0,0,0,0,0,0,0,0)';$S;
    'VSS1320':'(0,0,0,0,0,0,0,0,0,0,0,0,0,0,0,0,0,0,0,0,0,0,0,0,0,0,0,0,0,0,EH67~
,0,0,0,0,0,0,0,0,0,0,0)';$S;
    'VSS1319':'(0,0,0,0,0,0,0,0,0,0,0,0,0,0,0,0,0,0,0,0,0,0,0,0,0,0,0,0,0,0,EH61~
,0,0,0,0,0,0,0,0,0,0,0)';$S;
    'VSS1315':'(0,0,0,0,0,0,0,0,0,0,0,0,0,0,0,0,0,0,0,0,0,0,0,0,0,0,0,0,0,0,EH55~
,0,0,0,0,0,0,0,0,0,0,0)';$S;
    'VSS1312':'(0,0,0,0,0,0,0,0,0,0,0,0,0,0,0,0,0,0,0,0,0,0,0,0,0,0,0,0,0,0,EH42~
,0,0,0,0,0,0,0,0,0,0,0)';$S;
    'VSS1420':'(0,0,0,0,0,0,0,0,0,0,0,0,0,0,0,0,0,0,0,0,0,0,0,0,0,0,0,0,0,0,0,EH~
4,0,0,0,0,0,0,0,0,0,0)';$S;
    'VSS1418':'(0,0,0,0,0,0,0,0,0,0,0,0,0,0,0,0,0,0,0,0,0,0,0,0,0,0,0,0,0,0,0,EH~
30,0,0,0,0,0,0,0,0,0,0)';$S;
    'VSS1417':'(0,0,0,0,0,0,0,0,0,0,0,0,0,0,0,0,0,0,0,0,0,0,0,0,0,0,0,0,0,0,0,EH~
24,0,0,0,0,0,0,0,0,0,0)';$S;
    'VSS1416':'(0,0,0,0,0,0,0,0,0,0,0,0,0,0,0,0,0,0,0,0,0,0,0,0,0,0,0,0,0,0,0,EH~
16,0,0,0,0,0,0,0,0,0,0)';$S;
    'VSS1415':'(0,0,0,0,0,0,0,0,0,0,0,0,0,0,0,0,0,0,0,0,0,0,0,0,0,0,0,0,0,0,0,EG~
90,0,0,0,0,0,0,0,0,0,0)';$S;
    'VSS1414':'(0,0,0,0,0,0,0,0,0,0,0,0,0,0,0,0,0,0,0,0,0,0,0,0,0,0,0,0,0,0,0,EG~
9,0,0,0,0,0,0,0,0,0,0)';$S;
    'VSS1413':'(0,0,0,0,0,0,0,0,0,0,0,0,0,0,0,0,0,0,0,0,0,0,0,0,0,0,0,0,0,0,0,EG~
88,0,0,0,0,0,0,0,0,0,0)';$S;
    'VSS1412':'(0,0,0,0,0,0,0,0,0,0,0,0,0,0,0,0,0,0,0,0,0,0,0,0,0,0,0,0,0,0,0,EG~
86,0,0,0,0,0,0,0,0,0,0)';$S;
    'VSS1411':'(0,0,0,0,0,0,0,0,0,0,0,0,0,0,0,0,0,0,0,0,0,0,0,0,0,0,0,0,0,0,0,EG~
84,0,0,0,0,0,0,0,0,0,0)';$S;
    'VSS1410':'(0,0,0,0,0,0,0,0,0,0,0,0,0,0,0,0,0,0,0,0,0,0,0,0,0,0,0,0,0,0,0,EG~
82,0,0,0,0,0,0,0,0,0,0)';$S;
    'VSS1408':'(0,0,0,0,0,0,0,0,0,0,0,0,0,0,0,0,0,0,0,0,0,0,0,0,0,0,0,0,0,0,0,EG~
39,0,0,0,0,0,0,0,0,0,0)';$S;
    'VSS1407':'(0,0,0,0,0,0,0,0,0,0,0,0,0,0,0,0,0,0,0,0,0,0,0,0,0,0,0,0,0,0,0,EF~
87,0,0,0,0,0,0,0,0,0,0)';$S;
    'VSS1406':'(0,0,0,0,0,0,0,0,0,0,0,0,0,0,0,0,0,0,0,0,0,0,0,0,0,0,0,0,0,0,0,EF~
85,0,0,0,0,0,0,0,0,0,0)';$S;
    'VSS1404':'(0,0,0,0,0,0,0,0,0,0,0,0,0,0,0,0,0,0,0,0,0,0,0,0,0,0,0,0,0,0,0,EF~
8,0,0,0,0,0,0,0,0,0,0)';$S;
    'VSS1403':'(0,0,0,0,0,0,0,0,0,0,0,0,0,0,0,0,0,0,0,0,0,0,0,0,0,0,0,0,0,0,0,EF~
77,0,0,0,0,0,0,0,0,0,0)';$S;
    'VSS1402':'(0,0,0,0,0,0,0,0,0,0,0,0,0,0,0,0,0,0,0,0,0,0,0,0,0,0,0,0,0,0,0,EF~
71,0,0,0,0,0,0,0,0,0,0)';$S;
    'VSS1399':'(0,0,0,0,0,0,0,0,0,0,0,0,0,0,0,0,0,0,0,0,0,0,0,0,0,0,0,0,0,0,0,EF~
69,0,0,0,0,0,0,0,0,0,0)';$S;
    'VSS1395':'(0,0,0,0,0,0,0,0,0,0,0,0,0,0,0,0,0,0,0,0,0,0,0,0,0,0,0,0,0,0,0,EF~
67,0,0,0,0,0,0,0,0,0,0)';$S;
    'VSS1393':'(0,0,0,0,0,0,0,0,0,0,0,0,0,0,0,0,0,0,0,0,0,0,0,0,0,0,0,0,0,0,0,EF~
65,0,0,0,0,0,0,0,0,0,0)';$S;
    'VSS1392':'(0,0,0,0,0,0,0,0,0,0,0,0,0,0,0,0,0,0,0,0,0,0,0,0,0,0,0,0,0,0,0,EF~
63,0,0,0,0,0,0,0,0,0,0)';$S;
    'VSS1390':'(0,0,0,0,0,0,0,0,0,0,0,0,0,0,0,0,0,0,0,0,0,0,0,0,0,0,0,0,0,0,0,EF~
61,0,0,0,0,0,0,0,0,0,0)';$S;
    'VSS1389':'(0,0,0,0,0,0,0,0,0,0,0,0,0,0,0,0,0,0,0,0,0,0,0,0,0,0,0,0,0,0,0,EF~
59,0,0,0,0,0,0,0,0,0,0)';$S;
    'VSS1388':'(0,0,0,0,0,0,0,0,0,0,0,0,0,0,0,0,0,0,0,0,0,0,0,0,0,0,0,0,0,0,0,EF~
57,0,0,0,0,0,0,0,0,0,0)';$S;
    'VSS1387':'(0,0,0,0,0,0,0,0,0,0,0,0,0,0,0,0,0,0,0,0,0,0,0,0,0,0,0,0,0,0,0,EF~
55,0,0,0,0,0,0,0,0,0,0)';$S;
    'VSS1386':'(0,0,0,0,0,0,0,0,0,0,0,0,0,0,0,0,0,0,0,0,0,0,0,0,0,0,0,0,0,0,0,EF~
53,0,0,0,0,0,0,0,0,0,0)';$S;
    'VSS1385':'(0,0,0,0,0,0,0,0,0,0,0,0,0,0,0,0,0,0,0,0,0,0,0,0,0,0,0,0,0,0,0,EF~
49,0,0,0,0,0,0,0,0,0,0)';$S;
    'VSS1384':'(0,0,0,0,0,0,0,0,0,0,0,0,0,0,0,0,0,0,0,0,0,0,0,0,0,0,0,0,0,0,0,EF~
47,0,0,0,0,0,0,0,0,0,0)';$S;
    'VSS1383':'(0,0,0,0,0,0,0,0,0,0,0,0,0,0,0,0,0,0,0,0,0,0,0,0,0,0,0,0,0,0,0,EF~
44,0,0,0,0,0,0,0,0,0,0)';$S;
    'VSS1382':'(0,0,0,0,0,0,0,0,0,0,0,0,0,0,0,0,0,0,0,0,0,0,0,0,0,0,0,0,0,0,0,EF~
42,0,0,0,0,0,0,0,0,0,0)';$S;
    'VSS1376':'(0,0,0,0,0,0,0,0,0,0,0,0,0,0,0,0,0,0,0,0,0,0,0,0,0,0,0,0,0,0,0,EF~
40,0,0,0,0,0,0,0,0,0,0)';$S;
    'VSS1374':'(0,0,0,0,0,0,0,0,0,0,0,0,0,0,0,0,0,0,0,0,0,0,0,0,0,0,0,0,0,0,0,EF~
4,0,0,0,0,0,0,0,0,0,0)';$S;
    'VSS1373':'(0,0,0,0,0,0,0,0,0,0,0,0,0,0,0,0,0,0,0,0,0,0,0,0,0,0,0,0,0,0,0,EF~
38,0,0,0,0,0,0,0,0,0,0)';$S;
    'VSS1370':'(0,0,0,0,0,0,0,0,0,0,0,0,0,0,0,0,0,0,0,0,0,0,0,0,0,0,0,0,0,0,0,EF~
36,0,0,0,0,0,0,0,0,0,0)';$S;
    'VSS1367':'(0,0,0,0,0,0,0,0,0,0,0,0,0,0,0,0,0,0,0,0,0,0,0,0,0,0,0,0,0,0,0,EF~
34,0,0,0,0,0,0,0,0,0,0)';$S;
    'VSS1365':'(0,0,0,0,0,0,0,0,0,0,0,0,0,0,0,0,0,0,0,0,0,0,0,0,0,0,0,0,0,0,0,EF~
32,0,0,0,0,0,0,0,0,0,0)';$S;
    'VSS1364':'(0,0,0,0,0,0,0,0,0,0,0,0,0,0,0,0,0,0,0,0,0,0,0,0,0,0,0,0,0,0,0,EF~
30,0,0,0,0,0,0,0,0,0,0)';$S;
    'VSS1363':'(0,0,0,0,0,0,0,0,0,0,0,0,0,0,0,0,0,0,0,0,0,0,0,0,0,0,0,0,0,0,0,EF~
28,0,0,0,0,0,0,0,0,0,0)';$S;
    'VSS1362':'(0,0,0,0,0,0,0,0,0,0,0,0,0,0,0,0,0,0,0,0,0,0,0,0,0,0,0,0,0,0,0,EF~
26,0,0,0,0,0,0,0,0,0,0)';$S;
    'VSS1361':'(0,0,0,0,0,0,0,0,0,0,0,0,0,0,0,0,0,0,0,0,0,0,0,0,0,0,0,0,0,0,0,EF~
24,0,0,0,0,0,0,0,0,0,0)';$S;
    'VSS1360':'(0,0,0,0,0,0,0,0,0,0,0,0,0,0,0,0,0,0,0,0,0,0,0,0,0,0,0,0,0,0,0,EF~
22,0,0,0,0,0,0,0,0,0,0)';$S;
    'VSS1358':'(0,0,0,0,0,0,0,0,0,0,0,0,0,0,0,0,0,0,0,0,0,0,0,0,0,0,0,0,0,0,0,EF~
20,0,0,0,0,0,0,0,0,0,0)';$S;
    'VSS1356':'(0,0,0,0,0,0,0,0,0,0,0,0,0,0,0,0,0,0,0,0,0,0,0,0,0,0,0,0,0,0,0,EF~
2,0,0,0,0,0,0,0,0,0,0)';$S;
    'VSS1354':'(0,0,0,0,0,0,0,0,0,0,0,0,0,0,0,0,0,0,0,0,0,0,0,0,0,0,0,0,0,0,0,EF~
18,0,0,0,0,0,0,0,0,0,0)';$S;
    'VSS1353':'(0,0,0,0,0,0,0,0,0,0,0,0,0,0,0,0,0,0,0,0,0,0,0,0,0,0,0,0,0,0,0,EF~
16,0,0,0,0,0,0,0,0,0,0)';$S;
    'VSS1352':'(0,0,0,0,0,0,0,0,0,0,0,0,0,0,0,0,0,0,0,0,0,0,0,0,0,0,0,0,0,0,0,EF~
12,0,0,0,0,0,0,0,0,0,0)';$S;
    'VSS1351':'(0,0,0,0,0,0,0,0,0,0,0,0,0,0,0,0,0,0,0,0,0,0,0,0,0,0,0,0,0,0,0,EE~
88,0,0,0,0,0,0,0,0,0,0)';$S;
    'VSS1350':'(0,0,0,0,0,0,0,0,0,0,0,0,0,0,0,0,0,0,0,0,0,0,0,0,0,0,0,0,0,0,0,EE~
80,0,0,0,0,0,0,0,0,0,0)';$S;
    'VSS1349':'(0,0,0,0,0,0,0,0,0,0,0,0,0,0,0,0,0,0,0,0,0,0,0,0,0,0,0,0,0,0,0,EE~
78,0,0,0,0,0,0,0,0,0,0)';$S;
    'VSS1348':'(0,0,0,0,0,0,0,0,0,0,0,0,0,0,0,0,0,0,0,0,0,0,0,0,0,0,0,0,0,0,0,ED~
8,0,0,0,0,0,0,0,0,0,0)';$S;
    'VSS1346':'(0,0,0,0,0,0,0,0,0,0,0,0,0,0,0,0,0,0,0,0,0,0,0,0,0,0,0,0,0,0,0,ED~
49,0,0,0,0,0,0,0,0,0,0)';$S;
    'VSS1344':'(0,0,0,0,0,0,0,0,0,0,0,0,0,0,0,0,0,0,0,0,0,0,0,0,0,0,0,0,0,0,0,ED~
4,0,0,0,0,0,0,0,0,0,0)';$S;
    'VSS1342':'(0,0,0,0,0,0,0,0,0,0,0,0,0,0,0,0,0,0,0,0,0,0,0,0,0,0,0,0,0,0,0,ED~
36,0,0,0,0,0,0,0,0,0,0)';$S;
    'VSS1341':'(0,0,0,0,0,0,0,0,0,0,0,0,0,0,0,0,0,0,0,0,0,0,0,0,0,0,0,0,0,0,0,ED~
30,0,0,0,0,0,0,0,0,0,0)';$S;
    'VSS1339':'(0,0,0,0,0,0,0,0,0,0,0,0,0,0,0,0,0,0,0,0,0,0,0,0,0,0,0,0,0,0,0,ED~
24,0,0,0,0,0,0,0,0,0,0)';$S;
    'VSS1338':'(0,0,0,0,0,0,0,0,0,0,0,0,0,0,0,0,0,0,0,0,0,0,0,0,0,0,0,0,0,0,0,ED~
16,0,0,0,0,0,0,0,0,0,0)';$S;
    'VSS1337':'(0,0,0,0,0,0,0,0,0,0,0,0,0,0,0,0,0,0,0,0,0,0,0,0,0,0,0,0,0,0,0,EC~
9,0,0,0,0,0,0,0,0,0,0)';$S;
    'VSS1336':'(0,0,0,0,0,0,0,0,0,0,0,0,0,0,0,0,0,0,0,0,0,0,0,0,0,0,0,0,0,0,0,EC~
88,0,0,0,0,0,0,0,0,0,0)';$S;
    'VSS1335':'(0,0,0,0,0,0,0,0,0,0,0,0,0,0,0,0,0,0,0,0,0,0,0,0,0,0,0,0,0,0,0,EC~
84,0,0,0,0,0,0,0,0,0,0)';$S;
    'VSS1333':'(0,0,0,0,0,0,0,0,0,0,0,0,0,0,0,0,0,0,0,0,0,0,0,0,0,0,0,0,0,0,0,EC~
82,0,0,0,0,0,0,0,0,0,0)';$S;
    'VSS1332':'(0,0,0,0,0,0,0,0,0,0,0,0,0,0,0,0,0,0,0,0,0,0,0,0,0,0,0,0,0,0,0,EC~
74,0,0,0,0,0,0,0,0,0,0)';$S;
    'VSS1330':'(0,0,0,0,0,0,0,0,0,0,0,0,0,0,0,0,0,0,0,0,0,0,0,0,0,0,0,0,0,0,0,EC~
72,0,0,0,0,0,0,0,0,0,0)';$S;
    'VSS1329':'(0,0,0,0,0,0,0,0,0,0,0,0,0,0,0,0,0,0,0,0,0,0,0,0,0,0,0,0,0,0,0,EC~
66,0,0,0,0,0,0,0,0,0,0)';$S;
    'VSS1327':'(0,0,0,0,0,0,0,0,0,0,0,0,0,0,0,0,0,0,0,0,0,0,0,0,0,0,0,0,0,0,0,EC~
56,0,0,0,0,0,0,0,0,0,0)';$S;
    'VSS1326':'(0,0,0,0,0,0,0,0,0,0,0,0,0,0,0,0,0,0,0,0,0,0,0,0,0,0,0,0,0,0,0,EC~
50,0,0,0,0,0,0,0,0,0,0)';$S;
    'VSS1324':'(0,0,0,0,0,0,0,0,0,0,0,0,0,0,0,0,0,0,0,0,0,0,0,0,0,0,0,0,0,0,0,EC~
48,0,0,0,0,0,0,0,0,0,0)';$S;
    'VSS1323':'(0,0,0,0,0,0,0,0,0,0,0,0,0,0,0,0,0,0,0,0,0,0,0,0,0,0,0,0,0,0,0,EC~
43,0,0,0,0,0,0,0,0,0,0)';$S;
    'VSS1321':'(0,0,0,0,0,0,0,0,0,0,0,0,0,0,0,0,0,0,0,0,0,0,0,0,0,0,0,0,0,0,0,EC~
41,0,0,0,0,0,0,0,0,0,0)';$S;
    'VSS1318':'(0,0,0,0,0,0,0,0,0,0,0,0,0,0,0,0,0,0,0,0,0,0,0,0,0,0,0,0,0,0,0,EH~
6,0,0,0,0,0,0,0,0,0,0)';$S;
    'VSS1317':'(0,0,0,0,0,0,0,0,0,0,0,0,0,0,0,0,0,0,0,0,0,0,0,0,0,0,0,0,0,0,0,EC~
37,0,0,0,0,0,0,0,0,0,0)';$S;
    'VSS1316':'(0,0,0,0,0,0,0,0,0,0,0,0,0,0,0,0,0,0,0,0,0,0,0,0,0,0,0,0,0,0,0,EC~
31,0,0,0,0,0,0,0,0,0,0)';$S;
    'VSS1314':'(0,0,0,0,0,0,0,0,0,0,0,0,0,0,0,0,0,0,0,0,0,0,0,0,0,0,0,0,0,0,0,EC~
29,0,0,0,0,0,0,0,0,0,0)';$S;
    'VSS1313':'(0,0,0,0,0,0,0,0,0,0,0,0,0,0,0,0,0,0,0,0,0,0,0,0,0,0,0,0,0,0,0,EC~
23,0,0,0,0,0,0,0,0,0,0)';$S;
    'VSS1311':'(0,0,0,0,0,0,0,0,0,0,0,0,0,0,0,0,0,0,0,0,0,0,0,0,0,0,0,0,0,0,0,EC~
19,0,0,0,0,0,0,0,0,0,0)';$S;
    'VSS1310':'(0,0,0,0,0,0,0,0,0,0,0,0,0,0,0,0,0,0,0,0,0,0,0,0,0,0,0,0,0,0,0,EC~
13,0,0,0,0,0,0,0,0,0,0)';$S;
    'VSS1309':'(0,0,0,0,0,0,0,0,0,0,0,0,0,0,0,0,0,0,0,0,0,0,0,0,0,0,0,0,0,0,0,EC~
1,0,0,0,0,0,0,0,0,0,0)';$S;
    'VSS1308':'(0,0,0,0,0,0,0,0,0,0,0,0,0,0,0,0,0,0,0,0,0,0,0,0,0,0,0,0,0,0,0,EB~
87,0,0,0,0,0,0,0,0,0,0)';$S;
    'VSS1307':'(0,0,0,0,0,0,0,0,0,0,0,0,0,0,0,0,0,0,0,0,0,0,0,0,0,0,0,0,0,0,0,EB~
83,0,0,0,0,0,0,0,0,0,0)';$S;
    'VSS1306':'(0,0,0,0,0,0,0,0,0,0,0,0,0,0,0,0,0,0,0,0,0,0,0,0,0,0,0,0,0,0,0,EB~
8,0,0,0,0,0,0,0,0,0,0)';$S;
    'VSS1305':'(0,0,0,0,0,0,0,0,0,0,0,0,0,0,0,0,0,0,0,0,0,0,0,0,0,0,0,0,0,0,0,EH~
18,0,0,0,0,0,0,0,0,0,0)';$S;
    'VSS1304':'(0,0,0,0,0,0,0,0,0,0,0,0,0,0,0,0,0,0,0,0,0,0,0,0,0,0,0,0,0,0,0,EB~
79,0,0,0,0,0,0,0,0,0,0)';$S;
    'VSS1303':'(0,0,0,0,0,0,0,0,0,0,0,0,0,0,0,0,0,0,0,0,0,0,0,0,0,0,0,0,0,0,0,EH~
14,0,0,0,0,0,0,0,0,0,0)';$S;
    'VSS1302':'(0,0,0,0,0,0,0,0,0,0,0,0,0,0,0,0,0,0,0,0,0,0,0,0,0,0,0,0,0,0,0,EH~
12,0,0,0,0,0,0,0,0,0,0)';$S;
    'VSS1301':'(0,0,0,0,0,0,0,0,0,0,0,0,0,0,0,0,0,0,0,0,0,0,0,0,0,0,0,0,0,0,0,EB~
75,0,0,0,0,0,0,0,0,0,0)';$S;
    'VSS1300':'(0,0,0,0,0,0,0,0,0,0,0,0,0,0,0,0,0,0,0,0,0,0,0,0,0,0,0,0,0,0,0,EB~
71,0,0,0,0,0,0,0,0,0,0)';$S;
    'VSS1299':'(0,0,0,0,0,0,0,0,0,0,0,0,0,0,0,0,0,0,0,0,0,0,0,0,0,0,0,0,0,0,0,EB~
69,0,0,0,0,0,0,0,0,0,0)';$S;
    'VSS1298':'(0,0,0,0,0,0,0,0,0,0,0,0,0,0,0,0,0,0,0,0,0,0,0,0,0,0,0,0,0,0,0,EB~
65,0,0,0,0,0,0,0,0,0,0)';$S;
    'VSS1297':'(0,0,0,0,0,0,0,0,0,0,0,0,0,0,0,0,0,0,0,0,0,0,0,0,0,0,0,0,0,0,0,EB~
57,0,0,0,0,0,0,0,0,0,0)';$S;
    'VSS1296':'(0,0,0,0,0,0,0,0,0,0,0,0,0,0,0,0,0,0,0,0,0,0,0,0,0,0,0,0,0,0,0,EB~
47,0,0,0,0,0,0,0,0,0,0)';$S;
    'VSS1295':'(0,0,0,0,0,0,0,0,0,0,0,0,0,0,0,0,0,0,0,0,0,0,0,0,0,0,0,0,0,0,0,EB~
40,0,0,0,0,0,0,0,0,0,0)';$S;
    'VSS1294':'(0,0,0,0,0,0,0,0,0,0,0,0,0,0,0,0,0,0,0,0,0,0,0,0,0,0,0,0,0,0,0,EG~
7,0,0,0,0,0,0,0,0,0,0)';$S;
    'VSS1293':'(0,0,0,0,0,0,0,0,0,0,0,0,0,0,0,0,0,0,0,0,0,0,0,0,0,0,0,0,0,0,0,EB~
38,0,0,0,0,0,0,0,0,0,0)';$S;
    'VSS1292':'(0,0,0,0,0,0,0,0,0,0,0,0,0,0,0,0,0,0,0,0,0,0,0,0,0,0,0,0,0,0,0,EB~
32,0,0,0,0,0,0,0,0,0,0)';$S;
    'VSS1291':'(0,0,0,0,0,0,0,0,0,0,0,0,0,0,0,0,0,0,0,0,0,0,0,0,0,0,0,0,0,0,0,EG~
52,0,0,0,0,0,0,0,0,0,0)';$S;
    'VSS1290':'(0,0,0,0,0,0,0,0,0,0,0,0,0,0,0,0,0,0,0,0,0,0,0,0,0,0,0,0,0,0,0,EG~
5,0,0,0,0,0,0,0,0,0,0)';$S;
    'VSS1289':'(0,0,0,0,0,0,0,0,0,0,0,0,0,0,0,0,0,0,0,0,0,0,0,0,0,0,0,0,0,0,0,EB~
28,0,0,0,0,0,0,0,0,0,0)';$S;
    'VSS1288':'(0,0,0,0,0,0,0,0,0,0,0,0,0,0,0,0,0,0,0,0,0,0,0,0,0,0,0,0,0,0,0,EB~
22,0,0,0,0,0,0,0,0,0,0)';$S;
    'VSS1287':'(0,0,0,0,0,0,0,0,0,0,0,0,0,0,0,0,0,0,0,0,0,0,0,0,0,0,0,0,0,0,0,EB~
12,0,0,0,0,0,0,0,0,0,0)';$S;
    'VSS1286':'(0,0,0,0,0,0,0,0,0,0,0,0,0,0,0,0,0,0,0,0,0,0,0,0,0,0,0,0,0,0,0,EA~
88,0,0,0,0,0,0,0,0,0,0)';$S;
    'VSS1285':'(0,0,0,0,0,0,0,0,0,0,0,0,0,0,0,0,0,0,0,0,0,0,0,0,0,0,0,0,0,0,0,EA~
84,0,0,0,0,0,0,0,0,0,0)';$S;
    'VSS1284':'(0,0,0,0,0,0,0,0,0,0,0,0,0,0,0,0,0,0,0,0,0,0,0,0,0,0,0,0,0,0,0,EG~
13,0,0,0,0,0,0,0,0,0,0)';$S;
    'VSS1283':'(0,0,0,0,0,0,0,0,0,0,0,0,0,0,0,0,0,0,0,0,0,0,0,0,0,0,0,0,0,0,0,EF~
89,0,0,0,0,0,0,0,0,0,0)';$S;
    'VSS1282':'(0,0,0,0,0,0,0,0,0,0,0,0,0,0,0,0,0,0,0,0,0,0,0,0,0,0,0,0,0,0,0,EA~
80,0,0,0,0,0,0,0,0,0,0)';$S;
    'VSS1281':'(0,0,0,0,0,0,0,0,0,0,0,0,0,0,0,0,0,0,0,0,0,0,0,0,0,0,0,0,0,0,0,EA~
78,0,0,0,0,0,0,0,0,0,0)';$S;
    'VSS1280':'(0,0,0,0,0,0,0,0,0,0,0,0,0,0,0,0,0,0,0,0,0,0,0,0,0,0,0,0,0,0,0,EA~
76,0,0,0,0,0,0,0,0,0,0)';$S;
    'VSS1279':'(0,0,0,0,0,0,0,0,0,0,0,0,0,0,0,0,0,0,0,0,0,0,0,0,0,0,0,0,0,0,0,EA~
70,0,0,0,0,0,0,0,0,0,0)';$S;
    'VSS1278':'(0,0,0,0,0,0,0,0,0,0,0,0,0,0,0,0,0,0,0,0,0,0,0,0,0,0,0,0,0,0,0,EA~
33,0,0,0,0,0,0,0,0,0,0)';$S;
    'VSS1277':'(0,0,0,0,0,0,0,0,0,0,0,0,0,0,0,0,0,0,0,0,0,0,0,0,0,0,0,0,0,0,0,EF~
75,0,0,0,0,0,0,0,0,0,0)';$S;
    'VSS1276':'(0,0,0,0,0,0,0,0,0,0,0,0,0,0,0,0,0,0,0,0,0,0,0,0,0,0,0,0,0,0,0,EF~
73,0,0,0,0,0,0,0,0,0,0)';$S;
    'VSS1275':'(0,0,0,0,0,0,0,0,0,0,0,0,0,0,0,0,0,0,0,0,0,0,0,0,0,0,0,0,0,0,0,EA~
27,0,0,0,0,0,0,0,0,0,0)';$S;
    'VSS1274':'(0,0,0,0,0,0,0,0,0,0,0,0,0,0,0,0,0,0,0,0,0,0,0,0,0,0,0,0,0,0,0,EA~
21,0,0,0,0,0,0,0,0,0,0)';$S;
    'VSS1270':'(0,0,0,0,0,0,0,0,0,0,0,0,0,0,0,0,0,0,0,0,0,0,0,0,0,0,0,0,0,0,0,DY~
8,0,0,0,0,0,0,0,0,0,0)';$S;
    'VSS1269':'(0,0,0,0,0,0,0,0,0,0,0,0,0,0,0,0,0,0,0,0,0,0,0,0,0,0,0,0,0,0,0,DY~
77,0,0,0,0,0,0,0,0,0,0)';$S;
    'VSS1267':'(0,0,0,0,0,0,0,0,0,0,0,0,0,0,0,0,0,0,0,0,0,0,0,0,0,0,0,0,0,0,0,DW~
88,0,0,0,0,0,0,0,0,0,0)';$S;
    'VSS1266':'(0,0,0,0,0,0,0,0,0,0,0,0,0,0,0,0,0,0,0,0,0,0,0,0,0,0,0,0,0,0,0,DW~
84,0,0,0,0,0,0,0,0,0,0)';$S;
    'VSS1265':'(0,0,0,0,0,0,0,0,0,0,0,0,0,0,0,0,0,0,0,0,0,0,0,0,0,0,0,0,0,0,0,EF~
51,0,0,0,0,0,0,0,0,0,0)';$S;
    'VSS1264':'(0,0,0,0,0,0,0,0,0,0,0,0,0,0,0,0,0,0,0,0,0,0,0,0,0,0,0,0,0,0,0,DW~
82,0,0,0,0,0,0,0,0,0,0)';$S;
    'VSS1263':'(0,0,0,0,0,0,0,0,0,0,0,0,0,0,0,0,0,0,0,0,0,0,0,0,0,0,0,0,0,0,0,DW~
80,0,0,0,0,0,0,0,0,0,0)';$S;
    'VSS1262':'(0,0,0,0,0,0,0,0,0,0,0,0,0,0,0,0,0,0,0,0,0,0,0,0,0,0,0,0,0,0,0,DW~
76,0,0,0,0,0,0,0,0,0,0)';$S;
    'VSS1261':'(0,0,0,0,0,0,0,0,0,0,0,0,0,0,0,0,0,0,0,0,0,0,0,0,0,0,0,0,0,0,0,DW~
74,0,0,0,0,0,0,0,0,0,0)';$S;
    'VSS1260':'(0,0,0,0,0,0,0,0,0,0,0,0,0,0,0,0,0,0,0,0,0,0,0,0,0,0,0,0,0,0,0,DW~
72,0,0,0,0,0,0,0,0,0,0)';$S;
    'VSS1259':'(0,0,0,0,0,0,0,0,0,0,0,0,0,0,0,0,0,0,0,0,0,0,0,0,0,0,0,0,0,0,0,DW~
70,0,0,0,0,0,0,0,0,0,0)';$S;
    'VSS1258':'(0,0,0,0,0,0,0,0,0,0,0,0,0,0,0,0,0,0,0,0,0,0,0,0,0,0,0,0,0,0,0,DW~
68,0,0,0,0,0,0,0,0,0,0)';$S;
    'VSS1257':'(0,0,0,0,0,0,0,0,0,0,0,0,0,0,0,0,0,0,0,0,0,0,0,0,0,0,0,0,0,0,0,DW~
66,0,0,0,0,0,0,0,0,0,0)';$S;
    'VSS1237':'(0,0,0,0,0,0,0,0,0,0,0,0,0,0,0,0,0,0,0,0,0,0,0,0,0,0,0,0,0,0,0,EE~
52,0,0,0,0,0,0,0,0,0,0)';$S;
    'VSS1235':'(0,0,0,0,0,0,0,0,0,0,0,0,0,0,0,0,0,0,0,0,0,0,0,0,0,0,0,0,0,0,0,EE~
39,0,0,0,0,0,0,0,0,0,0)';$S;
    'VSS1232':'(0,0,0,0,0,0,0,0,0,0,0,0,0,0,0,0,0,0,0,0,0,0,0,0,0,0,0,0,0,0,0,EE~
17,0,0,0,0,0,0,0,0,0,0)';$S;
    'VSS1225':'(0,0,0,0,0,0,0,0,0,0,0,0,0,0,0,0,0,0,0,0,0,0,0,0,0,0,0,0,0,0,0,ED~
73,0,0,0,0,0,0,0,0,0,0)';$S;
    'VSS1224':'(0,0,0,0,0,0,0,0,0,0,0,0,0,0,0,0,0,0,0,0,0,0,0,0,0,0,0,0,0,0,0,ED~
67,0,0,0,0,0,0,0,0,0,0)';$S;
    'VSS1223':'(0,0,0,0,0,0,0,0,0,0,0,0,0,0,0,0,0,0,0,0,0,0,0,0,0,0,0,0,0,0,0,ED~
61,0,0,0,0,0,0,0,0,0,0)';$S;
    'VSS1220':'(0,0,0,0,0,0,0,0,0,0,0,0,0,0,0,0,0,0,0,0,0,0,0,0,0,0,0,0,0,0,0,ED~
55,0,0,0,0,0,0,0,0,0,0)';$S;
    'VSS1217':'(0,0,0,0,0,0,0,0,0,0,0,0,0,0,0,0,0,0,0,0,0,0,0,0,0,0,0,0,0,0,0,ED~
42,0,0,0,0,0,0,0,0,0,0)';$S;
    'VSS1210':'(0,0,0,0,0,0,0,0,0,0,0,0,0,0,0,0,0,0,0,0,0,0,0,0,0,0,0,0,0,0,0,ED~
18,0,0,0,0,0,0,0,0,0,0)';$S;
    'VSS1208':'(0,0,0,0,0,0,0,0,0,0,0,0,0,0,0,0,0,0,0,0,0,0,0,0,0,0,0,0,0,0,0,ED~
12,0,0,0,0,0,0,0,0,0,0)';$S;
    'VSS1200':'(0,0,0,0,0,0,0,0,0,0,0,0,0,0,0,0,0,0,0,0,0,0,0,0,0,0,0,0,0,0,0,EC~
68,0,0,0,0,0,0,0,0,0,0)';$S;
    'VSS1198':'(0,0,0,0,0,0,0,0,0,0,0,0,0,0,0,0,0,0,0,0,0,0,0,0,0,0,0,0,0,0,0,EC~
62,0,0,0,0,0,0,0,0,0,0)';$S;
    'VSS1197':'(0,0,0,0,0,0,0,0,0,0,0,0,0,0,0,0,0,0,0,0,0,0,0,0,0,0,0,0,0,0,0,EC~
60,0,0,0,0,0,0,0,0,0,0)';$S;
    'VSS1195':'(0,0,0,0,0,0,0,0,0,0,0,0,0,0,0,0,0,0,0,0,0,0,0,0,0,0,0,0,0,0,0,EC~
54,0,0,0,0,0,0,0,0,0,0)';$S;
    'VSS1193':'(0,0,0,0,0,0,0,0,0,0,0,0,0,0,0,0,0,0,0,0,0,0,0,0,0,0,0,0,0,0,0,EC~
5,0,0,0,0,0,0,0,0,0,0)';$S;
    'VSS1188':'(0,0,0,0,0,0,0,0,0,0,0,0,0,0,0,0,0,0,0,0,0,0,0,0,0,0,0,0,0,0,0,EC~
35,0,0,0,0,0,0,0,0,0,0)';$S;
    'VSS1185':'(0,0,0,0,0,0,0,0,0,0,0,0,0,0,0,0,0,0,0,0,0,0,0,0,0,0,0,0,0,0,0,EC~
25,0,0,0,0,0,0,0,0,0,0)';$S;
    'VSS1180':'(0,0,0,0,0,0,0,0,0,0,0,0,0,0,0,0,0,0,0,0,0,0,0,0,0,0,0,0,0,0,0,EB~
91,0,0,0,0,0,0,0,0,0,0)';$S;
    'VSS1171':'(0,0,0,0,0,0,0,0,0,0,0,0,0,0,0,0,0,0,0,0,0,0,0,0,0,0,0,0,0,0,0,EB~
63,0,0,0,0,0,0,0,0,0,0)';$S;
    'VSS1170':'(0,0,0,0,0,0,0,0,0,0,0,0,0,0,0,0,0,0,0,0,0,0,0,0,0,0,0,0,0,0,0,EB~
59,0,0,0,0,0,0,0,0,0,0)';$S;
    'VSS1168':'(0,0,0,0,0,0,0,0,0,0,0,0,0,0,0,0,0,0,0,0,0,0,0,0,0,0,0,0,0,0,0,EB~
53,0,0,0,0,0,0,0,0,0,0)';$S;
    'VSS1167':'(0,0,0,0,0,0,0,0,0,0,0,0,0,0,0,0,0,0,0,0,0,0,0,0,0,0,0,0,0,0,0,EB~
51,0,0,0,0,0,0,0,0,0,0)';$S;
    'VSS1165':'(0,0,0,0,0,0,0,0,0,0,0,0,0,0,0,0,0,0,0,0,0,0,0,0,0,0,0,0,0,0,0,EB~
44,0,0,0,0,0,0,0,0,0,0)';$S;
    'VSS1163':'(0,0,0,0,0,0,0,0,0,0,0,0,0,0,0,0,0,0,0,0,0,0,0,0,0,0,0,0,0,0,0,EB~
4,0,0,0,0,0,0,0,0,0,0)';$S;
    'VSS1161':'(0,0,0,0,0,0,0,0,0,0,0,0,0,0,0,0,0,0,0,0,0,0,0,0,0,0,0,0,0,0,0,EB~
34,0,0,0,0,0,0,0,0,0,0)';$S;
    'VSS1158':'(0,0,0,0,0,0,0,0,0,0,0,0,0,0,0,0,0,0,0,0,0,0,0,0,0,0,0,0,0,0,0,EB~
26,0,0,0,0,0,0,0,0,0,0)';$S;
    'VSS1156':'(0,0,0,0,0,0,0,0,0,0,0,0,0,0,0,0,0,0,0,0,0,0,0,0,0,0,0,0,0,0,0,EB~
20,0,0,0,0,0,0,0,0,0,0)';$S;
    'VSS1155':'(0,0,0,0,0,0,0,0,0,0,0,0,0,0,0,0,0,0,0,0,0,0,0,0,0,0,0,0,0,0,0,EB~
16,0,0,0,0,0,0,0,0,0,0)';$S;
    'VSS1146':'(0,0,0,0,0,0,0,0,0,0,0,0,0,0,0,0,0,0,0,0,0,0,0,0,0,0,0,0,0,0,0,EA~
64,0,0,0,0,0,0,0,0,0,0)';$S;
    'VSS1145':'(0,0,0,0,0,0,0,0,0,0,0,0,0,0,0,0,0,0,0,0,0,0,0,0,0,0,0,0,0,0,0,EA~
58,0,0,0,0,0,0,0,0,0,0)';$S;
    'VSS1144':'(0,0,0,0,0,0,0,0,0,0,0,0,0,0,0,0,0,0,0,0,0,0,0,0,0,0,0,0,0,0,0,EA~
52,0,0,0,0,0,0,0,0,0,0)';$S;
    'VSS1142':'(0,0,0,0,0,0,0,0,0,0,0,0,0,0,0,0,0,0,0,0,0,0,0,0,0,0,0,0,0,0,0,EA~
45,0,0,0,0,0,0,0,0,0,0)';$S;
    'VSS1141':'(0,0,0,0,0,0,0,0,0,0,0,0,0,0,0,0,0,0,0,0,0,0,0,0,0,0,0,0,0,0,0,EA~
39,0,0,0,0,0,0,0,0,0,0)';$S;
    'VSS1116':'(0,0,0,0,0,0,0,0,0,0,0,0,0,0,0,0,0,0,0,0,0,0,0,0,0,0,0,0,0,0,0,DY~
42,0,0,0,0,0,0,0,0,0,0)';$S;
    'VSS1115':'(0,0,0,0,0,0,0,0,0,0,0,0,0,0,0,0,0,0,0,0,0,0,0,0,0,0,0,0,0,0,0,DY~
4,0,0,0,0,0,0,0,0,0,0)';$S;
    'VSS1112':'(0,0,0,0,0,0,0,0,0,0,0,0,0,0,0,0,0,0,0,0,0,0,0,0,0,0,0,0,0,0,0,DY~
16,0,0,0,0,0,0,0,0,0,0)';$S;
    'VSS1111':'(0,0,0,0,0,0,0,0,0,0,0,0,0,0,0,0,0,0,0,0,0,0,0,0,0,0,0,0,0,0,0,DY~
12,0,0,0,0,0,0,0,0,0,0)';$S;
    'VSS1268':'(0,0,0,0,0,0,0,0,0,0,0,0,0,0,0,0,0,0,0,0,0,0,0,0,0,0,0,0,0,0,0,0,~
DW9,0,0,0,0,0,0,0,0,0)';$S;
    'VSS1256':'(0,0,0,0,0,0,0,0,0,0,0,0,0,0,0,0,0,0,0,0,0,0,0,0,0,0,0,0,0,0,0,0,~
DW64,0,0,0,0,0,0,0,0,0)';$S;
    'VSS1255':'(0,0,0,0,0,0,0,0,0,0,0,0,0,0,0,0,0,0,0,0,0,0,0,0,0,0,0,0,0,0,0,0,~
DW62,0,0,0,0,0,0,0,0,0)';$S;
    'VSS1254':'(0,0,0,0,0,0,0,0,0,0,0,0,0,0,0,0,0,0,0,0,0,0,0,0,0,0,0,0,0,0,0,0,~
DW58,0,0,0,0,0,0,0,0,0)';$S;
    'VSS1253':'(0,0,0,0,0,0,0,0,0,0,0,0,0,0,0,0,0,0,0,0,0,0,0,0,0,0,0,0,0,0,0,0,~
DW56,0,0,0,0,0,0,0,0,0)';$S;
    'VSS1252':'(0,0,0,0,0,0,0,0,0,0,0,0,0,0,0,0,0,0,0,0,0,0,0,0,0,0,0,0,0,0,0,0,~
DW54,0,0,0,0,0,0,0,0,0)';$S;
    'VSS1251':'(0,0,0,0,0,0,0,0,0,0,0,0,0,0,0,0,0,0,0,0,0,0,0,0,0,0,0,0,0,0,0,0,~
DW52,0,0,0,0,0,0,0,0,0)';$S;
    'VSS1250':'(0,0,0,0,0,0,0,0,0,0,0,0,0,0,0,0,0,0,0,0,0,0,0,0,0,0,0,0,0,0,0,0,~
DW50,0,0,0,0,0,0,0,0,0)';$S;
    'VSS1249':'(0,0,0,0,0,0,0,0,0,0,0,0,0,0,0,0,0,0,0,0,0,0,0,0,0,0,0,0,0,0,0,0,~
DW5,0,0,0,0,0,0,0,0,0)';$S;
    'VSS1248':'(0,0,0,0,0,0,0,0,0,0,0,0,0,0,0,0,0,0,0,0,0,0,0,0,0,0,0,0,0,0,0,0,~
DW48,0,0,0,0,0,0,0,0,0)';$S;
    'VSS1247':'(0,0,0,0,0,0,0,0,0,0,0,0,0,0,0,0,0,0,0,0,0,0,0,0,0,0,0,0,0,0,0,0,~
DW45,0,0,0,0,0,0,0,0,0)';$S;
    'VSS1246':'(0,0,0,0,0,0,0,0,0,0,0,0,0,0,0,0,0,0,0,0,0,0,0,0,0,0,0,0,0,0,0,0,~
DW43,0,0,0,0,0,0,0,0,0)';$S;
    'VSS1245':'(0,0,0,0,0,0,0,0,0,0,0,0,0,0,0,0,0,0,0,0,0,0,0,0,0,0,0,0,0,0,0,0,~
DW41,0,0,0,0,0,0,0,0,0)';$S;
    'VSS1244':'(0,0,0,0,0,0,0,0,0,0,0,0,0,0,0,0,0,0,0,0,0,0,0,0,0,0,0,0,0,0,0,0,~
DW39,0,0,0,0,0,0,0,0,0)';$S;
    'VSS1243':'(0,0,0,0,0,0,0,0,0,0,0,0,0,0,0,0,0,0,0,0,0,0,0,0,0,0,0,0,0,0,0,0,~
DW37,0,0,0,0,0,0,0,0,0)';$S;
    'VSS1242':'(0,0,0,0,0,0,0,0,0,0,0,0,0,0,0,0,0,0,0,0,0,0,0,0,0,0,0,0,0,0,0,0,~
DW35,0,0,0,0,0,0,0,0,0)';$S;
    'VSS1241':'(0,0,0,0,0,0,0,0,0,0,0,0,0,0,0,0,0,0,0,0,0,0,0,0,0,0,0,0,0,0,0,0,~
DW33,0,0,0,0,0,0,0,0,0)';$S;
    'VSS1240':'(0,0,0,0,0,0,0,0,0,0,0,0,0,0,0,0,0,0,0,0,0,0,0,0,0,0,0,0,0,0,0,0,~
DW31,0,0,0,0,0,0,0,0,0)';$S;
    'VSS1239':'(0,0,0,0,0,0,0,0,0,0,0,0,0,0,0,0,0,0,0,0,0,0,0,0,0,0,0,0,0,0,0,0,~
DW29,0,0,0,0,0,0,0,0,0)';$S;
    'VSS1238':'(0,0,0,0,0,0,0,0,0,0,0,0,0,0,0,0,0,0,0,0,0,0,0,0,0,0,0,0,0,0,0,0,~
DW27,0,0,0,0,0,0,0,0,0)';$S;
    'VSS1236':'(0,0,0,0,0,0,0,0,0,0,0,0,0,0,0,0,0,0,0,0,0,0,0,0,0,0,0,0,0,0,0,0,~
DW25,0,0,0,0,0,0,0,0,0)';$S;
    'VSS1234':'(0,0,0,0,0,0,0,0,0,0,0,0,0,0,0,0,0,0,0,0,0,0,0,0,0,0,0,0,0,0,0,0,~
DW23,0,0,0,0,0,0,0,0,0)';$S;
    'VSS1233':'(0,0,0,0,0,0,0,0,0,0,0,0,0,0,0,0,0,0,0,0,0,0,0,0,0,0,0,0,0,0,0,0,~
DW19,0,0,0,0,0,0,0,0,0)';$S;
    'VSS1231':'(0,0,0,0,0,0,0,0,0,0,0,0,0,0,0,0,0,0,0,0,0,0,0,0,0,0,0,0,0,0,0,0,~
DW17,0,0,0,0,0,0,0,0,0)';$S;
    'VSS1230':'(0,0,0,0,0,0,0,0,0,0,0,0,0,0,0,0,0,0,0,0,0,0,0,0,0,0,0,0,0,0,0,0,~
DW13,0,0,0,0,0,0,0,0,0)';$S;
    'VSS1229':'(0,0,0,0,0,0,0,0,0,0,0,0,0,0,0,0,0,0,0,0,0,0,0,0,0,0,0,0,0,0,0,0,~
DW1,0,0,0,0,0,0,0,0,0)';$S;
    'VSS1228':'(0,0,0,0,0,0,0,0,0,0,0,0,0,0,0,0,0,0,0,0,0,0,0,0,0,0,0,0,0,0,0,0,~
DV91,0,0,0,0,0,0,0,0,0)';$S;
    'VSS1227':'(0,0,0,0,0,0,0,0,0,0,0,0,0,0,0,0,0,0,0,0,0,0,0,0,0,0,0,0,0,0,0,0,~
DV87,0,0,0,0,0,0,0,0,0)';$S;
    'VSS1226':'(0,0,0,0,0,0,0,0,0,0,0,0,0,0,0,0,0,0,0,0,0,0,0,0,0,0,0,0,0,0,0,0,~
DV83,0,0,0,0,0,0,0,0,0)';$S;
    'VSS1222':'(0,0,0,0,0,0,0,0,0,0,0,0,0,0,0,0,0,0,0,0,0,0,0,0,0,0,0,0,0,0,0,0,~
DV81,0,0,0,0,0,0,0,0,0)';$S;
    'VSS1221':'(0,0,0,0,0,0,0,0,0,0,0,0,0,0,0,0,0,0,0,0,0,0,0,0,0,0,0,0,0,0,0,0,~
DV8,0,0,0,0,0,0,0,0,0)';$S;
    'VSS1219':'(0,0,0,0,0,0,0,0,0,0,0,0,0,0,0,0,0,0,0,0,0,0,0,0,0,0,0,0,0,0,0,0,~
DV79,0,0,0,0,0,0,0,0,0)';$S;
    'VSS1218':'(0,0,0,0,0,0,0,0,0,0,0,0,0,0,0,0,0,0,0,0,0,0,0,0,0,0,0,0,0,0,0,0,~
DV77,0,0,0,0,0,0,0,0,0)';$S;
    'VSS1216':'(0,0,0,0,0,0,0,0,0,0,0,0,0,0,0,0,0,0,0,0,0,0,0,0,0,0,0,0,0,0,0,0,~
DU88,0,0,0,0,0,0,0,0,0)';$S;
    'VSS1215':'(0,0,0,0,0,0,0,0,0,0,0,0,0,0,0,0,0,0,0,0,0,0,0,0,0,0,0,0,0,0,0,0,~
DU84,0,0,0,0,0,0,0,0,0)';$S;
    'VSS1214':'(0,0,0,0,0,0,0,0,0,0,0,0,0,0,0,0,0,0,0,0,0,0,0,0,0,0,0,0,0,0,0,0,~
DU78,0,0,0,0,0,0,0,0,0)';$S;
    'VSS1213':'(0,0,0,0,0,0,0,0,0,0,0,0,0,0,0,0,0,0,0,0,0,0,0,0,0,0,0,0,0,0,0,0,~
DU76,0,0,0,0,0,0,0,0,0)';$S;
    'VSS1212':'(0,0,0,0,0,0,0,0,0,0,0,0,0,0,0,0,0,0,0,0,0,0,0,0,0,0,0,0,0,0,0,0,~
DU33,0,0,0,0,0,0,0,0,0)';$S;
    'VSS1211':'(0,0,0,0,0,0,0,0,0,0,0,0,0,0,0,0,0,0,0,0,0,0,0,0,0,0,0,0,0,0,0,0,~
DU27,0,0,0,0,0,0,0,0,0)';$S;
    'VSS1209':'(0,0,0,0,0,0,0,0,0,0,0,0,0,0,0,0,0,0,0,0,0,0,0,0,0,0,0,0,0,0,0,0,~
DU21,0,0,0,0,0,0,0,0,0)';$S;
    'VSS1207':'(0,0,0,0,0,0,0,0,0,0,0,0,0,0,0,0,0,0,0,0,0,0,0,0,0,0,0,0,0,0,0,0,~
DT8,0,0,0,0,0,0,0,0,0)';$S;
    'VSS1206':'(0,0,0,0,0,0,0,0,0,0,0,0,0,0,0,0,0,0,0,0,0,0,0,0,0,0,0,0,0,0,0,0,~
DT75,0,0,0,0,0,0,0,0,0)';$S;
    'VSS1205':'(0,0,0,0,0,0,0,0,0,0,0,0,0,0,0,0,0,0,0,0,0,0,0,0,0,0,0,0,0,0,0,0,~
DT71,0,0,0,0,0,0,0,0,0)';$S;
    'VSS1204':'(0,0,0,0,0,0,0,0,0,0,0,0,0,0,0,0,0,0,0,0,0,0,0,0,0,0,0,0,0,0,0,0,~
DT69,0,0,0,0,0,0,0,0,0)';$S;
    'VSS1203':'(0,0,0,0,0,0,0,0,0,0,0,0,0,0,0,0,0,0,0,0,0,0,0,0,0,0,0,0,0,0,0,0,~
DT65,0,0,0,0,0,0,0,0,0)';$S;
    'VSS1202':'(0,0,0,0,0,0,0,0,0,0,0,0,0,0,0,0,0,0,0,0,0,0,0,0,0,0,0,0,0,0,0,0,~
DT57,0,0,0,0,0,0,0,0,0)';$S;
    'VSS1201':'(0,0,0,0,0,0,0,0,0,0,0,0,0,0,0,0,0,0,0,0,0,0,0,0,0,0,0,0,0,0,0,0,~
DT47,0,0,0,0,0,0,0,0,0)';$S;
    'VSS1199':'(0,0,0,0,0,0,0,0,0,0,0,0,0,0,0,0,0,0,0,0,0,0,0,0,0,0,0,0,0,0,0,0,~
DT40,0,0,0,0,0,0,0,0,0)';$S;
    'VSS1196':'(0,0,0,0,0,0,0,0,0,0,0,0,0,0,0,0,0,0,0,0,0,0,0,0,0,0,0,0,0,0,0,0,~
DT38,0,0,0,0,0,0,0,0,0)';$S;
    'VSS1194':'(0,0,0,0,0,0,0,0,0,0,0,0,0,0,0,0,0,0,0,0,0,0,0,0,0,0,0,0,0,0,0,0,~
DT34,0,0,0,0,0,0,0,0,0)';$S;
    'VSS1192':'(0,0,0,0,0,0,0,0,0,0,0,0,0,0,0,0,0,0,0,0,0,0,0,0,0,0,0,0,0,0,0,0,~
DT32,0,0,0,0,0,0,0,0,0)';$S;
    'VSS1191':'(0,0,0,0,0,0,0,0,0,0,0,0,0,0,0,0,0,0,0,0,0,0,0,0,0,0,0,0,0,0,0,0,~
DT28,0,0,0,0,0,0,0,0,0)';$S;
    'VSS1190':'(0,0,0,0,0,0,0,0,0,0,0,0,0,0,0,0,0,0,0,0,0,0,0,0,0,0,0,0,0,0,0,0,~
DT22,0,0,0,0,0,0,0,0,0)';$S;
    'VSS1189':'(0,0,0,0,0,0,0,0,0,0,0,0,0,0,0,0,0,0,0,0,0,0,0,0,0,0,0,0,0,0,0,0,~
DT12,0,0,0,0,0,0,0,0,0)';$S;
    'VSS1187':'(0,0,0,0,0,0,0,0,0,0,0,0,0,0,0,0,0,0,0,0,0,0,0,0,0,0,0,0,0,0,0,0,~
DR9,0,0,0,0,0,0,0,0,0)';$S;
    'VSS1186':'(0,0,0,0,0,0,0,0,0,0,0,0,0,0,0,0,0,0,0,0,0,0,0,0,0,0,0,0,0,0,0,0,~
DR88,0,0,0,0,0,0,0,0,0)';$S;
    'VSS1184':'(0,0,0,0,0,0,0,0,0,0,0,0,0,0,0,0,0,0,0,0,0,0,0,0,0,0,0,0,0,0,0,0,~
DR84,0,0,0,0,0,0,0,0,0)';$S;
    'VSS1183':'(0,0,0,0,0,0,0,0,0,0,0,0,0,0,0,0,0,0,0,0,0,0,0,0,0,0,0,0,0,0,0,0,~
DR78,0,0,0,0,0,0,0,0,0)';$S;
    'VSS1182':'(0,0,0,0,0,0,0,0,0,0,0,0,0,0,0,0,0,0,0,0,0,0,0,0,0,0,0,0,0,0,0,0,~
DR74,0,0,0,0,0,0,0,0,0)';$S;
    'VSS1181':'(0,0,0,0,0,0,0,0,0,0,0,0,0,0,0,0,0,0,0,0,0,0,0,0,0,0,0,0,0,0,0,0,~
DR66,0,0,0,0,0,0,0,0,0)';$S;
    'VSS1179':'(0,0,0,0,0,0,0,0,0,0,0,0,0,0,0,0,0,0,0,0,0,0,0,0,0,0,0,0,0,0,0,0,~
DR56,0,0,0,0,0,0,0,0,0)';$S;
    'VSS1178':'(0,0,0,0,0,0,0,0,0,0,0,0,0,0,0,0,0,0,0,0,0,0,0,0,0,0,0,0,0,0,0,0,~
DR50,0,0,0,0,0,0,0,0,0)';$S;
    'VSS1177':'(0,0,0,0,0,0,0,0,0,0,0,0,0,0,0,0,0,0,0,0,0,0,0,0,0,0,0,0,0,0,0,0,~
DR48,0,0,0,0,0,0,0,0,0)';$S;
    'VSS1176':'(0,0,0,0,0,0,0,0,0,0,0,0,0,0,0,0,0,0,0,0,0,0,0,0,0,0,0,0,0,0,0,0,~
DR43,0,0,0,0,0,0,0,0,0)';$S;
    'VSS1175':'(0,0,0,0,0,0,0,0,0,0,0,0,0,0,0,0,0,0,0,0,0,0,0,0,0,0,0,0,0,0,0,0,~
DR41,0,0,0,0,0,0,0,0,0)';$S;
    'VSS1174':'(0,0,0,0,0,0,0,0,0,0,0,0,0,0,0,0,0,0,0,0,0,0,0,0,0,0,0,0,0,0,0,0,~
DR37,0,0,0,0,0,0,0,0,0)';$S;
    'VSS1173':'(0,0,0,0,0,0,0,0,0,0,0,0,0,0,0,0,0,0,0,0,0,0,0,0,0,0,0,0,0,0,0,0,~
DR31,0,0,0,0,0,0,0,0,0)';$S;
    'VSS1172':'(0,0,0,0,0,0,0,0,0,0,0,0,0,0,0,0,0,0,0,0,0,0,0,0,0,0,0,0,0,0,0,0,~
DR29,0,0,0,0,0,0,0,0,0)';$S;
    'VSS1169':'(0,0,0,0,0,0,0,0,0,0,0,0,0,0,0,0,0,0,0,0,0,0,0,0,0,0,0,0,0,0,0,0,~
DR23,0,0,0,0,0,0,0,0,0)';$S;
    'VSS1166':'(0,0,0,0,0,0,0,0,0,0,0,0,0,0,0,0,0,0,0,0,0,0,0,0,0,0,0,0,0,0,0,0,~
DR19,0,0,0,0,0,0,0,0,0)';$S;
    'VSS1164':'(0,0,0,0,0,0,0,0,0,0,0,0,0,0,0,0,0,0,0,0,0,0,0,0,0,0,0,0,0,0,0,0,~
DR13,0,0,0,0,0,0,0,0,0)';$S;
    'VSS1162':'(0,0,0,0,0,0,0,0,0,0,0,0,0,0,0,0,0,0,0,0,0,0,0,0,0,0,0,0,0,0,0,0,~
DR1,0,0,0,0,0,0,0,0,0)';$S;
    'VSS1160':'(0,0,0,0,0,0,0,0,0,0,0,0,0,0,0,0,0,0,0,0,0,0,0,0,0,0,0,0,0,0,0,0,~
DP87,0,0,0,0,0,0,0,0,0)';$S;
    'VSS1159':'(0,0,0,0,0,0,0,0,0,0,0,0,0,0,0,0,0,0,0,0,0,0,0,0,0,0,0,0,0,0,0,0,~
DP81,0,0,0,0,0,0,0,0,0)';$S;
    'VSS1157':'(0,0,0,0,0,0,0,0,0,0,0,0,0,0,0,0,0,0,0,0,0,0,0,0,0,0,0,0,0,0,0,0,~
DP8,0,0,0,0,0,0,0,0,0)';$S;
    'VSS1154':'(0,0,0,0,0,0,0,0,0,0,0,0,0,0,0,0,0,0,0,0,0,0,0,0,0,0,0,0,0,0,0,0,~
DP73,0,0,0,0,0,0,0,0,0)';$S;
    'VSS1153':'(0,0,0,0,0,0,0,0,0,0,0,0,0,0,0,0,0,0,0,0,0,0,0,0,0,0,0,0,0,0,0,0,~
DP49,0,0,0,0,0,0,0,0,0)';$S;
    'VSS1152':'(0,0,0,0,0,0,0,0,0,0,0,0,0,0,0,0,0,0,0,0,0,0,0,0,0,0,0,0,0,0,0,0,~
DP4,0,0,0,0,0,0,0,0,0)';$S;
    'VSS1151':'(0,0,0,0,0,0,0,0,0,0,0,0,0,0,0,0,0,0,0,0,0,0,0,0,0,0,0,0,0,0,0,0,~
DP36,0,0,0,0,0,0,0,0,0)';$S;
    'VSS1150':'(0,0,0,0,0,0,0,0,0,0,0,0,0,0,0,0,0,0,0,0,0,0,0,0,0,0,0,0,0,0,0,0,~
DP30,0,0,0,0,0,0,0,0,0)';$S;
    'VSS1149':'(0,0,0,0,0,0,0,0,0,0,0,0,0,0,0,0,0,0,0,0,0,0,0,0,0,0,0,0,0,0,0,0,~
DP16,0,0,0,0,0,0,0,0,0)';$S;
    'VSS1148':'(0,0,0,0,0,0,0,0,0,0,0,0,0,0,0,0,0,0,0,0,0,0,0,0,0,0,0,0,0,0,0,0,~
DN88,0,0,0,0,0,0,0,0,0)';$S;
    'VSS1147':'(0,0,0,0,0,0,0,0,0,0,0,0,0,0,0,0,0,0,0,0,0,0,0,0,0,0,0,0,0,0,0,0,~
DN84,0,0,0,0,0,0,0,0,0)';$S;
    'VSS1143':'(0,0,0,0,0,0,0,0,0,0,0,0,0,0,0,0,0,0,0,0,0,0,0,0,0,0,0,0,0,0,0,0,~
DN78,0,0,0,0,0,0,0,0,0)';$S;
    'VSS1140':'(0,0,0,0,0,0,0,0,0,0,0,0,0,0,0,0,0,0,0,0,0,0,0,0,0,0,0,0,0,0,0,0,~
DM8,0,0,0,0,0,0,0,0,0)';$S;
    'VSS1139':'(0,0,0,0,0,0,0,0,0,0,0,0,0,0,0,0,0,0,0,0,0,0,0,0,0,0,0,0,0,0,0,0,~
DM79,0,0,0,0,0,0,0,0,0)';$S;
    'VSS1138':'(0,0,0,0,0,0,0,0,0,0,0,0,0,0,0,0,0,0,0,0,0,0,0,0,0,0,0,0,0,0,0,0,~
DM77,0,0,0,0,0,0,0,0,0)';$S;
    'VSS1137':'(0,0,0,0,0,0,0,0,0,0,0,0,0,0,0,0,0,0,0,0,0,0,0,0,0,0,0,0,0,0,0,0,~
DM75,0,0,0,0,0,0,0,0,0)';$S;
    'VSS1136':'(0,0,0,0,0,0,0,0,0,0,0,0,0,0,0,0,0,0,0,0,0,0,0,0,0,0,0,0,0,0,0,0,~
DM71,0,0,0,0,0,0,0,0,0)';$S;
    'VSS1135':'(0,0,0,0,0,0,0,0,0,0,0,0,0,0,0,0,0,0,0,0,0,0,0,0,0,0,0,0,0,0,0,0,~
DM69,0,0,0,0,0,0,0,0,0)';$S;
    'VSS1134':'(0,0,0,0,0,0,0,0,0,0,0,0,0,0,0,0,0,0,0,0,0,0,0,0,0,0,0,0,0,0,0,0,~
DM67,0,0,0,0,0,0,0,0,0)';$S;
    'VSS1133':'(0,0,0,0,0,0,0,0,0,0,0,0,0,0,0,0,0,0,0,0,0,0,0,0,0,0,0,0,0,0,0,0,~
DM65,0,0,0,0,0,0,0,0,0)';$S;
    'VSS1132':'(0,0,0,0,0,0,0,0,0,0,0,0,0,0,0,0,0,0,0,0,0,0,0,0,0,0,0,0,0,0,0,0,~
DM63,0,0,0,0,0,0,0,0,0)';$S;
    'VSS1130':'(0,0,0,0,0,0,0,0,0,0,0,0,0,0,0,0,0,0,0,0,0,0,0,0,0,0,0,0,0,0,0,0,~
DM61,0,0,0,0,0,0,0,0,0)';$S;
    'VSS1128':'(0,0,0,0,0,0,0,0,0,0,0,0,0,0,0,0,0,0,0,0,0,0,0,0,0,0,0,0,0,0,0,0,~
DM59,0,0,0,0,0,0,0,0,0)';$S;
    'VSS1127':'(0,0,0,0,0,0,0,0,0,0,0,0,0,0,0,0,0,0,0,0,0,0,0,0,0,0,0,0,0,0,0,0,~
DM57,0,0,0,0,0,0,0,0,0)';$S;
    'VSS1124':'(0,0,0,0,0,0,0,0,0,0,0,0,0,0,0,0,0,0,0,0,0,0,0,0,0,0,0,0,0,0,0,0,~
DM55,0,0,0,0,0,0,0,0,0)';$S;
    'VSS1123':'(0,0,0,0,0,0,0,0,0,0,0,0,0,0,0,0,0,0,0,0,0,0,0,0,0,0,0,0,0,0,0,0,~
DM53,0,0,0,0,0,0,0,0,0)';$S;
    'VSS1122':'(0,0,0,0,0,0,0,0,0,0,0,0,0,0,0,0,0,0,0,0,0,0,0,0,0,0,0,0,0,0,0,0,~
DM49,0,0,0,0,0,0,0,0,0)';$S;
    'VSS1121':'(0,0,0,0,0,0,0,0,0,0,0,0,0,0,0,0,0,0,0,0,0,0,0,0,0,0,0,0,0,0,0,0,~
DM47,0,0,0,0,0,0,0,0,0)';$S;
    'VSS1120':'(0,0,0,0,0,0,0,0,0,0,0,0,0,0,0,0,0,0,0,0,0,0,0,0,0,0,0,0,0,0,0,0,~
DM44,0,0,0,0,0,0,0,0,0)';$S;
    'VSS1119':'(0,0,0,0,0,0,0,0,0,0,0,0,0,0,0,0,0,0,0,0,0,0,0,0,0,0,0,0,0,0,0,0,~
DM42,0,0,0,0,0,0,0,0,0)';$S;
    'VSS1118':'(0,0,0,0,0,0,0,0,0,0,0,0,0,0,0,0,0,0,0,0,0,0,0,0,0,0,0,0,0,0,0,0,~
DM40,0,0,0,0,0,0,0,0,0)';$S;
    'VSS1117':'(0,0,0,0,0,0,0,0,0,0,0,0,0,0,0,0,0,0,0,0,0,0,0,0,0,0,0,0,0,0,0,0,~
DM4,0,0,0,0,0,0,0,0,0)';$S;
    'VSS1114':'(0,0,0,0,0,0,0,0,0,0,0,0,0,0,0,0,0,0,0,0,0,0,0,0,0,0,0,0,0,0,0,0,~
DM38,0,0,0,0,0,0,0,0,0)';$S;
    'VSS1113':'(0,0,0,0,0,0,0,0,0,0,0,0,0,0,0,0,0,0,0,0,0,0,0,0,0,0,0,0,0,0,0,0,~
DM36,0,0,0,0,0,0,0,0,0)';$S;
    'VSS1110':'(0,0,0,0,0,0,0,0,0,0,0,0,0,0,0,0,0,0,0,0,0,0,0,0,0,0,0,0,0,0,0,0,~
DM34,0,0,0,0,0,0,0,0,0)';$S;
    'VSS1109':'(0,0,0,0,0,0,0,0,0,0,0,0,0,0,0,0,0,0,0,0,0,0,0,0,0,0,0,0,0,0,0,0,~
DM32,0,0,0,0,0,0,0,0,0)';$S;
    'VSS1108':'(0,0,0,0,0,0,0,0,0,0,0,0,0,0,0,0,0,0,0,0,0,0,0,0,0,0,0,0,0,0,0,0,~
DM30,0,0,0,0,0,0,0,0,0)';$S;
    'VSS1107':'(0,0,0,0,0,0,0,0,0,0,0,0,0,0,0,0,0,0,0,0,0,0,0,0,0,0,0,0,0,0,0,0,~
DM28,0,0,0,0,0,0,0,0,0)';$S;
    'VSS1106':'(0,0,0,0,0,0,0,0,0,0,0,0,0,0,0,0,0,0,0,0,0,0,0,0,0,0,0,0,0,0,0,0,~
DM26,0,0,0,0,0,0,0,0,0)';$S;
    'VSS1105':'(0,0,0,0,0,0,0,0,0,0,0,0,0,0,0,0,0,0,0,0,0,0,0,0,0,0,0,0,0,0,0,0,~
DM24,0,0,0,0,0,0,0,0,0)';$S;
    'VSS1104':'(0,0,0,0,0,0,0,0,0,0,0,0,0,0,0,0,0,0,0,0,0,0,0,0,0,0,0,0,0,0,0,0,~
DM22,0,0,0,0,0,0,0,0,0)';$S;
    'VSS1103':'(0,0,0,0,0,0,0,0,0,0,0,0,0,0,0,0,0,0,0,0,0,0,0,0,0,0,0,0,0,0,0,0,~
DM20,0,0,0,0,0,0,0,0,0)';$S;
    'VSS1102':'(0,0,0,0,0,0,0,0,0,0,0,0,0,0,0,0,0,0,0,0,0,0,0,0,0,0,0,0,0,0,0,0,~
DM18,0,0,0,0,0,0,0,0,0)';$S;
    'VSS1101':'(0,0,0,0,0,0,0,0,0,0,0,0,0,0,0,0,0,0,0,0,0,0,0,0,0,0,0,0,0,0,0,0,~
DM16,0,0,0,0,0,0,0,0,0)';$S;
    'VSS1100':'(0,0,0,0,0,0,0,0,0,0,0,0,0,0,0,0,0,0,0,0,0,0,0,0,0,0,0,0,0,0,0,0,~
DM12,0,0,0,0,0,0,0,0,0)';$S;
    'VSS1097':'(0,0,0,0,0,0,0,0,0,0,0,0,0,0,0,0,0,0,0,0,0,0,0,0,0,0,0,0,0,0,0,0,~
DW60,0,0,0,0,0,0,0,0,0)';$S;
    'VSS1077':'(0,0,0,0,0,0,0,0,0,0,0,0,0,0,0,0,0,0,0,0,0,0,0,0,0,0,0,0,0,0,0,0,~
DW21,0,0,0,0,0,0,0,0,0)';$S;
    'VSS1064':'(0,0,0,0,0,0,0,0,0,0,0,0,0,0,0,0,0,0,0,0,0,0,0,0,0,0,0,0,0,0,0,0,~
DV42,0,0,0,0,0,0,0,0,0)';$S;
    'VSS1063':'(0,0,0,0,0,0,0,0,0,0,0,0,0,0,0,0,0,0,0,0,0,0,0,0,0,0,0,0,0,0,0,0,~
DV4,0,0,0,0,0,0,0,0,0)';$S;
    'VSS1060':'(0,0,0,0,0,0,0,0,0,0,0,0,0,0,0,0,0,0,0,0,0,0,0,0,0,0,0,0,0,0,0,0,~
DV16,0,0,0,0,0,0,0,0,0)';$S;
    'VSS1059':'(0,0,0,0,0,0,0,0,0,0,0,0,0,0,0,0,0,0,0,0,0,0,0,0,0,0,0,0,0,0,0,0,~
DV12,0,0,0,0,0,0,0,0,0)';$S;
    'VSS1054':'(0,0,0,0,0,0,0,0,0,0,0,0,0,0,0,0,0,0,0,0,0,0,0,0,0,0,0,0,0,0,0,0,~
DU70,0,0,0,0,0,0,0,0,0)';$S;
    'VSS1052':'(0,0,0,0,0,0,0,0,0,0,0,0,0,0,0,0,0,0,0,0,0,0,0,0,0,0,0,0,0,0,0,0,~
DU64,0,0,0,0,0,0,0,0,0)';$S;
    'VSS1051':'(0,0,0,0,0,0,0,0,0,0,0,0,0,0,0,0,0,0,0,0,0,0,0,0,0,0,0,0,0,0,0,0,~
DU58,0,0,0,0,0,0,0,0,0)';$S;
    'VSS1050':'(0,0,0,0,0,0,0,0,0,0,0,0,0,0,0,0,0,0,0,0,0,0,0,0,0,0,0,0,0,0,0,0,~
DU52,0,0,0,0,0,0,0,0,0)';$S;
    'VSS1048':'(0,0,0,0,0,0,0,0,0,0,0,0,0,0,0,0,0,0,0,0,0,0,0,0,0,0,0,0,0,0,0,0,~
DU45,0,0,0,0,0,0,0,0,0)';$S;
    'VSS1047':'(0,0,0,0,0,0,0,0,0,0,0,0,0,0,0,0,0,0,0,0,0,0,0,0,0,0,0,0,0,0,0,0,~
DU39,0,0,0,0,0,0,0,0,0)';$S;
    'VSS1036':'(0,0,0,0,0,0,0,0,0,0,0,0,0,0,0,0,0,0,0,0,0,0,0,0,0,0,0,0,0,0,0,0,~
DT83,0,0,0,0,0,0,0,0,0)';$S;
    'VSS1029':'(0,0,0,0,0,0,0,0,0,0,0,0,0,0,0,0,0,0,0,0,0,0,0,0,0,0,0,0,0,0,0,0,~
DT63,0,0,0,0,0,0,0,0,0)';$S;
    'VSS1028':'(0,0,0,0,0,0,0,0,0,0,0,0,0,0,0,0,0,0,0,0,0,0,0,0,0,0,0,0,0,0,0,0,~
DT59,0,0,0,0,0,0,0,0,0)';$S;
    'VSS1026':'(0,0,0,0,0,0,0,0,0,0,0,0,0,0,0,0,0,0,0,0,0,0,0,0,0,0,0,0,0,0,0,0,~
DT53,0,0,0,0,0,0,0,0,0)';$S;
    'VSS1025':'(0,0,0,0,0,0,0,0,0,0,0,0,0,0,0,0,0,0,0,0,0,0,0,0,0,0,0,0,0,0,0,0,~
DT51,0,0,0,0,0,0,0,0,0)';$S;
    'VSS1023':'(0,0,0,0,0,0,0,0,0,0,0,0,0,0,0,0,0,0,0,0,0,0,0,0,0,0,0,0,0,0,0,0,~
DT44,0,0,0,0,0,0,0,0,0)';$S;
    'VSS1021':'(0,0,0,0,0,0,0,0,0,0,0,0,0,0,0,0,0,0,0,0,0,0,0,0,0,0,0,0,0,0,0,0,~
DT4,0,0,0,0,0,0,0,0,0)';$S;
    'VSS1016':'(0,0,0,0,0,0,0,0,0,0,0,0,0,0,0,0,0,0,0,0,0,0,0,0,0,0,0,0,0,0,0,0,~
DT26,0,0,0,0,0,0,0,0,0)';$S;
    'VSS1014':'(0,0,0,0,0,0,0,0,0,0,0,0,0,0,0,0,0,0,0,0,0,0,0,0,0,0,0,0,0,0,0,0,~
DT20,0,0,0,0,0,0,0,0,0)';$S;
    'VSS1013':'(0,0,0,0,0,0,0,0,0,0,0,0,0,0,0,0,0,0,0,0,0,0,0,0,0,0,0,0,0,0,0,0,~
DT16,0,0,0,0,0,0,0,0,0)';$S;
    'VSS1006':'(0,0,0,0,0,0,0,0,0,0,0,0,0,0,0,0,0,0,0,0,0,0,0,0,0,0,0,0,0,0,0,0,~
DR72,0,0,0,0,0,0,0,0,0)';$S;
    'VSS1005':'(0,0,0,0,0,0,0,0,0,0,0,0,0,0,0,0,0,0,0,0,0,0,0,0,0,0,0,0,0,0,0,0,~
DR68,0,0,0,0,0,0,0,0,0)';$S;
    'VSS1003':'(0,0,0,0,0,0,0,0,0,0,0,0,0,0,0,0,0,0,0,0,0,0,0,0,0,0,0,0,0,0,0,0,~
DR62,0,0,0,0,0,0,0,0,0)';$S;
    'VSS1002':'(0,0,0,0,0,0,0,0,0,0,0,0,0,0,0,0,0,0,0,0,0,0,0,0,0,0,0,0,0,0,0,0,~
DR60,0,0,0,0,0,0,0,0,0)';$S;
    'VSS1000':'(0,0,0,0,0,0,0,0,0,0,0,0,0,0,0,0,0,0,0,0,0,0,0,0,0,0,0,0,0,0,0,0,~
DR54,0,0,0,0,0,0,0,0,0)';$S;
    'VSS998':'(0,0,0,0,0,0,0,0,0,0,0,0,0,0,0,0,0,0,0,0,0,0,0,0,0,0,0,0,0,0,0,0,D~
R5,0,0,0,0,0,0,0,0,0)';$S;
    'VSS993':'(0,0,0,0,0,0,0,0,0,0,0,0,0,0,0,0,0,0,0,0,0,0,0,0,0,0,0,0,0,0,0,0,D~
R35,0,0,0,0,0,0,0,0,0)';$S;
    'VSS990':'(0,0,0,0,0,0,0,0,0,0,0,0,0,0,0,0,0,0,0,0,0,0,0,0,0,0,0,0,0,0,0,0,D~
R25,0,0,0,0,0,0,0,0,0)';$S;
    'VSS985':'(0,0,0,0,0,0,0,0,0,0,0,0,0,0,0,0,0,0,0,0,0,0,0,0,0,0,0,0,0,0,0,0,D~
P91,0,0,0,0,0,0,0,0,0)';$S;
    'VSS980':'(0,0,0,0,0,0,0,0,0,0,0,0,0,0,0,0,0,0,0,0,0,0,0,0,0,0,0,0,0,0,0,0,D~
P67,0,0,0,0,0,0,0,0,0)';$S;
    'VSS979':'(0,0,0,0,0,0,0,0,0,0,0,0,0,0,0,0,0,0,0,0,0,0,0,0,0,0,0,0,0,0,0,0,D~
P61,0,0,0,0,0,0,0,0,0)';$S;
    'VSS976':'(0,0,0,0,0,0,0,0,0,0,0,0,0,0,0,0,0,0,0,0,0,0,0,0,0,0,0,0,0,0,0,0,D~
P55,0,0,0,0,0,0,0,0,0)';$S;
    'VSS973':'(0,0,0,0,0,0,0,0,0,0,0,0,0,0,0,0,0,0,0,0,0,0,0,0,0,0,0,0,0,0,0,0,D~
P42,0,0,0,0,0,0,0,0,0)';$S;
    'VSS969':'(0,0,0,0,0,0,0,0,0,0,0,0,0,0,0,0,0,0,0,0,0,0,0,0,0,0,0,0,0,0,0,0,D~
P24,0,0,0,0,0,0,0,0,0)';$S;
    'VSS968':'(0,0,0,0,0,0,0,0,0,0,0,0,0,0,0,0,0,0,0,0,0,0,0,0,0,0,0,0,0,0,0,0,D~
P18,0,0,0,0,0,0,0,0,0)';$S;
    'VSS966':'(0,0,0,0,0,0,0,0,0,0,0,0,0,0,0,0,0,0,0,0,0,0,0,0,0,0,0,0,0,0,0,0,D~
P12,0,0,0,0,0,0,0,0,0)';$S;
    'VSS959':'(0,0,0,0,0,0,0,0,0,0,0,0,0,0,0,0,0,0,0,0,0,0,0,0,0,0,0,0,0,0,0,0,D~
N52,0,0,0,0,0,0,0,0,0)';$S;
    'VSS957':'(0,0,0,0,0,0,0,0,0,0,0,0,0,0,0,0,0,0,0,0,0,0,0,0,0,0,0,0,0,0,0,0,D~
N39,0,0,0,0,0,0,0,0,0)';$S;
    'VSS955':'(0,0,0,0,0,0,0,0,0,0,0,0,0,0,0,0,0,0,0,0,0,0,0,0,0,0,0,0,0,0,0,0,D~
N17,0,0,0,0,0,0,0,0,0)';$S;
    'VSS945':'(0,0,0,0,0,0,0,0,0,0,0,0,0,0,0,0,0,0,0,0,0,0,0,0,0,0,0,0,0,0,0,0,D~
M73,0,0,0,0,0,0,0,0,0)';$S;
    'VSS934':'(0,0,0,0,0,0,0,0,0,0,0,0,0,0,0,0,0,0,0,0,0,0,0,0,0,0,0,0,0,0,0,0,D~
M51,0,0,0,0,0,0,0,0,0)';$S;
    'VSS1099':'(0,0,0,0,0,0,0,0,0,0,0,0,0,0,0,0,0,0,0,0,0,0,0,0,0,0,0,0,0,0,0,0,~
0,DL9,0,0,0,0,0,0,0,0)';$S;
    'VSS1098':'(0,0,0,0,0,0,0,0,0,0,0,0,0,0,0,0,0,0,0,0,0,0,0,0,0,0,0,0,0,0,0,0,~
0,DL88,0,0,0,0,0,0,0,0)';$S;
    'VSS1096':'(0,0,0,0,0,0,0,0,0,0,0,0,0,0,0,0,0,0,0,0,0,0,0,0,0,0,0,0,0,0,0,0,~
0,DL84,0,0,0,0,0,0,0,0)';$S;
    'VSS1095':'(0,0,0,0,0,0,0,0,0,0,0,0,0,0,0,0,0,0,0,0,0,0,0,0,0,0,0,0,0,0,0,0,~
0,DL39,0,0,0,0,0,0,0,0)';$S;
    'VSS1094':'(0,0,0,0,0,0,0,0,0,0,0,0,0,0,0,0,0,0,0,0,0,0,0,0,0,0,0,0,0,0,0,0,~
0,DK91,0,0,0,0,0,0,0,0)';$S;
    'VSS1093':'(0,0,0,0,0,0,0,0,0,0,0,0,0,0,0,0,0,0,0,0,0,0,0,0,0,0,0,0,0,0,0,0,~
0,DK87,0,0,0,0,0,0,0,0)';$S;
    'VSS1092':'(0,0,0,0,0,0,0,0,0,0,0,0,0,0,0,0,0,0,0,0,0,0,0,0,0,0,0,0,0,0,0,0,~
0,DK83,0,0,0,0,0,0,0,0)';$S;
    'VSS1091':'(0,0,0,0,0,0,0,0,0,0,0,0,0,0,0,0,0,0,0,0,0,0,0,0,0,0,0,0,0,0,0,0,~
0,DK81,0,0,0,0,0,0,0,0)';$S;
    'VSS1090':'(0,0,0,0,0,0,0,0,0,0,0,0,0,0,0,0,0,0,0,0,0,0,0,0,0,0,0,0,0,0,0,0,~
0,DK8,0,0,0,0,0,0,0,0)';$S;
    'VSS1089':'(0,0,0,0,0,0,0,0,0,0,0,0,0,0,0,0,0,0,0,0,0,0,0,0,0,0,0,0,0,0,0,0,~
0,DK79,0,0,0,0,0,0,0,0)';$S;
    'VSS1088':'(0,0,0,0,0,0,0,0,0,0,0,0,0,0,0,0,0,0,0,0,0,0,0,0,0,0,0,0,0,0,0,0,~
0,DK77,0,0,0,0,0,0,0,0)';$S;
    'VSS1087':'(0,0,0,0,0,0,0,0,0,0,0,0,0,0,0,0,0,0,0,0,0,0,0,0,0,0,0,0,0,0,0,0,~
0,DK73,0,0,0,0,0,0,0,0)';$S;
    'VSS1086':'(0,0,0,0,0,0,0,0,0,0,0,0,0,0,0,0,0,0,0,0,0,0,0,0,0,0,0,0,0,0,0,0,~
0,DK49,0,0,0,0,0,0,0,0)';$S;
    'VSS1085':'(0,0,0,0,0,0,0,0,0,0,0,0,0,0,0,0,0,0,0,0,0,0,0,0,0,0,0,0,0,0,0,0,~
0,DK4,0,0,0,0,0,0,0,0)';$S;
    'VSS1084':'(0,0,0,0,0,0,0,0,0,0,0,0,0,0,0,0,0,0,0,0,0,0,0,0,0,0,0,0,0,0,0,0,~
0,DK36,0,0,0,0,0,0,0,0)';$S;
    'VSS1083':'(0,0,0,0,0,0,0,0,0,0,0,0,0,0,0,0,0,0,0,0,0,0,0,0,0,0,0,0,0,0,0,0,~
0,DK30,0,0,0,0,0,0,0,0)';$S;
    'VSS1082':'(0,0,0,0,0,0,0,0,0,0,0,0,0,0,0,0,0,0,0,0,0,0,0,0,0,0,0,0,0,0,0,0,~
0,DK16,0,0,0,0,0,0,0,0)';$S;
    'VSS1081':'(0,0,0,0,0,0,0,0,0,0,0,0,0,0,0,0,0,0,0,0,0,0,0,0,0,0,0,0,0,0,0,0,~
0,DJ88,0,0,0,0,0,0,0,0)';$S;
    'VSS1080':'(0,0,0,0,0,0,0,0,0,0,0,0,0,0,0,0,0,0,0,0,0,0,0,0,0,0,0,0,0,0,0,0,~
0,DJ84,0,0,0,0,0,0,0,0)';$S;
    'VSS1079':'(0,0,0,0,0,0,0,0,0,0,0,0,0,0,0,0,0,0,0,0,0,0,0,0,0,0,0,0,0,0,0,0,~
0,DJ82,0,0,0,0,0,0,0,0)';$S;
    'VSS1078':'(0,0,0,0,0,0,0,0,0,0,0,0,0,0,0,0,0,0,0,0,0,0,0,0,0,0,0,0,0,0,0,0,~
0,DJ80,0,0,0,0,0,0,0,0)';$S;
    'VSS1076':'(0,0,0,0,0,0,0,0,0,0,0,0,0,0,0,0,0,0,0,0,0,0,0,0,0,0,0,0,0,0,0,0,~
0,DJ74,0,0,0,0,0,0,0,0)';$S;
    'VSS1075':'(0,0,0,0,0,0,0,0,0,0,0,0,0,0,0,0,0,0,0,0,0,0,0,0,0,0,0,0,0,0,0,0,~
0,DJ72,0,0,0,0,0,0,0,0)';$S;
    'VSS1074':'(0,0,0,0,0,0,0,0,0,0,0,0,0,0,0,0,0,0,0,0,0,0,0,0,0,0,0,0,0,0,0,0,~
0,DJ66,0,0,0,0,0,0,0,0)';$S;
    'VSS1073':'(0,0,0,0,0,0,0,0,0,0,0,0,0,0,0,0,0,0,0,0,0,0,0,0,0,0,0,0,0,0,0,0,~
0,DJ60,0,0,0,0,0,0,0,0)';$S;
    'VSS1072':'(0,0,0,0,0,0,0,0,0,0,0,0,0,0,0,0,0,0,0,0,0,0,0,0,0,0,0,0,0,0,0,0,~
0,DJ56,0,0,0,0,0,0,0,0)';$S;
    'VSS1071':'(0,0,0,0,0,0,0,0,0,0,0,0,0,0,0,0,0,0,0,0,0,0,0,0,0,0,0,0,0,0,0,0,~
0,DJ50,0,0,0,0,0,0,0,0)';$S;
    'VSS1070':'(0,0,0,0,0,0,0,0,0,0,0,0,0,0,0,0,0,0,0,0,0,0,0,0,0,0,0,0,0,0,0,0,~
0,DJ48,0,0,0,0,0,0,0,0)';$S;
    'VSS1069':'(0,0,0,0,0,0,0,0,0,0,0,0,0,0,0,0,0,0,0,0,0,0,0,0,0,0,0,0,0,0,0,0,~
0,DJ43,0,0,0,0,0,0,0,0)';$S;
    'VSS1068':'(0,0,0,0,0,0,0,0,0,0,0,0,0,0,0,0,0,0,0,0,0,0,0,0,0,0,0,0,0,0,0,0,~
0,DJ41,0,0,0,0,0,0,0,0)';$S;
    'VSS1067':'(0,0,0,0,0,0,0,0,0,0,0,0,0,0,0,0,0,0,0,0,0,0,0,0,0,0,0,0,0,0,0,0,~
0,DJ37,0,0,0,0,0,0,0,0)';$S;
    'VSS1066':'(0,0,0,0,0,0,0,0,0,0,0,0,0,0,0,0,0,0,0,0,0,0,0,0,0,0,0,0,0,0,0,0,~
0,DJ31,0,0,0,0,0,0,0,0)';$S;
    'VSS1065':'(0,0,0,0,0,0,0,0,0,0,0,0,0,0,0,0,0,0,0,0,0,0,0,0,0,0,0,0,0,0,0,0,~
0,DJ29,0,0,0,0,0,0,0,0)';$S;
    'VSS1062':'(0,0,0,0,0,0,0,0,0,0,0,0,0,0,0,0,0,0,0,0,0,0,0,0,0,0,0,0,0,0,0,0,~
0,DJ23,0,0,0,0,0,0,0,0)';$S;
    'VSS1061':'(0,0,0,0,0,0,0,0,0,0,0,0,0,0,0,0,0,0,0,0,0,0,0,0,0,0,0,0,0,0,0,0,~
0,DJ19,0,0,0,0,0,0,0,0)';$S;
    'VSS1058':'(0,0,0,0,0,0,0,0,0,0,0,0,0,0,0,0,0,0,0,0,0,0,0,0,0,0,0,0,0,0,0,0,~
0,DH85,0,0,0,0,0,0,0,0)';$S;
    'VSS1057':'(0,0,0,0,0,0,0,0,0,0,0,0,0,0,0,0,0,0,0,0,0,0,0,0,0,0,0,0,0,0,0,0,~
0,DH8,0,0,0,0,0,0,0,0)';$S;
    'VSS1056':'(0,0,0,0,0,0,0,0,0,0,0,0,0,0,0,0,0,0,0,0,0,0,0,0,0,0,0,0,0,0,0,0,~
0,DH77,0,0,0,0,0,0,0,0)';$S;
    'VSS1055':'(0,0,0,0,0,0,0,0,0,0,0,0,0,0,0,0,0,0,0,0,0,0,0,0,0,0,0,0,0,0,0,0,~
0,DH71,0,0,0,0,0,0,0,0)';$S;
    'VSS1053':'(0,0,0,0,0,0,0,0,0,0,0,0,0,0,0,0,0,0,0,0,0,0,0,0,0,0,0,0,0,0,0,0,~
0,DH65,0,0,0,0,0,0,0,0)';$S;
    'VSS1049':'(0,0,0,0,0,0,0,0,0,0,0,0,0,0,0,0,0,0,0,0,0,0,0,0,0,0,0,0,0,0,0,0,~
0,DH57,0,0,0,0,0,0,0,0)';$S;
    'VSS1046':'(0,0,0,0,0,0,0,0,0,0,0,0,0,0,0,0,0,0,0,0,0,0,0,0,0,0,0,0,0,0,0,0,~
0,DH47,0,0,0,0,0,0,0,0)';$S;
    'VSS1045':'(0,0,0,0,0,0,0,0,0,0,0,0,0,0,0,0,0,0,0,0,0,0,0,0,0,0,0,0,0,0,0,0,~
0,DH40,0,0,0,0,0,0,0,0)';$S;
    'VSS1044':'(0,0,0,0,0,0,0,0,0,0,0,0,0,0,0,0,0,0,0,0,0,0,0,0,0,0,0,0,0,0,0,0,~
0,DH4,0,0,0,0,0,0,0,0)';$S;
    'VSS1043':'(0,0,0,0,0,0,0,0,0,0,0,0,0,0,0,0,0,0,0,0,0,0,0,0,0,0,0,0,0,0,0,0,~
0,DH38,0,0,0,0,0,0,0,0)';$S;
    'VSS1042':'(0,0,0,0,0,0,0,0,0,0,0,0,0,0,0,0,0,0,0,0,0,0,0,0,0,0,0,0,0,0,0,0,~
0,DH32,0,0,0,0,0,0,0,0)';$S;
    'VSS1041':'(0,0,0,0,0,0,0,0,0,0,0,0,0,0,0,0,0,0,0,0,0,0,0,0,0,0,0,0,0,0,0,0,~
0,DH28,0,0,0,0,0,0,0,0)';$S;
    'VSS1040':'(0,0,0,0,0,0,0,0,0,0,0,0,0,0,0,0,0,0,0,0,0,0,0,0,0,0,0,0,0,0,0,0,~
0,DH22,0,0,0,0,0,0,0,0)';$S;
    'VSS1039':'(0,0,0,0,0,0,0,0,0,0,0,0,0,0,0,0,0,0,0,0,0,0,0,0,0,0,0,0,0,0,0,0,~
0,DH12,0,0,0,0,0,0,0,0)';$S;
    'VSS1038':'(0,0,0,0,0,0,0,0,0,0,0,0,0,0,0,0,0,0,0,0,0,0,0,0,0,0,0,0,0,0,0,0,~
0,DG9,0,0,0,0,0,0,0,0)';$S;
    'VSS1037':'(0,0,0,0,0,0,0,0,0,0,0,0,0,0,0,0,0,0,0,0,0,0,0,0,0,0,0,0,0,0,0,0,~
0,DG88,0,0,0,0,0,0,0,0)';$S;
    'VSS1035':'(0,0,0,0,0,0,0,0,0,0,0,0,0,0,0,0,0,0,0,0,0,0,0,0,0,0,0,0,0,0,0,0,~
0,DG84,0,0,0,0,0,0,0,0)';$S;
    'VSS1034':'(0,0,0,0,0,0,0,0,0,0,0,0,0,0,0,0,0,0,0,0,0,0,0,0,0,0,0,0,0,0,0,0,~
0,DG80,0,0,0,0,0,0,0,0)';$S;
    'VSS1033':'(0,0,0,0,0,0,0,0,0,0,0,0,0,0,0,0,0,0,0,0,0,0,0,0,0,0,0,0,0,0,0,0,~
0,DG76,0,0,0,0,0,0,0,0)';$S;
    'VSS1032':'(0,0,0,0,0,0,0,0,0,0,0,0,0,0,0,0,0,0,0,0,0,0,0,0,0,0,0,0,0,0,0,0,~
0,DG70,0,0,0,0,0,0,0,0)';$S;
    'VSS1031':'(0,0,0,0,0,0,0,0,0,0,0,0,0,0,0,0,0,0,0,0,0,0,0,0,0,0,0,0,0,0,0,0,~
0,DG5,0,0,0,0,0,0,0,0)';$S;
    'VSS1030':'(0,0,0,0,0,0,0,0,0,0,0,0,0,0,0,0,0,0,0,0,0,0,0,0,0,0,0,0,0,0,0,0,~
0,DG45,0,0,0,0,0,0,0,0)';$S;
    'VSS1027':'(0,0,0,0,0,0,0,0,0,0,0,0,0,0,0,0,0,0,0,0,0,0,0,0,0,0,0,0,0,0,0,0,~
0,DG39,0,0,0,0,0,0,0,0)';$S;
    'VSS1024':'(0,0,0,0,0,0,0,0,0,0,0,0,0,0,0,0,0,0,0,0,0,0,0,0,0,0,0,0,0,0,0,0,~
0,DG33,0,0,0,0,0,0,0,0)';$S;
    'VSS1022':'(0,0,0,0,0,0,0,0,0,0,0,0,0,0,0,0,0,0,0,0,0,0,0,0,0,0,0,0,0,0,0,0,~
0,DG27,0,0,0,0,0,0,0,0)';$S;
    'VSS1020':'(0,0,0,0,0,0,0,0,0,0,0,0,0,0,0,0,0,0,0,0,0,0,0,0,0,0,0,0,0,0,0,0,~
0,DF87,0,0,0,0,0,0,0,0)';$S;
    'VSS1019':'(0,0,0,0,0,0,0,0,0,0,0,0,0,0,0,0,0,0,0,0,0,0,0,0,0,0,0,0,0,0,0,0,~
0,DF8,0,0,0,0,0,0,0,0)';$S;
    'VSS1018':'(0,0,0,0,0,0,0,0,0,0,0,0,0,0,0,0,0,0,0,0,0,0,0,0,0,0,0,0,0,0,0,0,~
0,DF79,0,0,0,0,0,0,0,0)';$S;
    'VSS1017':'(0,0,0,0,0,0,0,0,0,0,0,0,0,0,0,0,0,0,0,0,0,0,0,0,0,0,0,0,0,0,0,0,~
0,DF4,0,0,0,0,0,0,0,0)';$S;
    'VSS1015':'(0,0,0,0,0,0,0,0,0,0,0,0,0,0,0,0,0,0,0,0,0,0,0,0,0,0,0,0,0,0,0,0,~
0,DE88,0,0,0,0,0,0,0,0)';$S;
    'VSS1012':'(0,0,0,0,0,0,0,0,0,0,0,0,0,0,0,0,0,0,0,0,0,0,0,0,0,0,0,0,0,0,0,0,~
0,DE84,0,0,0,0,0,0,0,0)';$S;
    'VSS1011':'(0,0,0,0,0,0,0,0,0,0,0,0,0,0,0,0,0,0,0,0,0,0,0,0,0,0,0,0,0,0,0,0,~
0,DE82,0,0,0,0,0,0,0,0)';$S;
    'VSS1010':'(0,0,0,0,0,0,0,0,0,0,0,0,0,0,0,0,0,0,0,0,0,0,0,0,0,0,0,0,0,0,0,0,~
0,DE76,0,0,0,0,0,0,0,0)';$S;
    'VSS1009':'(0,0,0,0,0,0,0,0,0,0,0,0,0,0,0,0,0,0,0,0,0,0,0,0,0,0,0,0,0,0,0,0,~
0,DE74,0,0,0,0,0,0,0,0)';$S;
    'VSS1008':'(0,0,0,0,0,0,0,0,0,0,0,0,0,0,0,0,0,0,0,0,0,0,0,0,0,0,0,0,0,0,0,0,~
0,DE72,0,0,0,0,0,0,0,0)';$S;
    'VSS1007':'(0,0,0,0,0,0,0,0,0,0,0,0,0,0,0,0,0,0,0,0,0,0,0,0,0,0,0,0,0,0,0,0,~
0,DE68,0,0,0,0,0,0,0,0)';$S;
    'VSS1004':'(0,0,0,0,0,0,0,0,0,0,0,0,0,0,0,0,0,0,0,0,0,0,0,0,0,0,0,0,0,0,0,0,~
0,DE66,0,0,0,0,0,0,0,0)';$S;
    'VSS1001':'(0,0,0,0,0,0,0,0,0,0,0,0,0,0,0,0,0,0,0,0,0,0,0,0,0,0,0,0,0,0,0,0,~
0,DE64,0,0,0,0,0,0,0,0)';$S;
    'VSS999':'(0,0,0,0,0,0,0,0,0,0,0,0,0,0,0,0,0,0,0,0,0,0,0,0,0,0,0,0,0,0,0,0,0~
,DE62,0,0,0,0,0,0,0,0)';$S;
    'VSS997':'(0,0,0,0,0,0,0,0,0,0,0,0,0,0,0,0,0,0,0,0,0,0,0,0,0,0,0,0,0,0,0,0,0~
,DE60,0,0,0,0,0,0,0,0)';$S;
    'VSS996':'(0,0,0,0,0,0,0,0,0,0,0,0,0,0,0,0,0,0,0,0,0,0,0,0,0,0,0,0,0,0,0,0,0~
,DE58,0,0,0,0,0,0,0,0)';$S;
    'VSS995':'(0,0,0,0,0,0,0,0,0,0,0,0,0,0,0,0,0,0,0,0,0,0,0,0,0,0,0,0,0,0,0,0,0~
,DE56,0,0,0,0,0,0,0,0)';$S;
    'VSS994':'(0,0,0,0,0,0,0,0,0,0,0,0,0,0,0,0,0,0,0,0,0,0,0,0,0,0,0,0,0,0,0,0,0~
,DE54,0,0,0,0,0,0,0,0)';$S;
    'VSS992':'(0,0,0,0,0,0,0,0,0,0,0,0,0,0,0,0,0,0,0,0,0,0,0,0,0,0,0,0,0,0,0,0,0~
,DE52,0,0,0,0,0,0,0,0)';$S;
    'VSS991':'(0,0,0,0,0,0,0,0,0,0,0,0,0,0,0,0,0,0,0,0,0,0,0,0,0,0,0,0,0,0,0,0,0~
,DE50,0,0,0,0,0,0,0,0)';$S;
    'VSS989':'(0,0,0,0,0,0,0,0,0,0,0,0,0,0,0,0,0,0,0,0,0,0,0,0,0,0,0,0,0,0,0,0,0~
,DE48,0,0,0,0,0,0,0,0)';$S;
    'VSS988':'(0,0,0,0,0,0,0,0,0,0,0,0,0,0,0,0,0,0,0,0,0,0,0,0,0,0,0,0,0,0,0,0,0~
,DE45,0,0,0,0,0,0,0,0)';$S;
    'VSS987':'(0,0,0,0,0,0,0,0,0,0,0,0,0,0,0,0,0,0,0,0,0,0,0,0,0,0,0,0,0,0,0,0,0~
,DE43,0,0,0,0,0,0,0,0)';$S;
    'VSS986':'(0,0,0,0,0,0,0,0,0,0,0,0,0,0,0,0,0,0,0,0,0,0,0,0,0,0,0,0,0,0,0,0,0~
,DE41,0,0,0,0,0,0,0,0)';$S;
    'VSS984':'(0,0,0,0,0,0,0,0,0,0,0,0,0,0,0,0,0,0,0,0,0,0,0,0,0,0,0,0,0,0,0,0,0~
,DE37,0,0,0,0,0,0,0,0)';$S;
    'VSS983':'(0,0,0,0,0,0,0,0,0,0,0,0,0,0,0,0,0,0,0,0,0,0,0,0,0,0,0,0,0,0,0,0,0~
,DE35,0,0,0,0,0,0,0,0)';$S;
    'VSS982':'(0,0,0,0,0,0,0,0,0,0,0,0,0,0,0,0,0,0,0,0,0,0,0,0,0,0,0,0,0,0,0,0,0~
,DE33,0,0,0,0,0,0,0,0)';$S;
    'VSS981':'(0,0,0,0,0,0,0,0,0,0,0,0,0,0,0,0,0,0,0,0,0,0,0,0,0,0,0,0,0,0,0,0,0~
,DE31,0,0,0,0,0,0,0,0)';$S;
    'VSS978':'(0,0,0,0,0,0,0,0,0,0,0,0,0,0,0,0,0,0,0,0,0,0,0,0,0,0,0,0,0,0,0,0,0~
,DE29,0,0,0,0,0,0,0,0)';$S;
    'VSS977':'(0,0,0,0,0,0,0,0,0,0,0,0,0,0,0,0,0,0,0,0,0,0,0,0,0,0,0,0,0,0,0,0,0~
,DE27,0,0,0,0,0,0,0,0)';$S;
    'VSS975':'(0,0,0,0,0,0,0,0,0,0,0,0,0,0,0,0,0,0,0,0,0,0,0,0,0,0,0,0,0,0,0,0,0~
,DE25,0,0,0,0,0,0,0,0)';$S;
    'VSS974':'(0,0,0,0,0,0,0,0,0,0,0,0,0,0,0,0,0,0,0,0,0,0,0,0,0,0,0,0,0,0,0,0,0~
,DE23,0,0,0,0,0,0,0,0)';$S;
    'VSS972':'(0,0,0,0,0,0,0,0,0,0,0,0,0,0,0,0,0,0,0,0,0,0,0,0,0,0,0,0,0,0,0,0,0~
,DE21,0,0,0,0,0,0,0,0)';$S;
    'VSS971':'(0,0,0,0,0,0,0,0,0,0,0,0,0,0,0,0,0,0,0,0,0,0,0,0,0,0,0,0,0,0,0,0,0~
,DE19,0,0,0,0,0,0,0,0)';$S;
    'VSS970':'(0,0,0,0,0,0,0,0,0,0,0,0,0,0,0,0,0,0,0,0,0,0,0,0,0,0,0,0,0,0,0,0,0~
,DE17,0,0,0,0,0,0,0,0)';$S;
    'VSS967':'(0,0,0,0,0,0,0,0,0,0,0,0,0,0,0,0,0,0,0,0,0,0,0,0,0,0,0,0,0,0,0,0,0~
,DD8,0,0,0,0,0,0,0,0)';$S;
    'VSS965':'(0,0,0,0,0,0,0,0,0,0,0,0,0,0,0,0,0,0,0,0,0,0,0,0,0,0,0,0,0,0,0,0,0~
,DD79,0,0,0,0,0,0,0,0)';$S;
    'VSS964':'(0,0,0,0,0,0,0,0,0,0,0,0,0,0,0,0,0,0,0,0,0,0,0,0,0,0,0,0,0,0,0,0,0~
,DD4,0,0,0,0,0,0,0,0)';$S;
    'VSS963':'(0,0,0,0,0,0,0,0,0,0,0,0,0,0,0,0,0,0,0,0,0,0,0,0,0,0,0,0,0,0,0,0,0~
,DC9,0,0,0,0,0,0,0,0)';$S;
    'VSS962':'(0,0,0,0,0,0,0,0,0,0,0,0,0,0,0,0,0,0,0,0,0,0,0,0,0,0,0,0,0,0,0,0,0~
,DC88,0,0,0,0,0,0,0,0)';$S;
    'VSS961':'(0,0,0,0,0,0,0,0,0,0,0,0,0,0,0,0,0,0,0,0,0,0,0,0,0,0,0,0,0,0,0,0,0~
,DC84,0,0,0,0,0,0,0,0)';$S;
    'VSS960':'(0,0,0,0,0,0,0,0,0,0,0,0,0,0,0,0,0,0,0,0,0,0,0,0,0,0,0,0,0,0,0,0,0~
,DC80,0,0,0,0,0,0,0,0)';$S;
    'VSS958':'(0,0,0,0,0,0,0,0,0,0,0,0,0,0,0,0,0,0,0,0,0,0,0,0,0,0,0,0,0,0,0,0,0~
,DC78,0,0,0,0,0,0,0,0)';$S;
    'VSS956':'(0,0,0,0,0,0,0,0,0,0,0,0,0,0,0,0,0,0,0,0,0,0,0,0,0,0,0,0,0,0,0,0,0~
,DC76,0,0,0,0,0,0,0,0)';$S;
    'VSS954':'(0,0,0,0,0,0,0,0,0,0,0,0,0,0,0,0,0,0,0,0,0,0,0,0,0,0,0,0,0,0,0,0,0~
,DC70,0,0,0,0,0,0,0,0)';$S;
    'VSS953':'(0,0,0,0,0,0,0,0,0,0,0,0,0,0,0,0,0,0,0,0,0,0,0,0,0,0,0,0,0,0,0,0,0~
,DC5,0,0,0,0,0,0,0,0)';$S;
    'VSS952':'(0,0,0,0,0,0,0,0,0,0,0,0,0,0,0,0,0,0,0,0,0,0,0,0,0,0,0,0,0,0,0,0,0~
,DC45,0,0,0,0,0,0,0,0)';$S;
    'VSS951':'(0,0,0,0,0,0,0,0,0,0,0,0,0,0,0,0,0,0,0,0,0,0,0,0,0,0,0,0,0,0,0,0,0~
,DC39,0,0,0,0,0,0,0,0)';$S;
    'VSS950':'(0,0,0,0,0,0,0,0,0,0,0,0,0,0,0,0,0,0,0,0,0,0,0,0,0,0,0,0,0,0,0,0,0~
,DC33,0,0,0,0,0,0,0,0)';$S;
    'VSS949':'(0,0,0,0,0,0,0,0,0,0,0,0,0,0,0,0,0,0,0,0,0,0,0,0,0,0,0,0,0,0,0,0,0~
,DC27,0,0,0,0,0,0,0,0)';$S;
    'VSS909':'(0,0,0,0,0,0,0,0,0,0,0,0,0,0,0,0,0,0,0,0,0,0,0,0,0,0,0,0,0,0,0,0,0~
,DL52,0,0,0,0,0,0,0,0)';$S;
    'VSS908':'(0,0,0,0,0,0,0,0,0,0,0,0,0,0,0,0,0,0,0,0,0,0,0,0,0,0,0,0,0,0,0,0,0~
,DL5,0,0,0,0,0,0,0,0)';$S;
    'VSS905':'(0,0,0,0,0,0,0,0,0,0,0,0,0,0,0,0,0,0,0,0,0,0,0,0,0,0,0,0,0,0,0,0,0~
,DL17,0,0,0,0,0,0,0,0)';$S;
    'VSS904':'(0,0,0,0,0,0,0,0,0,0,0,0,0,0,0,0,0,0,0,0,0,0,0,0,0,0,0,0,0,0,0,0,0~
,DL13,0,0,0,0,0,0,0,0)';$S;
    'VSS903':'(0,0,0,0,0,0,0,0,0,0,0,0,0,0,0,0,0,0,0,0,0,0,0,0,0,0,0,0,0,0,0,0,0~
,DL1,0,0,0,0,0,0,0,0)';$S;
    'VSS894':'(0,0,0,0,0,0,0,0,0,0,0,0,0,0,0,0,0,0,0,0,0,0,0,0,0,0,0,0,0,0,0,0,0~
,DK67,0,0,0,0,0,0,0,0)';$S;
    'VSS893':'(0,0,0,0,0,0,0,0,0,0,0,0,0,0,0,0,0,0,0,0,0,0,0,0,0,0,0,0,0,0,0,0,0~
,DK61,0,0,0,0,0,0,0,0)';$S;
    'VSS890':'(0,0,0,0,0,0,0,0,0,0,0,0,0,0,0,0,0,0,0,0,0,0,0,0,0,0,0,0,0,0,0,0,0~
,DK55,0,0,0,0,0,0,0,0)';$S;
    'VSS887':'(0,0,0,0,0,0,0,0,0,0,0,0,0,0,0,0,0,0,0,0,0,0,0,0,0,0,0,0,0,0,0,0,0~
,DK42,0,0,0,0,0,0,0,0)';$S;
    'VSS883':'(0,0,0,0,0,0,0,0,0,0,0,0,0,0,0,0,0,0,0,0,0,0,0,0,0,0,0,0,0,0,0,0,0~
,DK24,0,0,0,0,0,0,0,0)';$S;
    'VSS882':'(0,0,0,0,0,0,0,0,0,0,0,0,0,0,0,0,0,0,0,0,0,0,0,0,0,0,0,0,0,0,0,0,0~
,DK18,0,0,0,0,0,0,0,0)';$S;
    'VSS880':'(0,0,0,0,0,0,0,0,0,0,0,0,0,0,0,0,0,0,0,0,0,0,0,0,0,0,0,0,0,0,0,0,0~
,DK12,0,0,0,0,0,0,0,0)';$S;
    'VSS872':'(0,0,0,0,0,0,0,0,0,0,0,0,0,0,0,0,0,0,0,0,0,0,0,0,0,0,0,0,0,0,0,0,0~
,DJ68,0,0,0,0,0,0,0,0)';$S;
    'VSS870':'(0,0,0,0,0,0,0,0,0,0,0,0,0,0,0,0,0,0,0,0,0,0,0,0,0,0,0,0,0,0,0,0,0~
,DJ62,0,0,0,0,0,0,0,0)';$S;
    'VSS867':'(0,0,0,0,0,0,0,0,0,0,0,0,0,0,0,0,0,0,0,0,0,0,0,0,0,0,0,0,0,0,0,0,0~
,DJ54,0,0,0,0,0,0,0,0)';$S;
    'VSS861':'(0,0,0,0,0,0,0,0,0,0,0,0,0,0,0,0,0,0,0,0,0,0,0,0,0,0,0,0,0,0,0,0,0~
,DJ35,0,0,0,0,0,0,0,0)';$S;
    'VSS857':'(0,0,0,0,0,0,0,0,0,0,0,0,0,0,0,0,0,0,0,0,0,0,0,0,0,0,0,0,0,0,0,0,0~
,DJ25,0,0,0,0,0,0,0,0)';$S;
    'VSS849':'(0,0,0,0,0,0,0,0,0,0,0,0,0,0,0,0,0,0,0,0,0,0,0,0,0,0,0,0,0,0,0,0,0~
,DH75,0,0,0,0,0,0,0,0)';$S;
    'VSS847':'(0,0,0,0,0,0,0,0,0,0,0,0,0,0,0,0,0,0,0,0,0,0,0,0,0,0,0,0,0,0,0,0,0~
,DH69,0,0,0,0,0,0,0,0)';$S;
    'VSS845':'(0,0,0,0,0,0,0,0,0,0,0,0,0,0,0,0,0,0,0,0,0,0,0,0,0,0,0,0,0,0,0,0,0~
,DH63,0,0,0,0,0,0,0,0)';$S;
    'VSS844':'(0,0,0,0,0,0,0,0,0,0,0,0,0,0,0,0,0,0,0,0,0,0,0,0,0,0,0,0,0,0,0,0,0~
,DH59,0,0,0,0,0,0,0,0)';$S;
    'VSS842':'(0,0,0,0,0,0,0,0,0,0,0,0,0,0,0,0,0,0,0,0,0,0,0,0,0,0,0,0,0,0,0,0,0~
,DH53,0,0,0,0,0,0,0,0)';$S;
    'VSS841':'(0,0,0,0,0,0,0,0,0,0,0,0,0,0,0,0,0,0,0,0,0,0,0,0,0,0,0,0,0,0,0,0,0~
,DH51,0,0,0,0,0,0,0,0)';$S;
    'VSS839':'(0,0,0,0,0,0,0,0,0,0,0,0,0,0,0,0,0,0,0,0,0,0,0,0,0,0,0,0,0,0,0,0,0~
,DH44,0,0,0,0,0,0,0,0)';$S;
    'VSS835':'(0,0,0,0,0,0,0,0,0,0,0,0,0,0,0,0,0,0,0,0,0,0,0,0,0,0,0,0,0,0,0,0,0~
,DH34,0,0,0,0,0,0,0,0)';$S;
    'VSS832':'(0,0,0,0,0,0,0,0,0,0,0,0,0,0,0,0,0,0,0,0,0,0,0,0,0,0,0,0,0,0,0,0,0~
,DH26,0,0,0,0,0,0,0,0)';$S;
    'VSS830':'(0,0,0,0,0,0,0,0,0,0,0,0,0,0,0,0,0,0,0,0,0,0,0,0,0,0,0,0,0,0,0,0,0~
,DH20,0,0,0,0,0,0,0,0)';$S;
    'VSS829':'(0,0,0,0,0,0,0,0,0,0,0,0,0,0,0,0,0,0,0,0,0,0,0,0,0,0,0,0,0,0,0,0,0~
,DH16,0,0,0,0,0,0,0,0)';$S;
    'VSS821':'(0,0,0,0,0,0,0,0,0,0,0,0,0,0,0,0,0,0,0,0,0,0,0,0,0,0,0,0,0,0,0,0,0~
,DG64,0,0,0,0,0,0,0,0)';$S;
    'VSS820':'(0,0,0,0,0,0,0,0,0,0,0,0,0,0,0,0,0,0,0,0,0,0,0,0,0,0,0,0,0,0,0,0,0~
,DG58,0,0,0,0,0,0,0,0)';$S;
    'VSS817':'(0,0,0,0,0,0,0,0,0,0,0,0,0,0,0,0,0,0,0,0,0,0,0,0,0,0,0,0,0,0,0,0,0~
,DG52,0,0,0,0,0,0,0,0)';$S;
    'VSS809':'(0,0,0,0,0,0,0,0,0,0,0,0,0,0,0,0,0,0,0,0,0,0,0,0,0,0,0,0,0,0,0,0,0~
,DG21,0,0,0,0,0,0,0,0)';$S;
    'VSS808':'(0,0,0,0,0,0,0,0,0,0,0,0,0,0,0,0,0,0,0,0,0,0,0,0,0,0,0,0,0,0,0,0,0~
,DG13,0,0,0,0,0,0,0,0)';$S;
    'VSS807':'(0,0,0,0,0,0,0,0,0,0,0,0,0,0,0,0,0,0,0,0,0,0,0,0,0,0,0,0,0,0,0,0,0~
,DG1,0,0,0,0,0,0,0,0)';$S;
    'VSS806':'(0,0,0,0,0,0,0,0,0,0,0,0,0,0,0,0,0,0,0,0,0,0,0,0,0,0,0,0,0,0,0,0,0~
,DF91,0,0,0,0,0,0,0,0)';$S;
    'VSS802':'(0,0,0,0,0,0,0,0,0,0,0,0,0,0,0,0,0,0,0,0,0,0,0,0,0,0,0,0,0,0,0,0,0~
,DF49,0,0,0,0,0,0,0,0)';$S;
    'VSS799':'(0,0,0,0,0,0,0,0,0,0,0,0,0,0,0,0,0,0,0,0,0,0,0,0,0,0,0,0,0,0,0,0,0~
,DF16,0,0,0,0,0,0,0,0)';$S;
    'VSS798':'(0,0,0,0,0,0,0,0,0,0,0,0,0,0,0,0,0,0,0,0,0,0,0,0,0,0,0,0,0,0,0,0,0~
,DF12,0,0,0,0,0,0,0,0)';$S;
    'VSS791':'(0,0,0,0,0,0,0,0,0,0,0,0,0,0,0,0,0,0,0,0,0,0,0,0,0,0,0,0,0,0,0,0,0~
,DE70,0,0,0,0,0,0,0,0)';$S;
    'VSS776':'(0,0,0,0,0,0,0,0,0,0,0,0,0,0,0,0,0,0,0,0,0,0,0,0,0,0,0,0,0,0,0,0,0~
,DE39,0,0,0,0,0,0,0,0)';$S;
    'VSS753':'(0,0,0,0,0,0,0,0,0,0,0,0,0,0,0,0,0,0,0,0,0,0,0,0,0,0,0,0,0,0,0,0,0~
,DD49,0,0,0,0,0,0,0,0)';$S;
    'VSS748':'(0,0,0,0,0,0,0,0,0,0,0,0,0,0,0,0,0,0,0,0,0,0,0,0,0,0,0,0,0,0,0,0,0~
,DD16,0,0,0,0,0,0,0,0)';$S;
    'VSS747':'(0,0,0,0,0,0,0,0,0,0,0,0,0,0,0,0,0,0,0,0,0,0,0,0,0,0,0,0,0,0,0,0,0~
,DD12,0,0,0,0,0,0,0,0)';$S;
    'VSS739':'(0,0,0,0,0,0,0,0,0,0,0,0,0,0,0,0,0,0,0,0,0,0,0,0,0,0,0,0,0,0,0,0,0~
,DC64,0,0,0,0,0,0,0,0)';$S;
    'VSS738':'(0,0,0,0,0,0,0,0,0,0,0,0,0,0,0,0,0,0,0,0,0,0,0,0,0,0,0,0,0,0,0,0,0~
,DC58,0,0,0,0,0,0,0,0)';$S;
    'VSS735':'(0,0,0,0,0,0,0,0,0,0,0,0,0,0,0,0,0,0,0,0,0,0,0,0,0,0,0,0,0,0,0,0,0~
,DC52,0,0,0,0,0,0,0,0)';$S;
    'VSS726':'(0,0,0,0,0,0,0,0,0,0,0,0,0,0,0,0,0,0,0,0,0,0,0,0,0,0,0,0,0,0,0,0,0~
,DC21,0,0,0,0,0,0,0,0)';$S;
    'VSS725':'(0,0,0,0,0,0,0,0,0,0,0,0,0,0,0,0,0,0,0,0,0,0,0,0,0,0,0,0,0,0,0,0,0~
,DC13,0,0,0,0,0,0,0,0)';$S;
    'VSS724':'(0,0,0,0,0,0,0,0,0,0,0,0,0,0,0,0,0,0,0,0,0,0,0,0,0,0,0,0,0,0,0,0,0~
,DC1,0,0,0,0,0,0,0,0)';$S;
    'VSS723':'(0,0,0,0,0,0,0,0,0,0,0,0,0,0,0,0,0,0,0,0,0,0,0,0,0,0,0,0,0,0,0,0,0~
,DB91,0,0,0,0,0,0,0,0)';$S;
    'VSS948':'(0,0,0,0,0,0,0,0,0,0,0,0,0,0,0,0,0,0,0,0,0,0,0,0,0,0,0,0,0,0,0,0,0~
,0,DB87,0,0,0,0,0,0,0)';$S;
    'VSS947':'(0,0,0,0,0,0,0,0,0,0,0,0,0,0,0,0,0,0,0,0,0,0,0,0,0,0,0,0,0,0,0,0,0~
,0,DB8,0,0,0,0,0,0,0)';$S;
    'VSS946':'(0,0,0,0,0,0,0,0,0,0,0,0,0,0,0,0,0,0,0,0,0,0,0,0,0,0,0,0,0,0,0,0,0~
,0,DB77,0,0,0,0,0,0,0)';$S;
    'VSS944':'(0,0,0,0,0,0,0,0,0,0,0,0,0,0,0,0,0,0,0,0,0,0,0,0,0,0,0,0,0,0,0,0,0~
,0,DB71,0,0,0,0,0,0,0)';$S;
    'VSS943':'(0,0,0,0,0,0,0,0,0,0,0,0,0,0,0,0,0,0,0,0,0,0,0,0,0,0,0,0,0,0,0,0,0~
,0,DB65,0,0,0,0,0,0,0)';$S;
    'VSS942':'(0,0,0,0,0,0,0,0,0,0,0,0,0,0,0,0,0,0,0,0,0,0,0,0,0,0,0,0,0,0,0,0,0~
,0,DB57,0,0,0,0,0,0,0)';$S;
    'VSS941':'(0,0,0,0,0,0,0,0,0,0,0,0,0,0,0,0,0,0,0,0,0,0,0,0,0,0,0,0,0,0,0,0,0~
,0,DB47,0,0,0,0,0,0,0)';$S;
    'VSS940':'(0,0,0,0,0,0,0,0,0,0,0,0,0,0,0,0,0,0,0,0,0,0,0,0,0,0,0,0,0,0,0,0,0~
,0,DB40,0,0,0,0,0,0,0)';$S;
    'VSS939':'(0,0,0,0,0,0,0,0,0,0,0,0,0,0,0,0,0,0,0,0,0,0,0,0,0,0,0,0,0,0,0,0,0~
,0,DB4,0,0,0,0,0,0,0)';$S;
    'VSS938':'(0,0,0,0,0,0,0,0,0,0,0,0,0,0,0,0,0,0,0,0,0,0,0,0,0,0,0,0,0,0,0,0,0~
,0,DB38,0,0,0,0,0,0,0)';$S;
    'VSS937':'(0,0,0,0,0,0,0,0,0,0,0,0,0,0,0,0,0,0,0,0,0,0,0,0,0,0,0,0,0,0,0,0,0~
,0,DB32,0,0,0,0,0,0,0)';$S;
    'VSS936':'(0,0,0,0,0,0,0,0,0,0,0,0,0,0,0,0,0,0,0,0,0,0,0,0,0,0,0,0,0,0,0,0,0~
,0,DB28,0,0,0,0,0,0,0)';$S;
    'VSS935':'(0,0,0,0,0,0,0,0,0,0,0,0,0,0,0,0,0,0,0,0,0,0,0,0,0,0,0,0,0,0,0,0,0~
,0,DB22,0,0,0,0,0,0,0)';$S;
    'VSS933':'(0,0,0,0,0,0,0,0,0,0,0,0,0,0,0,0,0,0,0,0,0,0,0,0,0,0,0,0,0,0,0,0,0~
,0,DB12,0,0,0,0,0,0,0)';$S;
    'VSS932':'(0,0,0,0,0,0,0,0,0,0,0,0,0,0,0,0,0,0,0,0,0,0,0,0,0,0,0,0,0,0,0,0,0~
,0,DA88,0,0,0,0,0,0,0)';$S;
    'VSS931':'(0,0,0,0,0,0,0,0,0,0,0,0,0,0,0,0,0,0,0,0,0,0,0,0,0,0,0,0,0,0,0,0,0~
,0,DA84,0,0,0,0,0,0,0)';$S;
    'VSS930':'(0,0,0,0,0,0,0,0,0,0,0,0,0,0,0,0,0,0,0,0,0,0,0,0,0,0,0,0,0,0,0,0,0~
,0,DA82,0,0,0,0,0,0,0)';$S;
    'VSS929':'(0,0,0,0,0,0,0,0,0,0,0,0,0,0,0,0,0,0,0,0,0,0,0,0,0,0,0,0,0,0,0,0,0~
,0,DA80,0,0,0,0,0,0,0)';$S;
    'VSS928':'(0,0,0,0,0,0,0,0,0,0,0,0,0,0,0,0,0,0,0,0,0,0,0,0,0,0,0,0,0,0,0,0,0~
,0,DA74,0,0,0,0,0,0,0)';$S;
    'VSS927':'(0,0,0,0,0,0,0,0,0,0,0,0,0,0,0,0,0,0,0,0,0,0,0,0,0,0,0,0,0,0,0,0,0~
,0,DA72,0,0,0,0,0,0,0)';$S;
    'VSS926':'(0,0,0,0,0,0,0,0,0,0,0,0,0,0,0,0,0,0,0,0,0,0,0,0,0,0,0,0,0,0,0,0,0~
,0,DA66,0,0,0,0,0,0,0)';$S;
    'VSS925':'(0,0,0,0,0,0,0,0,0,0,0,0,0,0,0,0,0,0,0,0,0,0,0,0,0,0,0,0,0,0,0,0,0~
,0,DA62,0,0,0,0,0,0,0)';$S;
    'VSS924':'(0,0,0,0,0,0,0,0,0,0,0,0,0,0,0,0,0,0,0,0,0,0,0,0,0,0,0,0,0,0,0,0,0~
,0,DA60,0,0,0,0,0,0,0)';$S;
    'VSS923':'(0,0,0,0,0,0,0,0,0,0,0,0,0,0,0,0,0,0,0,0,0,0,0,0,0,0,0,0,0,0,0,0,0~
,0,DA58,0,0,0,0,0,0,0)';$S;
    'VSS922':'(0,0,0,0,0,0,0,0,0,0,0,0,0,0,0,0,0,0,0,0,0,0,0,0,0,0,0,0,0,0,0,0,0~
,0,DA56,0,0,0,0,0,0,0)';$S;
    'VSS921':'(0,0,0,0,0,0,0,0,0,0,0,0,0,0,0,0,0,0,0,0,0,0,0,0,0,0,0,0,0,0,0,0,0~
,0,DA54,0,0,0,0,0,0,0)';$S;
    'VSS920':'(0,0,0,0,0,0,0,0,0,0,0,0,0,0,0,0,0,0,0,0,0,0,0,0,0,0,0,0,0,0,0,0,0~
,0,DA50,0,0,0,0,0,0,0)';$S;
    'VSS919':'(0,0,0,0,0,0,0,0,0,0,0,0,0,0,0,0,0,0,0,0,0,0,0,0,0,0,0,0,0,0,0,0,0~
,0,DA48,0,0,0,0,0,0,0)';$S;
    'VSS918':'(0,0,0,0,0,0,0,0,0,0,0,0,0,0,0,0,0,0,0,0,0,0,0,0,0,0,0,0,0,0,0,0,0~
,0,DA41,0,0,0,0,0,0,0)';$S;
    'VSS917':'(0,0,0,0,0,0,0,0,0,0,0,0,0,0,0,0,0,0,0,0,0,0,0,0,0,0,0,0,0,0,0,0,0~
,0,DA37,0,0,0,0,0,0,0)';$S;
    'VSS916':'(0,0,0,0,0,0,0,0,0,0,0,0,0,0,0,0,0,0,0,0,0,0,0,0,0,0,0,0,0,0,0,0,0~
,0,DA35,0,0,0,0,0,0,0)';$S;
    'VSS915':'(0,0,0,0,0,0,0,0,0,0,0,0,0,0,0,0,0,0,0,0,0,0,0,0,0,0,0,0,0,0,0,0,0~
,0,DA33,0,0,0,0,0,0,0)';$S;
    'VSS914':'(0,0,0,0,0,0,0,0,0,0,0,0,0,0,0,0,0,0,0,0,0,0,0,0,0,0,0,0,0,0,0,0,0~
,0,DA31,0,0,0,0,0,0,0)';$S;
    'VSS913':'(0,0,0,0,0,0,0,0,0,0,0,0,0,0,0,0,0,0,0,0,0,0,0,0,0,0,0,0,0,0,0,0,0~
,0,DA29,0,0,0,0,0,0,0)';$S;
    'VSS912':'(0,0,0,0,0,0,0,0,0,0,0,0,0,0,0,0,0,0,0,0,0,0,0,0,0,0,0,0,0,0,0,0,0~
,0,DA25,0,0,0,0,0,0,0)';$S;
    'VSS911':'(0,0,0,0,0,0,0,0,0,0,0,0,0,0,0,0,0,0,0,0,0,0,0,0,0,0,0,0,0,0,0,0,0~
,0,DA23,0,0,0,0,0,0,0)';$S;
    'VSS910':'(0,0,0,0,0,0,0,0,0,0,0,0,0,0,0,0,0,0,0,0,0,0,0,0,0,0,0,0,0,0,0,0,0~
,0,DA19,0,0,0,0,0,0,0)';$S;
    'VSS863':'(0,0,0,0,0,0,0,0,0,0,0,0,0,0,0,0,0,0,0,0,0,0,0,0,0,0,0,0,0,0,0,0,0~
,0,CY83,0,0,0,0,0,0,0)';$S;
    'VSS862':'(0,0,0,0,0,0,0,0,0,0,0,0,0,0,0,0,0,0,0,0,0,0,0,0,0,0,0,0,0,0,0,0,0~
,0,CY81,0,0,0,0,0,0,0)';$S;
    'VSS860':'(0,0,0,0,0,0,0,0,0,0,0,0,0,0,0,0,0,0,0,0,0,0,0,0,0,0,0,0,0,0,0,0,0~
,0,CY8,0,0,0,0,0,0,0)';$S;
    'VSS859':'(0,0,0,0,0,0,0,0,0,0,0,0,0,0,0,0,0,0,0,0,0,0,0,0,0,0,0,0,0,0,0,0,0~
,0,CY77,0,0,0,0,0,0,0)';$S;
    'VSS858':'(0,0,0,0,0,0,0,0,0,0,0,0,0,0,0,0,0,0,0,0,0,0,0,0,0,0,0,0,0,0,0,0,0~
,0,CY73,0,0,0,0,0,0,0)';$S;
    'VSS856':'(0,0,0,0,0,0,0,0,0,0,0,0,0,0,0,0,0,0,0,0,0,0,0,0,0,0,0,0,0,0,0,0,0~
,0,CY63,0,0,0,0,0,0,0)';$S;
    'VSS855':'(0,0,0,0,0,0,0,0,0,0,0,0,0,0,0,0,0,0,0,0,0,0,0,0,0,0,0,0,0,0,0,0,0~
,0,CY30,0,0,0,0,0,0,0)';$S;
    'VSS854':'(0,0,0,0,0,0,0,0,0,0,0,0,0,0,0,0,0,0,0,0,0,0,0,0,0,0,0,0,0,0,0,0,0~
,0,CY26,0,0,0,0,0,0,0)';$S;
    'VSS853':'(0,0,0,0,0,0,0,0,0,0,0,0,0,0,0,0,0,0,0,0,0,0,0,0,0,0,0,0,0,0,0,0,0~
,0,CY18,0,0,0,0,0,0,0)';$S;
    'VSS852':'(0,0,0,0,0,0,0,0,0,0,0,0,0,0,0,0,0,0,0,0,0,0,0,0,0,0,0,0,0,0,0,0,0~
,0,CY16,0,0,0,0,0,0,0)';$S;
    'VSS851':'(0,0,0,0,0,0,0,0,0,0,0,0,0,0,0,0,0,0,0,0,0,0,0,0,0,0,0,0,0,0,0,0,0~
,0,CY12,0,0,0,0,0,0,0)';$S;
    'VSS850':'(0,0,0,0,0,0,0,0,0,0,0,0,0,0,0,0,0,0,0,0,0,0,0,0,0,0,0,0,0,0,0,0,0~
,0,CW9,0,0,0,0,0,0,0)';$S;
    'VSS848':'(0,0,0,0,0,0,0,0,0,0,0,0,0,0,0,0,0,0,0,0,0,0,0,0,0,0,0,0,0,0,0,0,0~
,0,CW88,0,0,0,0,0,0,0)';$S;
    'VSS846':'(0,0,0,0,0,0,0,0,0,0,0,0,0,0,0,0,0,0,0,0,0,0,0,0,0,0,0,0,0,0,0,0,0~
,0,CW84,0,0,0,0,0,0,0)';$S;
    'VSS843':'(0,0,0,0,0,0,0,0,0,0,0,0,0,0,0,0,0,0,0,0,0,0,0,0,0,0,0,0,0,0,0,0,0~
,0,CW78,0,0,0,0,0,0,0)';$S;
    'VSS840':'(0,0,0,0,0,0,0,0,0,0,0,0,0,0,0,0,0,0,0,0,0,0,0,0,0,0,0,0,0,0,0,0,0~
,0,CW72,0,0,0,0,0,0,0)';$S;
    'VSS838':'(0,0,0,0,0,0,0,0,0,0,0,0,0,0,0,0,0,0,0,0,0,0,0,0,0,0,0,0,0,0,0,0,0~
,0,CW5,0,0,0,0,0,0,0)';$S;
    'VSS837':'(0,0,0,0,0,0,0,0,0,0,0,0,0,0,0,0,0,0,0,0,0,0,0,0,0,0,0,0,0,0,0,0,0~
,0,CW17,0,0,0,0,0,0,0)';$S;
    'VSS836':'(0,0,0,0,0,0,0,0,0,0,0,0,0,0,0,0,0,0,0,0,0,0,0,0,0,0,0,0,0,0,0,0,0~
,0,CW13,0,0,0,0,0,0,0)';$S;
    'VSS834':'(0,0,0,0,0,0,0,0,0,0,0,0,0,0,0,0,0,0,0,0,0,0,0,0,0,0,0,0,0,0,0,0,0~
,0,CW1,0,0,0,0,0,0,0)';$S;
    'VSS833':'(0,0,0,0,0,0,0,0,0,0,0,0,0,0,0,0,0,0,0,0,0,0,0,0,0,0,0,0,0,0,0,0,0~
,0,CV91,0,0,0,0,0,0,0)';$S;
    'VSS831':'(0,0,0,0,0,0,0,0,0,0,0,0,0,0,0,0,0,0,0,0,0,0,0,0,0,0,0,0,0,0,0,0,0~
,0,CV87,0,0,0,0,0,0,0)';$S;
    'VSS828':'(0,0,0,0,0,0,0,0,0,0,0,0,0,0,0,0,0,0,0,0,0,0,0,0,0,0,0,0,0,0,0,0,0~
,0,CV83,0,0,0,0,0,0,0)';$S;
    'VSS827':'(0,0,0,0,0,0,0,0,0,0,0,0,0,0,0,0,0,0,0,0,0,0,0,0,0,0,0,0,0,0,0,0,0~
,0,CV8,0,0,0,0,0,0,0)';$S;
    'VSS826':'(0,0,0,0,0,0,0,0,0,0,0,0,0,0,0,0,0,0,0,0,0,0,0,0,0,0,0,0,0,0,0,0,0~
,0,CV75,0,0,0,0,0,0,0)';$S;
    'VSS825':'(0,0,0,0,0,0,0,0,0,0,0,0,0,0,0,0,0,0,0,0,0,0,0,0,0,0,0,0,0,0,0,0,0~
,0,CV4,0,0,0,0,0,0,0)';$S;
    'VSS824':'(0,0,0,0,0,0,0,0,0,0,0,0,0,0,0,0,0,0,0,0,0,0,0,0,0,0,0,0,0,0,0,0,0~
,0,CV12,0,0,0,0,0,0,0)';$S;
    'VSS823':'(0,0,0,0,0,0,0,0,0,0,0,0,0,0,0,0,0,0,0,0,0,0,0,0,0,0,0,0,0,0,0,0,0~
,0,CU88,0,0,0,0,0,0,0)';$S;
    'VSS822':'(0,0,0,0,0,0,0,0,0,0,0,0,0,0,0,0,0,0,0,0,0,0,0,0,0,0,0,0,0,0,0,0,0~
,0,CU84,0,0,0,0,0,0,0)';$S;
    'VSS819':'(0,0,0,0,0,0,0,0,0,0,0,0,0,0,0,0,0,0,0,0,0,0,0,0,0,0,0,0,0,0,0,0,0~
,0,CU68,0,0,0,0,0,0,0)';$S;
    'VSS818':'(0,0,0,0,0,0,0,0,0,0,0,0,0,0,0,0,0,0,0,0,0,0,0,0,0,0,0,0,0,0,0,0,0~
,0,CU66,0,0,0,0,0,0,0)';$S;
    'VSS816':'(0,0,0,0,0,0,0,0,0,0,0,0,0,0,0,0,0,0,0,0,0,0,0,0,0,0,0,0,0,0,0,0,0~
,0,CU60,0,0,0,0,0,0,0)';$S;
    'VSS815':'(0,0,0,0,0,0,0,0,0,0,0,0,0,0,0,0,0,0,0,0,0,0,0,0,0,0,0,0,0,0,0,0,0~
,0,CU23,0,0,0,0,0,0,0)';$S;
    'VSS814':'(0,0,0,0,0,0,0,0,0,0,0,0,0,0,0,0,0,0,0,0,0,0,0,0,0,0,0,0,0,0,0,0,0~
,0,CU21,0,0,0,0,0,0,0)';$S;
    'VSS813':'(0,0,0,0,0,0,0,0,0,0,0,0,0,0,0,0,0,0,0,0,0,0,0,0,0,0,0,0,0,0,0,0,0~
,0,CU19,0,0,0,0,0,0,0)';$S;
    'VSS812':'(0,0,0,0,0,0,0,0,0,0,0,0,0,0,0,0,0,0,0,0,0,0,0,0,0,0,0,0,0,0,0,0,0~
,0,CT81,0,0,0,0,0,0,0)';$S;
    'VSS811':'(0,0,0,0,0,0,0,0,0,0,0,0,0,0,0,0,0,0,0,0,0,0,0,0,0,0,0,0,0,0,0,0,0~
,0,CT73,0,0,0,0,0,0,0)';$S;
    'VSS810':'(0,0,0,0,0,0,0,0,0,0,0,0,0,0,0,0,0,0,0,0,0,0,0,0,0,0,0,0,0,0,0,0,0~
,0,CT69,0,0,0,0,0,0,0)';$S;
    'VSS805':'(0,0,0,0,0,0,0,0,0,0,0,0,0,0,0,0,0,0,0,0,0,0,0,0,0,0,0,0,0,0,0,0,0~
,0,CT12,0,0,0,0,0,0,0)';$S;
    'VSS804':'(0,0,0,0,0,0,0,0,0,0,0,0,0,0,0,0,0,0,0,0,0,0,0,0,0,0,0,0,0,0,0,0,0~
,0,CT10,0,0,0,0,0,0,0)';$S;
    'VSS803':'(0,0,0,0,0,0,0,0,0,0,0,0,0,0,0,0,0,0,0,0,0,0,0,0,0,0,0,0,0,0,0,0,0~
,0,CR90,0,0,0,0,0,0,0)';$S;
    'VSS801':'(0,0,0,0,0,0,0,0,0,0,0,0,0,0,0,0,0,0,0,0,0,0,0,0,0,0,0,0,0,0,0,0,0~
,0,CR9,0,0,0,0,0,0,0)';$S;
    'VSS800':'(0,0,0,0,0,0,0,0,0,0,0,0,0,0,0,0,0,0,0,0,0,0,0,0,0,0,0,0,0,0,0,0,0~
,0,CR88,0,0,0,0,0,0,0)';$S;
    'VSS797':'(0,0,0,0,0,0,0,0,0,0,0,0,0,0,0,0,0,0,0,0,0,0,0,0,0,0,0,0,0,0,0,0,0~
,0,CR84,0,0,0,0,0,0,0)';$S;
    'VSS796':'(0,0,0,0,0,0,0,0,0,0,0,0,0,0,0,0,0,0,0,0,0,0,0,0,0,0,0,0,0,0,0,0,0~
,0,CR64,0,0,0,0,0,0,0)';$S;
    'VSS795':'(0,0,0,0,0,0,0,0,0,0,0,0,0,0,0,0,0,0,0,0,0,0,0,0,0,0,0,0,0,0,0,0,0~
,0,CR62,0,0,0,0,0,0,0)';$S;
    'VSS794':'(0,0,0,0,0,0,0,0,0,0,0,0,0,0,0,0,0,0,0,0,0,0,0,0,0,0,0,0,0,0,0,0,0~
,0,CR5,0,0,0,0,0,0,0)';$S;
    'VSS793':'(0,0,0,0,0,0,0,0,0,0,0,0,0,0,0,0,0,0,0,0,0,0,0,0,0,0,0,0,0,0,0,0,0~
,0,CR17,0,0,0,0,0,0,0)';$S;
    'VSS792':'(0,0,0,0,0,0,0,0,0,0,0,0,0,0,0,0,0,0,0,0,0,0,0,0,0,0,0,0,0,0,0,0,0~
,0,CR13,0,0,0,0,0,0,0)';$S;
    'VSS790':'(0,0,0,0,0,0,0,0,0,0,0,0,0,0,0,0,0,0,0,0,0,0,0,0,0,0,0,0,0,0,0,0,0~
,0,CR11,0,0,0,0,0,0,0)';$S;
    'VSS789':'(0,0,0,0,0,0,0,0,0,0,0,0,0,0,0,0,0,0,0,0,0,0,0,0,0,0,0,0,0,0,0,0,0~
,0,CR1,0,0,0,0,0,0,0)';$S;
    'VSS788':'(0,0,0,0,0,0,0,0,0,0,0,0,0,0,0,0,0,0,0,0,0,0,0,0,0,0,0,0,0,0,0,0,0~
,0,CP91,0,0,0,0,0,0,0)';$S;
    'VSS787':'(0,0,0,0,0,0,0,0,0,0,0,0,0,0,0,0,0,0,0,0,0,0,0,0,0,0,0,0,0,0,0,0,0~
,0,CP87,0,0,0,0,0,0,0)';$S;
    'VSS786':'(0,0,0,0,0,0,0,0,0,0,0,0,0,0,0,0,0,0,0,0,0,0,0,0,0,0,0,0,0,0,0,0,0~
,0,CP83,0,0,0,0,0,0,0)';$S;
    'VSS785':'(0,0,0,0,0,0,0,0,0,0,0,0,0,0,0,0,0,0,0,0,0,0,0,0,0,0,0,0,0,0,0,0,0~
,0,CP8,0,0,0,0,0,0,0)';$S;
    'VSS784':'(0,0,0,0,0,0,0,0,0,0,0,0,0,0,0,0,0,0,0,0,0,0,0,0,0,0,0,0,0,0,0,0,0~
,0,CP77,0,0,0,0,0,0,0)';$S;
    'VSS783':'(0,0,0,0,0,0,0,0,0,0,0,0,0,0,0,0,0,0,0,0,0,0,0,0,0,0,0,0,0,0,0,0,0~
,0,CP75,0,0,0,0,0,0,0)';$S;
    'VSS782':'(0,0,0,0,0,0,0,0,0,0,0,0,0,0,0,0,0,0,0,0,0,0,0,0,0,0,0,0,0,0,0,0,0~
,0,CP4,0,0,0,0,0,0,0)';$S;
    'VSS781':'(0,0,0,0,0,0,0,0,0,0,0,0,0,0,0,0,0,0,0,0,0,0,0,0,0,0,0,0,0,0,0,0,0~
,0,CP18,0,0,0,0,0,0,0)';$S;
    'VSS780':'(0,0,0,0,0,0,0,0,0,0,0,0,0,0,0,0,0,0,0,0,0,0,0,0,0,0,0,0,0,0,0,0,0~
,0,CP12,0,0,0,0,0,0,0)';$S;
    'VSS779':'(0,0,0,0,0,0,0,0,0,0,0,0,0,0,0,0,0,0,0,0,0,0,0,0,0,0,0,0,0,0,0,0,0~
,0,CN86,0,0,0,0,0,0,0)';$S;
    'VSS778':'(0,0,0,0,0,0,0,0,0,0,0,0,0,0,0,0,0,0,0,0,0,0,0,0,0,0,0,0,0,0,0,0,0~
,0,CN84,0,0,0,0,0,0,0)';$S;
    'VSS777':'(0,0,0,0,0,0,0,0,0,0,0,0,0,0,0,0,0,0,0,0,0,0,0,0,0,0,0,0,0,0,0,0,0~
,0,CN74,0,0,0,0,0,0,0)';$S;
    'VSS775':'(0,0,0,0,0,0,0,0,0,0,0,0,0,0,0,0,0,0,0,0,0,0,0,0,0,0,0,0,0,0,0,0,0~
,0,CN72,0,0,0,0,0,0,0)';$S;
    'VSS774':'(0,0,0,0,0,0,0,0,0,0,0,0,0,0,0,0,0,0,0,0,0,0,0,0,0,0,0,0,0,0,0,0,0~
,0,CN70,0,0,0,0,0,0,0)';$S;
    'VSS773':'(0,0,0,0,0,0,0,0,0,0,0,0,0,0,0,0,0,0,0,0,0,0,0,0,0,0,0,0,0,0,0,0,0~
,0,CN68,0,0,0,0,0,0,0)';$S;
    'VSS772':'(0,0,0,0,0,0,0,0,0,0,0,0,0,0,0,0,0,0,0,0,0,0,0,0,0,0,0,0,0,0,0,0,0~
,0,CM85,0,0,0,0,0,0,0)';$S;
    'VSS771':'(0,0,0,0,0,0,0,0,0,0,0,0,0,0,0,0,0,0,0,0,0,0,0,0,0,0,0,0,0,0,0,0,0~
,0,CM83,0,0,0,0,0,0,0)';$S;
    'VSS770':'(0,0,0,0,0,0,0,0,0,0,0,0,0,0,0,0,0,0,0,0,0,0,0,0,0,0,0,0,0,0,0,0,0~
,0,CM81,0,0,0,0,0,0,0)';$S;
    'VSS769':'(0,0,0,0,0,0,0,0,0,0,0,0,0,0,0,0,0,0,0,0,0,0,0,0,0,0,0,0,0,0,0,0,0~
,0,CM8,0,0,0,0,0,0,0)';$S;
    'VSS768':'(0,0,0,0,0,0,0,0,0,0,0,0,0,0,0,0,0,0,0,0,0,0,0,0,0,0,0,0,0,0,0,0,0~
,0,CM79,0,0,0,0,0,0,0)';$S;
    'VSS767':'(0,0,0,0,0,0,0,0,0,0,0,0,0,0,0,0,0,0,0,0,0,0,0,0,0,0,0,0,0,0,0,0,0~
,0,CM67,0,0,0,0,0,0,0)';$S;
    'VSS766':'(0,0,0,0,0,0,0,0,0,0,0,0,0,0,0,0,0,0,0,0,0,0,0,0,0,0,0,0,0,0,0,0,0~
,0,CM65,0,0,0,0,0,0,0)';$S;
    'VSS765':'(0,0,0,0,0,0,0,0,0,0,0,0,0,0,0,0,0,0,0,0,0,0,0,0,0,0,0,0,0,0,0,0,0~
,0,CM61,0,0,0,0,0,0,0)';$S;
    'VSS764':'(0,0,0,0,0,0,0,0,0,0,0,0,0,0,0,0,0,0,0,0,0,0,0,0,0,0,0,0,0,0,0,0,0~
,0,CM4,0,0,0,0,0,0,0)';$S;
    'VSS763':'(0,0,0,0,0,0,0,0,0,0,0,0,0,0,0,0,0,0,0,0,0,0,0,0,0,0,0,0,0,0,0,0,0~
,0,CM24,0,0,0,0,0,0,0)';$S;
    'VSS762':'(0,0,0,0,0,0,0,0,0,0,0,0,0,0,0,0,0,0,0,0,0,0,0,0,0,0,0,0,0,0,0,0,0~
,0,CM20,0,0,0,0,0,0,0)';$S;
    'VSS761':'(0,0,0,0,0,0,0,0,0,0,0,0,0,0,0,0,0,0,0,0,0,0,0,0,0,0,0,0,0,0,0,0,0~
,0,CM12,0,0,0,0,0,0,0)';$S;
    'VSS760':'(0,0,0,0,0,0,0,0,0,0,0,0,0,0,0,0,0,0,0,0,0,0,0,0,0,0,0,0,0,0,0,0,0~
,0,CL9,0,0,0,0,0,0,0)';$S;
    'VSS759':'(0,0,0,0,0,0,0,0,0,0,0,0,0,0,0,0,0,0,0,0,0,0,0,0,0,0,0,0,0,0,0,0,0~
,0,CL82,0,0,0,0,0,0,0)';$S;
    'VSS758':'(0,0,0,0,0,0,0,0,0,0,0,0,0,0,0,0,0,0,0,0,0,0,0,0,0,0,0,0,0,0,0,0,0~
,0,CL80,0,0,0,0,0,0,0)';$S;
    'VSS757':'(0,0,0,0,0,0,0,0,0,0,0,0,0,0,0,0,0,0,0,0,0,0,0,0,0,0,0,0,0,0,0,0,0~
,0,CL78,0,0,0,0,0,0,0)';$S;
    'VSS756':'(0,0,0,0,0,0,0,0,0,0,0,0,0,0,0,0,0,0,0,0,0,0,0,0,0,0,0,0,0,0,0,0,0~
,0,CL74,0,0,0,0,0,0,0)';$S;
    'VSS755':'(0,0,0,0,0,0,0,0,0,0,0,0,0,0,0,0,0,0,0,0,0,0,0,0,0,0,0,0,0,0,0,0,0~
,0,CL62,0,0,0,0,0,0,0)';$S;
    'VSS754':'(0,0,0,0,0,0,0,0,0,0,0,0,0,0,0,0,0,0,0,0,0,0,0,0,0,0,0,0,0,0,0,0,0~
,0,CL5,0,0,0,0,0,0,0)';$S;
    'VSS752':'(0,0,0,0,0,0,0,0,0,0,0,0,0,0,0,0,0,0,0,0,0,0,0,0,0,0,0,0,0,0,0,0,0~
,0,CL17,0,0,0,0,0,0,0)';$S;
    'VSS751':'(0,0,0,0,0,0,0,0,0,0,0,0,0,0,0,0,0,0,0,0,0,0,0,0,0,0,0,0,0,0,0,0,0~
,0,CL13,0,0,0,0,0,0,0)';$S;
    'VSS750':'(0,0,0,0,0,0,0,0,0,0,0,0,0,0,0,0,0,0,0,0,0,0,0,0,0,0,0,0,0,0,0,0,0~
,0,CL1,0,0,0,0,0,0,0)';$S;
    'VSS749':'(0,0,0,0,0,0,0,0,0,0,0,0,0,0,0,0,0,0,0,0,0,0,0,0,0,0,0,0,0,0,0,0,0~
,0,CK81,0,0,0,0,0,0,0)';$S;
    'VSS745':'(0,0,0,0,0,0,0,0,0,0,0,0,0,0,0,0,0,0,0,0,0,0,0,0,0,0,0,0,0,0,0,0,0~
,0,CK69,0,0,0,0,0,0,0)';$S;
    'VSS744':'(0,0,0,0,0,0,0,0,0,0,0,0,0,0,0,0,0,0,0,0,0,0,0,0,0,0,0,0,0,0,0,0,0~
,0,CK63,0,0,0,0,0,0,0)';$S;
    'VSS719':'(0,0,0,0,0,0,0,0,0,0,0,0,0,0,0,0,0,0,0,0,0,0,0,0,0,0,0,0,0,0,0,0,0~
,0,DB75,0,0,0,0,0,0,0)';$S;
    'VSS717':'(0,0,0,0,0,0,0,0,0,0,0,0,0,0,0,0,0,0,0,0,0,0,0,0,0,0,0,0,0,0,0,0,0~
,0,DB69,0,0,0,0,0,0,0)';$S;
    'VSS715':'(0,0,0,0,0,0,0,0,0,0,0,0,0,0,0,0,0,0,0,0,0,0,0,0,0,0,0,0,0,0,0,0,0~
,0,DB63,0,0,0,0,0,0,0)';$S;
    'VSS714':'(0,0,0,0,0,0,0,0,0,0,0,0,0,0,0,0,0,0,0,0,0,0,0,0,0,0,0,0,0,0,0,0,0~
,0,DB59,0,0,0,0,0,0,0)';$S;
    'VSS712':'(0,0,0,0,0,0,0,0,0,0,0,0,0,0,0,0,0,0,0,0,0,0,0,0,0,0,0,0,0,0,0,0,0~
,0,DB53,0,0,0,0,0,0,0)';$S;
    'VSS711':'(0,0,0,0,0,0,0,0,0,0,0,0,0,0,0,0,0,0,0,0,0,0,0,0,0,0,0,0,0,0,0,0,0~
,0,DB51,0,0,0,0,0,0,0)';$S;
    'VSS709':'(0,0,0,0,0,0,0,0,0,0,0,0,0,0,0,0,0,0,0,0,0,0,0,0,0,0,0,0,0,0,0,0,0~
,0,DB44,0,0,0,0,0,0,0)';$S;
    'VSS705':'(0,0,0,0,0,0,0,0,0,0,0,0,0,0,0,0,0,0,0,0,0,0,0,0,0,0,0,0,0,0,0,0,0~
,0,DB34,0,0,0,0,0,0,0)';$S;
    'VSS702':'(0,0,0,0,0,0,0,0,0,0,0,0,0,0,0,0,0,0,0,0,0,0,0,0,0,0,0,0,0,0,0,0,0~
,0,DB26,0,0,0,0,0,0,0)';$S;
    'VSS700':'(0,0,0,0,0,0,0,0,0,0,0,0,0,0,0,0,0,0,0,0,0,0,0,0,0,0,0,0,0,0,0,0,0~
,0,DB20,0,0,0,0,0,0,0)';$S;
    'VSS699':'(0,0,0,0,0,0,0,0,0,0,0,0,0,0,0,0,0,0,0,0,0,0,0,0,0,0,0,0,0,0,0,0,0~
,0,DB16,0,0,0,0,0,0,0)';$S;
    'VSS690':'(0,0,0,0,0,0,0,0,0,0,0,0,0,0,0,0,0,0,0,0,0,0,0,0,0,0,0,0,0,0,0,0,0~
,0,DA68,0,0,0,0,0,0,0)';$S;
    'VSS679':'(0,0,0,0,0,0,0,0,0,0,0,0,0,0,0,0,0,0,0,0,0,0,0,0,0,0,0,0,0,0,0,0,0~
,0,DA43,0,0,0,0,0,0,0)';$S;
    'VSS611':'(0,0,0,0,0,0,0,0,0,0,0,0,0,0,0,0,0,0,0,0,0,0,0,0,0,0,0,0,0,0,0,0,0~
,0,CY4,0,0,0,0,0,0,0)';$S;
    'VSS595':'(0,0,0,0,0,0,0,0,0,0,0,0,0,0,0,0,0,0,0,0,0,0,0,0,0,0,0,0,0,0,0,0,0~
,0,CW70,0,0,0,0,0,0,0)';$S;
    'VSS583':'(0,0,0,0,0,0,0,0,0,0,0,0,0,0,0,0,0,0,0,0,0,0,0,0,0,0,0,0,0,0,0,0,0~
,0,CW33,0,0,0,0,0,0,0)';$S;
    'VSS571':'(0,0,0,0,0,0,0,0,0,0,0,0,0,0,0,0,0,0,0,0,0,0,0,0,0,0,0,0,0,0,0,0,0~
,0,CV79,0,0,0,0,0,0,0)';$S;
    'VSS562':'(0,0,0,0,0,0,0,0,0,0,0,0,0,0,0,0,0,0,0,0,0,0,0,0,0,0,0,0,0,0,0,0,0~
,0,CV26,0,0,0,0,0,0,0)';$S;
    'VSS558':'(0,0,0,0,0,0,0,0,0,0,0,0,0,0,0,0,0,0,0,0,0,0,0,0,0,0,0,0,0,0,0,0,0~
,0,CV16,0,0,0,0,0,0,0)';$S;
    'VSS554':'(0,0,0,0,0,0,0,0,0,0,0,0,0,0,0,0,0,0,0,0,0,0,0,0,0,0,0,0,0,0,0,0,0~
,0,CU78,0,0,0,0,0,0,0)';$S;
    'VSS553':'(0,0,0,0,0,0,0,0,0,0,0,0,0,0,0,0,0,0,0,0,0,0,0,0,0,0,0,0,0,0,0,0,0~
,0,CU72,0,0,0,0,0,0,0)';$S;
    'VSS544':'(0,0,0,0,0,0,0,0,0,0,0,0,0,0,0,0,0,0,0,0,0,0,0,0,0,0,0,0,0,0,0,0,0~
,0,CU25,0,0,0,0,0,0,0)';$S;
    'VSS537':'(0,0,0,0,0,0,0,0,0,0,0,0,0,0,0,0,0,0,0,0,0,0,0,0,0,0,0,0,0,0,0,0,0~
,0,CT89,0,0,0,0,0,0,0)';$S;
    'VSS534':'(0,0,0,0,0,0,0,0,0,0,0,0,0,0,0,0,0,0,0,0,0,0,0,0,0,0,0,0,0,0,0,0,0~
,0,CT8,0,0,0,0,0,0,0)';$S;
    'VSS526':'(0,0,0,0,0,0,0,0,0,0,0,0,0,0,0,0,0,0,0,0,0,0,0,0,0,0,0,0,0,0,0,0,0~
,0,CT4,0,0,0,0,0,0,0)';$S;
    'VSS521':'(0,0,0,0,0,0,0,0,0,0,0,0,0,0,0,0,0,0,0,0,0,0,0,0,0,0,0,0,0,0,0,0,0~
,0,CT16,0,0,0,0,0,0,0)';$S;
    'VSS514':'(0,0,0,0,0,0,0,0,0,0,0,0,0,0,0,0,0,0,0,0,0,0,0,0,0,0,0,0,0,0,0,0,0~
,0,CR78,0,0,0,0,0,0,0)';$S;
    'VSS493':'(0,0,0,0,0,0,0,0,0,0,0,0,0,0,0,0,0,0,0,0,0,0,0,0,0,0,0,0,0,0,0,0,0~
,0,CP79,0,0,0,0,0,0,0)';$S;
    'VSS478':'(0,0,0,0,0,0,0,0,0,0,0,0,0,0,0,0,0,0,0,0,0,0,0,0,0,0,0,0,0,0,0,0,0~
,0,CP16,0,0,0,0,0,0,0)';$S;
    'VSS471':'(0,0,0,0,0,0,0,0,0,0,0,0,0,0,0,0,0,0,0,0,0,0,0,0,0,0,0,0,0,0,0,0,0~
,0,CN76,0,0,0,0,0,0,0)';$S;
    'VSS438':'(0,0,0,0,0,0,0,0,0,0,0,0,0,0,0,0,0,0,0,0,0,0,0,0,0,0,0,0,0,0,0,0,0~
,0,CM22,0,0,0,0,0,0,0)';$S;
    'VSS436':'(0,0,0,0,0,0,0,0,0,0,0,0,0,0,0,0,0,0,0,0,0,0,0,0,0,0,0,0,0,0,0,0,0~
,0,CM16,0,0,0,0,0,0,0)';$S;
    'VSS746':'(0,0,0,0,0,0,0,0,0,0,0,0,0,0,0,0,0,0,0,0,0,0,0,0,0,0,0,0,0,0,0,0,0~
,0,0,CK8,0,0,0,0,0,0)';$S;
    'VSS743':'(0,0,0,0,0,0,0,0,0,0,0,0,0,0,0,0,0,0,0,0,0,0,0,0,0,0,0,0,0,0,0,0,0~
,0,0,CK26,0,0,0,0,0,0)';$S;
    'VSS742':'(0,0,0,0,0,0,0,0,0,0,0,0,0,0,0,0,0,0,0,0,0,0,0,0,0,0,0,0,0,0,0,0,0~
,0,0,CK20,0,0,0,0,0,0)';$S;
    'VSS741':'(0,0,0,0,0,0,0,0,0,0,0,0,0,0,0,0,0,0,0,0,0,0,0,0,0,0,0,0,0,0,0,0,0~
,0,0,CK16,0,0,0,0,0,0)';$S;
    'VSS740':'(0,0,0,0,0,0,0,0,0,0,0,0,0,0,0,0,0,0,0,0,0,0,0,0,0,0,0,0,0,0,0,0,0~
,0,0,CK12,0,0,0,0,0,0)';$S;
    'VSS737':'(0,0,0,0,0,0,0,0,0,0,0,0,0,0,0,0,0,0,0,0,0,0,0,0,0,0,0,0,0,0,0,0,0~
,0,0,CJ80,0,0,0,0,0,0)';$S;
    'VSS736':'(0,0,0,0,0,0,0,0,0,0,0,0,0,0,0,0,0,0,0,0,0,0,0,0,0,0,0,0,0,0,0,0,0~
,0,0,CJ60,0,0,0,0,0,0)';$S;
    'VSS734':'(0,0,0,0,0,0,0,0,0,0,0,0,0,0,0,0,0,0,0,0,0,0,0,0,0,0,0,0,0,0,0,0,0~
,0,0,CH89,0,0,0,0,0,0)';$S;
    'VSS733':'(0,0,0,0,0,0,0,0,0,0,0,0,0,0,0,0,0,0,0,0,0,0,0,0,0,0,0,0,0,0,0,0,0~
,0,0,CH87,0,0,0,0,0,0)';$S;
    'VSS732':'(0,0,0,0,0,0,0,0,0,0,0,0,0,0,0,0,0,0,0,0,0,0,0,0,0,0,0,0,0,0,0,0,0~
,0,0,CH85,0,0,0,0,0,0)';$S;
    'VSS731':'(0,0,0,0,0,0,0,0,0,0,0,0,0,0,0,0,0,0,0,0,0,0,0,0,0,0,0,0,0,0,0,0,0~
,0,0,CH83,0,0,0,0,0,0)';$S;
    'VSS730':'(0,0,0,0,0,0,0,0,0,0,0,0,0,0,0,0,0,0,0,0,0,0,0,0,0,0,0,0,0,0,0,0,0~
,0,0,CH8,0,0,0,0,0,0)';$S;
    'VSS729':'(0,0,0,0,0,0,0,0,0,0,0,0,0,0,0,0,0,0,0,0,0,0,0,0,0,0,0,0,0,0,0,0,0~
,0,0,CH79,0,0,0,0,0,0)';$S;
    'VSS728':'(0,0,0,0,0,0,0,0,0,0,0,0,0,0,0,0,0,0,0,0,0,0,0,0,0,0,0,0,0,0,0,0,0~
,0,0,CH73,0,0,0,0,0,0)';$S;
    'VSS727':'(0,0,0,0,0,0,0,0,0,0,0,0,0,0,0,0,0,0,0,0,0,0,0,0,0,0,0,0,0,0,0,0,0~
,0,0,CH67,0,0,0,0,0,0)';$S;
    'VSS722':'(0,0,0,0,0,0,0,0,0,0,0,0,0,0,0,0,0,0,0,0,0,0,0,0,0,0,0,0,0,0,0,0,0~
,0,0,CH4,0,0,0,0,0,0)';$S;
    'VSS721':'(0,0,0,0,0,0,0,0,0,0,0,0,0,0,0,0,0,0,0,0,0,0,0,0,0,0,0,0,0,0,0,0,0~
,0,0,CH20,0,0,0,0,0,0)';$S;
    'VSS720':'(0,0,0,0,0,0,0,0,0,0,0,0,0,0,0,0,0,0,0,0,0,0,0,0,0,0,0,0,0,0,0,0,0~
,0,0,CH16,0,0,0,0,0,0)';$S;
    'VSS718':'(0,0,0,0,0,0,0,0,0,0,0,0,0,0,0,0,0,0,0,0,0,0,0,0,0,0,0,0,0,0,0,0,0~
,0,0,CH12,0,0,0,0,0,0)';$S;
    'VSS716':'(0,0,0,0,0,0,0,0,0,0,0,0,0,0,0,0,0,0,0,0,0,0,0,0,0,0,0,0,0,0,0,0,0~
,0,0,CG9,0,0,0,0,0,0)';$S;
    'VSS713':'(0,0,0,0,0,0,0,0,0,0,0,0,0,0,0,0,0,0,0,0,0,0,0,0,0,0,0,0,0,0,0,0,0~
,0,0,CG78,0,0,0,0,0,0)';$S;
    'VSS710':'(0,0,0,0,0,0,0,0,0,0,0,0,0,0,0,0,0,0,0,0,0,0,0,0,0,0,0,0,0,0,0,0,0~
,0,0,CG74,0,0,0,0,0,0)';$S;
    'VSS708':'(0,0,0,0,0,0,0,0,0,0,0,0,0,0,0,0,0,0,0,0,0,0,0,0,0,0,0,0,0,0,0,0,0~
,0,0,CG72,0,0,0,0,0,0)';$S;
    'VSS707':'(0,0,0,0,0,0,0,0,0,0,0,0,0,0,0,0,0,0,0,0,0,0,0,0,0,0,0,0,0,0,0,0,0~
,0,0,CG70,0,0,0,0,0,0)';$S;
    'VSS706':'(0,0,0,0,0,0,0,0,0,0,0,0,0,0,0,0,0,0,0,0,0,0,0,0,0,0,0,0,0,0,0,0,0~
,0,0,CG64,0,0,0,0,0,0)';$S;
    'VSS704':'(0,0,0,0,0,0,0,0,0,0,0,0,0,0,0,0,0,0,0,0,0,0,0,0,0,0,0,0,0,0,0,0,0~
,0,0,CG62,0,0,0,0,0,0)';$S;
    'VSS703':'(0,0,0,0,0,0,0,0,0,0,0,0,0,0,0,0,0,0,0,0,0,0,0,0,0,0,0,0,0,0,0,0,0~
,0,0,CG5,0,0,0,0,0,0)';$S;
    'VSS701':'(0,0,0,0,0,0,0,0,0,0,0,0,0,0,0,0,0,0,0,0,0,0,0,0,0,0,0,0,0,0,0,0,0~
,0,0,CG25,0,0,0,0,0,0)';$S;
    'VSS698':'(0,0,0,0,0,0,0,0,0,0,0,0,0,0,0,0,0,0,0,0,0,0,0,0,0,0,0,0,0,0,0,0,0~
,0,0,CG23,0,0,0,0,0,0)';$S;
    'VSS697':'(0,0,0,0,0,0,0,0,0,0,0,0,0,0,0,0,0,0,0,0,0,0,0,0,0,0,0,0,0,0,0,0,0~
,0,0,CG21,0,0,0,0,0,0)';$S;
    'VSS696':'(0,0,0,0,0,0,0,0,0,0,0,0,0,0,0,0,0,0,0,0,0,0,0,0,0,0,0,0,0,0,0,0,0~
,0,0,CG17,0,0,0,0,0,0)';$S;
    'VSS695':'(0,0,0,0,0,0,0,0,0,0,0,0,0,0,0,0,0,0,0,0,0,0,0,0,0,0,0,0,0,0,0,0,0~
,0,0,CG13,0,0,0,0,0,0)';$S;
    'VSS694':'(0,0,0,0,0,0,0,0,0,0,0,0,0,0,0,0,0,0,0,0,0,0,0,0,0,0,0,0,0,0,0,0,0~
,0,0,CG1,0,0,0,0,0,0)';$S;
    'VSS693':'(0,0,0,0,0,0,0,0,0,0,0,0,0,0,0,0,0,0,0,0,0,0,0,0,0,0,0,0,0,0,0,0,0~
,0,0,CF8,0,0,0,0,0,0)';$S;
    'VSS692':'(0,0,0,0,0,0,0,0,0,0,0,0,0,0,0,0,0,0,0,0,0,0,0,0,0,0,0,0,0,0,0,0,0~
,0,0,CF71,0,0,0,0,0,0)';$S;
    'VSS691':'(0,0,0,0,0,0,0,0,0,0,0,0,0,0,0,0,0,0,0,0,0,0,0,0,0,0,0,0,0,0,0,0,0~
,0,0,CF69,0,0,0,0,0,0)';$S;
    'VSS689':'(0,0,0,0,0,0,0,0,0,0,0,0,0,0,0,0,0,0,0,0,0,0,0,0,0,0,0,0,0,0,0,0,0~
,0,0,CF4,0,0,0,0,0,0)';$S;
    'VSS688':'(0,0,0,0,0,0,0,0,0,0,0,0,0,0,0,0,0,0,0,0,0,0,0,0,0,0,0,0,0,0,0,0,0~
,0,0,CF20,0,0,0,0,0,0)';$S;
    'VSS687':'(0,0,0,0,0,0,0,0,0,0,0,0,0,0,0,0,0,0,0,0,0,0,0,0,0,0,0,0,0,0,0,0,0~
,0,0,CF16,0,0,0,0,0,0)';$S;
    'VSS686':'(0,0,0,0,0,0,0,0,0,0,0,0,0,0,0,0,0,0,0,0,0,0,0,0,0,0,0,0,0,0,0,0,0~
,0,0,CF12,0,0,0,0,0,0)';$S;
    'VSS685':'(0,0,0,0,0,0,0,0,0,0,0,0,0,0,0,0,0,0,0,0,0,0,0,0,0,0,0,0,0,0,0,0,0~
,0,0,CE78,0,0,0,0,0,0)';$S;
    'VSS684':'(0,0,0,0,0,0,0,0,0,0,0,0,0,0,0,0,0,0,0,0,0,0,0,0,0,0,0,0,0,0,0,0,0~
,0,0,CE76,0,0,0,0,0,0)';$S;
    'VSS683':'(0,0,0,0,0,0,0,0,0,0,0,0,0,0,0,0,0,0,0,0,0,0,0,0,0,0,0,0,0,0,0,0,0~
,0,0,CE72,0,0,0,0,0,0)';$S;
    'VSS682':'(0,0,0,0,0,0,0,0,0,0,0,0,0,0,0,0,0,0,0,0,0,0,0,0,0,0,0,0,0,0,0,0,0~
,0,0,CE66,0,0,0,0,0,0)';$S;
    'VSS681':'(0,0,0,0,0,0,0,0,0,0,0,0,0,0,0,0,0,0,0,0,0,0,0,0,0,0,0,0,0,0,0,0,0~
,0,0,CE60,0,0,0,0,0,0)';$S;
    'VSS680':'(0,0,0,0,0,0,0,0,0,0,0,0,0,0,0,0,0,0,0,0,0,0,0,0,0,0,0,0,0,0,0,0,0~
,0,0,CE3,0,0,0,0,0,0)';$S;
    'VSS678':'(0,0,0,0,0,0,0,0,0,0,0,0,0,0,0,0,0,0,0,0,0,0,0,0,0,0,0,0,0,0,0,0,0~
,0,0,CD8,0,0,0,0,0,0)';$S;
    'VSS677':'(0,0,0,0,0,0,0,0,0,0,0,0,0,0,0,0,0,0,0,0,0,0,0,0,0,0,0,0,0,0,0,0,0~
,0,0,CD77,0,0,0,0,0,0)';$S;
    'VSS676':'(0,0,0,0,0,0,0,0,0,0,0,0,0,0,0,0,0,0,0,0,0,0,0,0,0,0,0,0,0,0,0,0,0~
,0,0,CD75,0,0,0,0,0,0)';$S;
    'VSS675':'(0,0,0,0,0,0,0,0,0,0,0,0,0,0,0,0,0,0,0,0,0,0,0,0,0,0,0,0,0,0,0,0,0~
,0,0,CD61,0,0,0,0,0,0)';$S;
    'VSS674':'(0,0,0,0,0,0,0,0,0,0,0,0,0,0,0,0,0,0,0,0,0,0,0,0,0,0,0,0,0,0,0,0,0~
,0,0,CD4,0,0,0,0,0,0)';$S;
    'VSS673':'(0,0,0,0,0,0,0,0,0,0,0,0,0,0,0,0,0,0,0,0,0,0,0,0,0,0,0,0,0,0,0,0,0~
,0,0,CD20,0,0,0,0,0,0)';$S;
    'VSS672':'(0,0,0,0,0,0,0,0,0,0,0,0,0,0,0,0,0,0,0,0,0,0,0,0,0,0,0,0,0,0,0,0,0~
,0,0,CD16,0,0,0,0,0,0)';$S;
    'VSS671':'(0,0,0,0,0,0,0,0,0,0,0,0,0,0,0,0,0,0,0,0,0,0,0,0,0,0,0,0,0,0,0,0,0~
,0,0,CD12,0,0,0,0,0,0)';$S;
    'VSS670':'(0,0,0,0,0,0,0,0,0,0,0,0,0,0,0,0,0,0,0,0,0,0,0,0,0,0,0,0,0,0,0,0,0~
,0,0,CC9,0,0,0,0,0,0)';$S;
    'VSS669':'(0,0,0,0,0,0,0,0,0,0,0,0,0,0,0,0,0,0,0,0,0,0,0,0,0,0,0,0,0,0,0,0,0~
,0,0,CC74,0,0,0,0,0,0)';$S;
    'VSS668':'(0,0,0,0,0,0,0,0,0,0,0,0,0,0,0,0,0,0,0,0,0,0,0,0,0,0,0,0,0,0,0,0,0~
,0,0,CC72,0,0,0,0,0,0)';$S;
    'VSS667':'(0,0,0,0,0,0,0,0,0,0,0,0,0,0,0,0,0,0,0,0,0,0,0,0,0,0,0,0,0,0,0,0,0~
,0,0,CC70,0,0,0,0,0,0)';$S;
    'VSS666':'(0,0,0,0,0,0,0,0,0,0,0,0,0,0,0,0,0,0,0,0,0,0,0,0,0,0,0,0,0,0,0,0,0~
,0,0,CC62,0,0,0,0,0,0)';$S;
    'VSS665':'(0,0,0,0,0,0,0,0,0,0,0,0,0,0,0,0,0,0,0,0,0,0,0,0,0,0,0,0,0,0,0,0,0~
,0,0,CC5,0,0,0,0,0,0)';$S;
    'VSS664':'(0,0,0,0,0,0,0,0,0,0,0,0,0,0,0,0,0,0,0,0,0,0,0,0,0,0,0,0,0,0,0,0,0~
,0,0,CC31,0,0,0,0,0,0)';$S;
    'VSS661':'(0,0,0,0,0,0,0,0,0,0,0,0,0,0,0,0,0,0,0,0,0,0,0,0,0,0,0,0,0,0,0,0,0~
,0,0,CC17,0,0,0,0,0,0)';$S;
    'VSS660':'(0,0,0,0,0,0,0,0,0,0,0,0,0,0,0,0,0,0,0,0,0,0,0,0,0,0,0,0,0,0,0,0,0~
,0,0,CC13,0,0,0,0,0,0)';$S;
    'VSS656':'(0,0,0,0,0,0,0,0,0,0,0,0,0,0,0,0,0,0,0,0,0,0,0,0,0,0,0,0,0,0,0,0,0~
,0,0,CB89,0,0,0,0,0,0)';$S;
    'VSS655':'(0,0,0,0,0,0,0,0,0,0,0,0,0,0,0,0,0,0,0,0,0,0,0,0,0,0,0,0,0,0,0,0,0~
,0,0,CB87,0,0,0,0,0,0)';$S;
    'VSS654':'(0,0,0,0,0,0,0,0,0,0,0,0,0,0,0,0,0,0,0,0,0,0,0,0,0,0,0,0,0,0,0,0,0~
,0,0,CB85,0,0,0,0,0,0)';$S;
    'VSS653':'(0,0,0,0,0,0,0,0,0,0,0,0,0,0,0,0,0,0,0,0,0,0,0,0,0,0,0,0,0,0,0,0,0~
,0,0,CB83,0,0,0,0,0,0)';$S;
    'VSS652':'(0,0,0,0,0,0,0,0,0,0,0,0,0,0,0,0,0,0,0,0,0,0,0,0,0,0,0,0,0,0,0,0,0~
,0,0,CB81,0,0,0,0,0,0)';$S;
    'VSS651':'(0,0,0,0,0,0,0,0,0,0,0,0,0,0,0,0,0,0,0,0,0,0,0,0,0,0,0,0,0,0,0,0,0~
,0,0,CB8,0,0,0,0,0,0)';$S;
    'VSS650':'(0,0,0,0,0,0,0,0,0,0,0,0,0,0,0,0,0,0,0,0,0,0,0,0,0,0,0,0,0,0,0,0,0~
,0,0,CB79,0,0,0,0,0,0)';$S;
    'VSS649':'(0,0,0,0,0,0,0,0,0,0,0,0,0,0,0,0,0,0,0,0,0,0,0,0,0,0,0,0,0,0,0,0,0~
,0,0,CB73,0,0,0,0,0,0)';$S;
    'VSS648':'(0,0,0,0,0,0,0,0,0,0,0,0,0,0,0,0,0,0,0,0,0,0,0,0,0,0,0,0,0,0,0,0,0~
,0,0,CB71,0,0,0,0,0,0)';$S;
    'VSS647':'(0,0,0,0,0,0,0,0,0,0,0,0,0,0,0,0,0,0,0,0,0,0,0,0,0,0,0,0,0,0,0,0,0~
,0,0,CB69,0,0,0,0,0,0)';$S;
    'VSS646':'(0,0,0,0,0,0,0,0,0,0,0,0,0,0,0,0,0,0,0,0,0,0,0,0,0,0,0,0,0,0,0,0,0~
,0,0,CB67,0,0,0,0,0,0)';$S;
    'VSS645':'(0,0,0,0,0,0,0,0,0,0,0,0,0,0,0,0,0,0,0,0,0,0,0,0,0,0,0,0,0,0,0,0,0~
,0,0,CB65,0,0,0,0,0,0)';$S;
    'VSS644':'(0,0,0,0,0,0,0,0,0,0,0,0,0,0,0,0,0,0,0,0,0,0,0,0,0,0,0,0,0,0,0,0,0~
,0,0,CB63,0,0,0,0,0,0)';$S;
    'VSS643':'(0,0,0,0,0,0,0,0,0,0,0,0,0,0,0,0,0,0,0,0,0,0,0,0,0,0,0,0,0,0,0,0,0~
,0,0,CB59,0,0,0,0,0,0)';$S;
    'VSS642':'(0,0,0,0,0,0,0,0,0,0,0,0,0,0,0,0,0,0,0,0,0,0,0,0,0,0,0,0,0,0,0,0,0~
,0,0,CB57,0,0,0,0,0,0)';$S;
    'VSS641':'(0,0,0,0,0,0,0,0,0,0,0,0,0,0,0,0,0,0,0,0,0,0,0,0,0,0,0,0,0,0,0,0,0~
,0,0,CB55,0,0,0,0,0,0)';$S;
    'VSS640':'(0,0,0,0,0,0,0,0,0,0,0,0,0,0,0,0,0,0,0,0,0,0,0,0,0,0,0,0,0,0,0,0,0~
,0,0,CB53,0,0,0,0,0,0)';$S;
    'VSS639':'(0,0,0,0,0,0,0,0,0,0,0,0,0,0,0,0,0,0,0,0,0,0,0,0,0,0,0,0,0,0,0,0,0~
,0,0,CB51,0,0,0,0,0,0)';$S;
    'VSS638':'(0,0,0,0,0,0,0,0,0,0,0,0,0,0,0,0,0,0,0,0,0,0,0,0,0,0,0,0,0,0,0,0,0~
,0,0,CB49,0,0,0,0,0,0)';$S;
    'VSS637':'(0,0,0,0,0,0,0,0,0,0,0,0,0,0,0,0,0,0,0,0,0,0,0,0,0,0,0,0,0,0,0,0,0~
,0,0,CB47,0,0,0,0,0,0)';$S;
    'VSS636':'(0,0,0,0,0,0,0,0,0,0,0,0,0,0,0,0,0,0,0,0,0,0,0,0,0,0,0,0,0,0,0,0,0~
,0,0,CB44,0,0,0,0,0,0)';$S;
    'VSS635':'(0,0,0,0,0,0,0,0,0,0,0,0,0,0,0,0,0,0,0,0,0,0,0,0,0,0,0,0,0,0,0,0,0~
,0,0,CB42,0,0,0,0,0,0)';$S;
    'VSS634':'(0,0,0,0,0,0,0,0,0,0,0,0,0,0,0,0,0,0,0,0,0,0,0,0,0,0,0,0,0,0,0,0,0~
,0,0,CB40,0,0,0,0,0,0)';$S;
    'VSS633':'(0,0,0,0,0,0,0,0,0,0,0,0,0,0,0,0,0,0,0,0,0,0,0,0,0,0,0,0,0,0,0,0,0~
,0,0,CB4,0,0,0,0,0,0)';$S;
    'VSS632':'(0,0,0,0,0,0,0,0,0,0,0,0,0,0,0,0,0,0,0,0,0,0,0,0,0,0,0,0,0,0,0,0,0~
,0,0,CB38,0,0,0,0,0,0)';$S;
    'VSS631':'(0,0,0,0,0,0,0,0,0,0,0,0,0,0,0,0,0,0,0,0,0,0,0,0,0,0,0,0,0,0,0,0,0~
,0,0,CB36,0,0,0,0,0,0)';$S;
    'VSS630':'(0,0,0,0,0,0,0,0,0,0,0,0,0,0,0,0,0,0,0,0,0,0,0,0,0,0,0,0,0,0,0,0,0~
,0,0,CB34,0,0,0,0,0,0)';$S;
    'VSS629':'(0,0,0,0,0,0,0,0,0,0,0,0,0,0,0,0,0,0,0,0,0,0,0,0,0,0,0,0,0,0,0,0,0~
,0,0,CB32,0,0,0,0,0,0)';$S;
    'VSS628':'(0,0,0,0,0,0,0,0,0,0,0,0,0,0,0,0,0,0,0,0,0,0,0,0,0,0,0,0,0,0,0,0,0~
,0,0,CB28,0,0,0,0,0,0)';$S;
    'VSS627':'(0,0,0,0,0,0,0,0,0,0,0,0,0,0,0,0,0,0,0,0,0,0,0,0,0,0,0,0,0,0,0,0,0~
,0,0,CB26,0,0,0,0,0,0)';$S;
    'VSS626':'(0,0,0,0,0,0,0,0,0,0,0,0,0,0,0,0,0,0,0,0,0,0,0,0,0,0,0,0,0,0,0,0,0~
,0,0,CB24,0,0,0,0,0,0)';$S;
    'VSS625':'(0,0,0,0,0,0,0,0,0,0,0,0,0,0,0,0,0,0,0,0,0,0,0,0,0,0,0,0,0,0,0,0,0~
,0,0,CB22,0,0,0,0,0,0)';$S;
    'VSS624':'(0,0,0,0,0,0,0,0,0,0,0,0,0,0,0,0,0,0,0,0,0,0,0,0,0,0,0,0,0,0,0,0,0~
,0,0,CB20,0,0,0,0,0,0)';$S;
    'VSS623':'(0,0,0,0,0,0,0,0,0,0,0,0,0,0,0,0,0,0,0,0,0,0,0,0,0,0,0,0,0,0,0,0,0~
,0,0,CB16,0,0,0,0,0,0)';$S;
    'VSS622':'(0,0,0,0,0,0,0,0,0,0,0,0,0,0,0,0,0,0,0,0,0,0,0,0,0,0,0,0,0,0,0,0,0~
,0,0,CB12,0,0,0,0,0,0)';$S;
    'VSS621':'(0,0,0,0,0,0,0,0,0,0,0,0,0,0,0,0,0,0,0,0,0,0,0,0,0,0,0,0,0,0,0,0,0~
,0,0,CA31,0,0,0,0,0,0)';$S;
    'VSS620':'(0,0,0,0,0,0,0,0,0,0,0,0,0,0,0,0,0,0,0,0,0,0,0,0,0,0,0,0,0,0,0,0,0~
,0,0,CA3,0,0,0,0,0,0)';$S;
    'VSS608':'(0,0,0,0,0,0,0,0,0,0,0,0,0,0,0,0,0,0,0,0,0,0,0,0,0,0,0,0,0,0,0,0,0~
,0,0,BY8,0,0,0,0,0,0)';$S;
    'VSS607':'(0,0,0,0,0,0,0,0,0,0,0,0,0,0,0,0,0,0,0,0,0,0,0,0,0,0,0,0,0,0,0,0,0~
,0,0,BY4,0,0,0,0,0,0)';$S;
    'VSS606':'(0,0,0,0,0,0,0,0,0,0,0,0,0,0,0,0,0,0,0,0,0,0,0,0,0,0,0,0,0,0,0,0,0~
,0,0,BY20,0,0,0,0,0,0)';$S;
    'VSS605':'(0,0,0,0,0,0,0,0,0,0,0,0,0,0,0,0,0,0,0,0,0,0,0,0,0,0,0,0,0,0,0,0,0~
,0,0,BY16,0,0,0,0,0,0)';$S;
    'VSS604':'(0,0,0,0,0,0,0,0,0,0,0,0,0,0,0,0,0,0,0,0,0,0,0,0,0,0,0,0,0,0,0,0,0~
,0,0,BY12,0,0,0,0,0,0)';$S;
    'VSS603':'(0,0,0,0,0,0,0,0,0,0,0,0,0,0,0,0,0,0,0,0,0,0,0,0,0,0,0,0,0,0,0,0,0~
,0,0,BW9,0,0,0,0,0,0)';$S;
    'VSS602':'(0,0,0,0,0,0,0,0,0,0,0,0,0,0,0,0,0,0,0,0,0,0,0,0,0,0,0,0,0,0,0,0,0~
,0,0,BW5,0,0,0,0,0,0)';$S;
    'VSS601':'(0,0,0,0,0,0,0,0,0,0,0,0,0,0,0,0,0,0,0,0,0,0,0,0,0,0,0,0,0,0,0,0,0~
,0,0,BW31,0,0,0,0,0,0)';$S;
    'VSS600':'(0,0,0,0,0,0,0,0,0,0,0,0,0,0,0,0,0,0,0,0,0,0,0,0,0,0,0,0,0,0,0,0,0~
,0,0,BW3,0,0,0,0,0,0)';$S;
    'VSS599':'(0,0,0,0,0,0,0,0,0,0,0,0,0,0,0,0,0,0,0,0,0,0,0,0,0,0,0,0,0,0,0,0,0~
,0,0,BW29,0,0,0,0,0,0)';$S;
    'VSS598':'(0,0,0,0,0,0,0,0,0,0,0,0,0,0,0,0,0,0,0,0,0,0,0,0,0,0,0,0,0,0,0,0,0~
,0,0,BW27,0,0,0,0,0,0)';$S;
    'VSS597':'(0,0,0,0,0,0,0,0,0,0,0,0,0,0,0,0,0,0,0,0,0,0,0,0,0,0,0,0,0,0,0,0,0~
,0,0,BW17,0,0,0,0,0,0)';$S;
    'VSS596':'(0,0,0,0,0,0,0,0,0,0,0,0,0,0,0,0,0,0,0,0,0,0,0,0,0,0,0,0,0,0,0,0,0~
,0,0,BW13,0,0,0,0,0,0)';$S;
    'VSS594':'(0,0,0,0,0,0,0,0,0,0,0,0,0,0,0,0,0,0,0,0,0,0,0,0,0,0,0,0,0,0,0,0,0~
,0,0,BV8,0,0,0,0,0,0)';$S;
    'VSS593':'(0,0,0,0,0,0,0,0,0,0,0,0,0,0,0,0,0,0,0,0,0,0,0,0,0,0,0,0,0,0,0,0,0~
,0,0,BV6,0,0,0,0,0,0)';$S;
    'VSS592':'(0,0,0,0,0,0,0,0,0,0,0,0,0,0,0,0,0,0,0,0,0,0,0,0,0,0,0,0,0,0,0,0,0~
,0,0,BV4,0,0,0,0,0,0)';$S;
    'VSS591':'(0,0,0,0,0,0,0,0,0,0,0,0,0,0,0,0,0,0,0,0,0,0,0,0,0,0,0,0,0,0,0,0,0~
,0,0,BV20,0,0,0,0,0,0)';$S;
    'VSS590':'(0,0,0,0,0,0,0,0,0,0,0,0,0,0,0,0,0,0,0,0,0,0,0,0,0,0,0,0,0,0,0,0,0~
,0,0,BV2,0,0,0,0,0,0)';$S;
    'VSS589':'(0,0,0,0,0,0,0,0,0,0,0,0,0,0,0,0,0,0,0,0,0,0,0,0,0,0,0,0,0,0,0,0,0~
,0,0,BV18,0,0,0,0,0,0)';$S;
    'VSS588':'(0,0,0,0,0,0,0,0,0,0,0,0,0,0,0,0,0,0,0,0,0,0,0,0,0,0,0,0,0,0,0,0,0~
,0,0,BV16,0,0,0,0,0,0)';$S;
    'VSS587':'(0,0,0,0,0,0,0,0,0,0,0,0,0,0,0,0,0,0,0,0,0,0,0,0,0,0,0,0,0,0,0,0,0~
,0,0,BV12,0,0,0,0,0,0)';$S;
    'VSS586':'(0,0,0,0,0,0,0,0,0,0,0,0,0,0,0,0,0,0,0,0,0,0,0,0,0,0,0,0,0,0,0,0,0~
,0,0,BU7,0,0,0,0,0,0)';$S;
    'VSS585':'(0,0,0,0,0,0,0,0,0,0,0,0,0,0,0,0,0,0,0,0,0,0,0,0,0,0,0,0,0,0,0,0,0~
,0,0,BU31,0,0,0,0,0,0)';$S;
    'VSS584':'(0,0,0,0,0,0,0,0,0,0,0,0,0,0,0,0,0,0,0,0,0,0,0,0,0,0,0,0,0,0,0,0,0~
,0,0,BU25,0,0,0,0,0,0)';$S;
    'VSS582':'(0,0,0,0,0,0,0,0,0,0,0,0,0,0,0,0,0,0,0,0,0,0,0,0,0,0,0,0,0,0,0,0,0~
,0,0,BU23,0,0,0,0,0,0)';$S;
    'VSS581':'(0,0,0,0,0,0,0,0,0,0,0,0,0,0,0,0,0,0,0,0,0,0,0,0,0,0,0,0,0,0,0,0,0~
,0,0,BU21,0,0,0,0,0,0)';$S;
    'VSS580':'(0,0,0,0,0,0,0,0,0,0,0,0,0,0,0,0,0,0,0,0,0,0,0,0,0,0,0,0,0,0,0,0,0~
,0,0,BU19,0,0,0,0,0,0)';$S;
    'VSS579':'(0,0,0,0,0,0,0,0,0,0,0,0,0,0,0,0,0,0,0,0,0,0,0,0,0,0,0,0,0,0,0,0,0~
,0,0,BU15,0,0,0,0,0,0)';$S;
    'VSS578':'(0,0,0,0,0,0,0,0,0,0,0,0,0,0,0,0,0,0,0,0,0,0,0,0,0,0,0,0,0,0,0,0,0~
,0,0,BT8,0,0,0,0,0,0)';$S;
    'VSS577':'(0,0,0,0,0,0,0,0,0,0,0,0,0,0,0,0,0,0,0,0,0,0,0,0,0,0,0,0,0,0,0,0,0~
,0,0,BT4,0,0,0,0,0,0)';$S;
    'VSS576':'(0,0,0,0,0,0,0,0,0,0,0,0,0,0,0,0,0,0,0,0,0,0,0,0,0,0,0,0,0,0,0,0,0~
,0,0,BT20,0,0,0,0,0,0)';$S;
    'VSS575':'(0,0,0,0,0,0,0,0,0,0,0,0,0,0,0,0,0,0,0,0,0,0,0,0,0,0,0,0,0,0,0,0,0~
,0,0,BT16,0,0,0,0,0,0)';$S;
    'VSS574':'(0,0,0,0,0,0,0,0,0,0,0,0,0,0,0,0,0,0,0,0,0,0,0,0,0,0,0,0,0,0,0,0,0~
,0,0,BT12,0,0,0,0,0,0)';$S;
    'VSS573':'(0,0,0,0,0,0,0,0,0,0,0,0,0,0,0,0,0,0,0,0,0,0,0,0,0,0,0,0,0,0,0,0,0~
,0,0,BR90,0,0,0,0,0,0)';$S;
    'VSS570':'(0,0,0,0,0,0,0,0,0,0,0,0,0,0,0,0,0,0,0,0,0,0,0,0,0,0,0,0,0,0,0,0,0~
,0,0,BR88,0,0,0,0,0,0)';$S;
    'VSS569':'(0,0,0,0,0,0,0,0,0,0,0,0,0,0,0,0,0,0,0,0,0,0,0,0,0,0,0,0,0,0,0,0,0~
,0,0,BR86,0,0,0,0,0,0)';$S;
    'VSS568':'(0,0,0,0,0,0,0,0,0,0,0,0,0,0,0,0,0,0,0,0,0,0,0,0,0,0,0,0,0,0,0,0,0~
,0,0,BR84,0,0,0,0,0,0)';$S;
    'VSS567':'(0,0,0,0,0,0,0,0,0,0,0,0,0,0,0,0,0,0,0,0,0,0,0,0,0,0,0,0,0,0,0,0,0~
,0,0,BR82,0,0,0,0,0,0)';$S;
    'VSS566':'(0,0,0,0,0,0,0,0,0,0,0,0,0,0,0,0,0,0,0,0,0,0,0,0,0,0,0,0,0,0,0,0,0~
,0,0,BR80,0,0,0,0,0,0)';$S;
    'VSS565':'(0,0,0,0,0,0,0,0,0,0,0,0,0,0,0,0,0,0,0,0,0,0,0,0,0,0,0,0,0,0,0,0,0~
,0,0,BR76,0,0,0,0,0,0)';$S;
    'VSS564':'(0,0,0,0,0,0,0,0,0,0,0,0,0,0,0,0,0,0,0,0,0,0,0,0,0,0,0,0,0,0,0,0,0~
,0,0,BR74,0,0,0,0,0,0)';$S;
    'VSS563':'(0,0,0,0,0,0,0,0,0,0,0,0,0,0,0,0,0,0,0,0,0,0,0,0,0,0,0,0,0,0,0,0,0~
,0,0,BR72,0,0,0,0,0,0)';$S;
    'VSS561':'(0,0,0,0,0,0,0,0,0,0,0,0,0,0,0,0,0,0,0,0,0,0,0,0,0,0,0,0,0,0,0,0,0~
,0,0,BR70,0,0,0,0,0,0)';$S;
    'VSS560':'(0,0,0,0,0,0,0,0,0,0,0,0,0,0,0,0,0,0,0,0,0,0,0,0,0,0,0,0,0,0,0,0,0~
,0,0,BR68,0,0,0,0,0,0)';$S;
    'VSS559':'(0,0,0,0,0,0,0,0,0,0,0,0,0,0,0,0,0,0,0,0,0,0,0,0,0,0,0,0,0,0,0,0,0~
,0,0,BR66,0,0,0,0,0,0)';$S;
    'VSS557':'(0,0,0,0,0,0,0,0,0,0,0,0,0,0,0,0,0,0,0,0,0,0,0,0,0,0,0,0,0,0,0,0,0~
,0,0,BR64,0,0,0,0,0,0)';$S;
    'VSS556':'(0,0,0,0,0,0,0,0,0,0,0,0,0,0,0,0,0,0,0,0,0,0,0,0,0,0,0,0,0,0,0,0,0~
,0,0,BR58,0,0,0,0,0,0)';$S;
    'VSS555':'(0,0,0,0,0,0,0,0,0,0,0,0,0,0,0,0,0,0,0,0,0,0,0,0,0,0,0,0,0,0,0,0,0~
,0,0,BR56,0,0,0,0,0,0)';$S;
    'VSS552':'(0,0,0,0,0,0,0,0,0,0,0,0,0,0,0,0,0,0,0,0,0,0,0,0,0,0,0,0,0,0,0,0,0~
,0,0,BR54,0,0,0,0,0,0)';$S;
    'VSS551':'(0,0,0,0,0,0,0,0,0,0,0,0,0,0,0,0,0,0,0,0,0,0,0,0,0,0,0,0,0,0,0,0,0~
,0,0,BR52,0,0,0,0,0,0)';$S;
    'VSS550':'(0,0,0,0,0,0,0,0,0,0,0,0,0,0,0,0,0,0,0,0,0,0,0,0,0,0,0,0,0,0,0,0,0~
,0,0,BR50,0,0,0,0,0,0)';$S;
    'VSS549':'(0,0,0,0,0,0,0,0,0,0,0,0,0,0,0,0,0,0,0,0,0,0,0,0,0,0,0,0,0,0,0,0,0~
,0,0,BR48,0,0,0,0,0,0)';$S;
    'VSS548':'(0,0,0,0,0,0,0,0,0,0,0,0,0,0,0,0,0,0,0,0,0,0,0,0,0,0,0,0,0,0,0,0,0~
,0,0,BR45,0,0,0,0,0,0)';$S;
    'VSS547':'(0,0,0,0,0,0,0,0,0,0,0,0,0,0,0,0,0,0,0,0,0,0,0,0,0,0,0,0,0,0,0,0,0~
,0,0,BR43,0,0,0,0,0,0)';$S;
    'VSS546':'(0,0,0,0,0,0,0,0,0,0,0,0,0,0,0,0,0,0,0,0,0,0,0,0,0,0,0,0,0,0,0,0,0~
,0,0,BR41,0,0,0,0,0,0)';$S;
    'VSS545':'(0,0,0,0,0,0,0,0,0,0,0,0,0,0,0,0,0,0,0,0,0,0,0,0,0,0,0,0,0,0,0,0,0~
,0,0,BR39,0,0,0,0,0,0)';$S;
    'VSS543':'(0,0,0,0,0,0,0,0,0,0,0,0,0,0,0,0,0,0,0,0,0,0,0,0,0,0,0,0,0,0,0,0,0~
,0,0,BR37,0,0,0,0,0,0)';$S;
    'VSS542':'(0,0,0,0,0,0,0,0,0,0,0,0,0,0,0,0,0,0,0,0,0,0,0,0,0,0,0,0,0,0,0,0,0~
,0,0,BR35,0,0,0,0,0,0)';$S;
    'VSS396':'(0,0,0,0,0,0,0,0,0,0,0,0,0,0,0,0,0,0,0,0,0,0,0,0,0,0,0,0,0,0,0,0,0~
,0,0,CK4,0,0,0,0,0,0)';$S;
    'VSS383':'(0,0,0,0,0,0,0,0,0,0,0,0,0,0,0,0,0,0,0,0,0,0,0,0,0,0,0,0,0,0,0,0,0~
,0,0,CJ76,0,0,0,0,0,0)';$S;
    'VSS572':'(0,0,0,0,0,0,0,0,0,0,0,0,0,0,0,0,0,0,0,0,0,0,0,0,0,0,0,0,0,0,0,0,0~
,0,0,0,BR9,0,0,0,0,0)';$S;
    'VSS541':'(0,0,0,0,0,0,0,0,0,0,0,0,0,0,0,0,0,0,0,0,0,0,0,0,0,0,0,0,0,0,0,0,0~
,0,0,0,BR33,0,0,0,0,0)';$S;
    'VSS540':'(0,0,0,0,0,0,0,0,0,0,0,0,0,0,0,0,0,0,0,0,0,0,0,0,0,0,0,0,0,0,0,0,0~
,0,0,0,BR31,0,0,0,0,0)';$S;
    'VSS539':'(0,0,0,0,0,0,0,0,0,0,0,0,0,0,0,0,0,0,0,0,0,0,0,0,0,0,0,0,0,0,0,0,0~
,0,0,0,BR29,0,0,0,0,0)';$S;
    'VSS538':'(0,0,0,0,0,0,0,0,0,0,0,0,0,0,0,0,0,0,0,0,0,0,0,0,0,0,0,0,0,0,0,0,0~
,0,0,0,BR27,0,0,0,0,0)';$S;
    'VSS536':'(0,0,0,0,0,0,0,0,0,0,0,0,0,0,0,0,0,0,0,0,0,0,0,0,0,0,0,0,0,0,0,0,0~
,0,0,0,BR17,0,0,0,0,0)';$S;
    'VSS535':'(0,0,0,0,0,0,0,0,0,0,0,0,0,0,0,0,0,0,0,0,0,0,0,0,0,0,0,0,0,0,0,0,0~
,0,0,0,BR13,0,0,0,0,0)';$S;
    'VSS533':'(0,0,0,0,0,0,0,0,0,0,0,0,0,0,0,0,0,0,0,0,0,0,0,0,0,0,0,0,0,0,0,0,0~
,0,0,0,BP8,0,0,0,0,0)';$S;
    'VSS532':'(0,0,0,0,0,0,0,0,0,0,0,0,0,0,0,0,0,0,0,0,0,0,0,0,0,0,0,0,0,0,0,0,0~
,0,0,0,BP77,0,0,0,0,0)';$S;
    'VSS531':'(0,0,0,0,0,0,0,0,0,0,0,0,0,0,0,0,0,0,0,0,0,0,0,0,0,0,0,0,0,0,0,0,0~
,0,0,0,BP75,0,0,0,0,0)';$S;
    'VSS530':'(0,0,0,0,0,0,0,0,0,0,0,0,0,0,0,0,0,0,0,0,0,0,0,0,0,0,0,0,0,0,0,0,0~
,0,0,0,BP73,0,0,0,0,0)';$S;
    'VSS529':'(0,0,0,0,0,0,0,0,0,0,0,0,0,0,0,0,0,0,0,0,0,0,0,0,0,0,0,0,0,0,0,0,0~
,0,0,0,BP71,0,0,0,0,0)';$S;
    'VSS528':'(0,0,0,0,0,0,0,0,0,0,0,0,0,0,0,0,0,0,0,0,0,0,0,0,0,0,0,0,0,0,0,0,0~
,0,0,0,BP63,0,0,0,0,0)';$S;
    'VSS527':'(0,0,0,0,0,0,0,0,0,0,0,0,0,0,0,0,0,0,0,0,0,0,0,0,0,0,0,0,0,0,0,0,0~
,0,0,0,BP4,0,0,0,0,0)';$S;
    'VSS525':'(0,0,0,0,0,0,0,0,0,0,0,0,0,0,0,0,0,0,0,0,0,0,0,0,0,0,0,0,0,0,0,0,0~
,0,0,0,BP20,0,0,0,0,0)';$S;
    'VSS524':'(0,0,0,0,0,0,0,0,0,0,0,0,0,0,0,0,0,0,0,0,0,0,0,0,0,0,0,0,0,0,0,0,0~
,0,0,0,BP2,0,0,0,0,0)';$S;
    'VSS523':'(0,0,0,0,0,0,0,0,0,0,0,0,0,0,0,0,0,0,0,0,0,0,0,0,0,0,0,0,0,0,0,0,0~
,0,0,0,BP16,0,0,0,0,0)';$S;
    'VSS522':'(0,0,0,0,0,0,0,0,0,0,0,0,0,0,0,0,0,0,0,0,0,0,0,0,0,0,0,0,0,0,0,0,0~
,0,0,0,BP12,0,0,0,0,0)';$S;
    'VSS520':'(0,0,0,0,0,0,0,0,0,0,0,0,0,0,0,0,0,0,0,0,0,0,0,0,0,0,0,0,0,0,0,0,0~
,0,0,0,BN70,0,0,0,0,0)';$S;
    'VSS519':'(0,0,0,0,0,0,0,0,0,0,0,0,0,0,0,0,0,0,0,0,0,0,0,0,0,0,0,0,0,0,0,0,0~
,0,0,0,BN62,0,0,0,0,0)';$S;
    'VSS518':'(0,0,0,0,0,0,0,0,0,0,0,0,0,0,0,0,0,0,0,0,0,0,0,0,0,0,0,0,0,0,0,0,0~
,0,0,0,BN31,0,0,0,0,0)';$S;
    'VSS517':'(0,0,0,0,0,0,0,0,0,0,0,0,0,0,0,0,0,0,0,0,0,0,0,0,0,0,0,0,0,0,0,0,0~
,0,0,0,BM8,0,0,0,0,0)';$S;
    'VSS516':'(0,0,0,0,0,0,0,0,0,0,0,0,0,0,0,0,0,0,0,0,0,0,0,0,0,0,0,0,0,0,0,0,0~
,0,0,0,BM77,0,0,0,0,0)';$S;
    'VSS515':'(0,0,0,0,0,0,0,0,0,0,0,0,0,0,0,0,0,0,0,0,0,0,0,0,0,0,0,0,0,0,0,0,0~
,0,0,0,BM73,0,0,0,0,0)';$S;
    'VSS513':'(0,0,0,0,0,0,0,0,0,0,0,0,0,0,0,0,0,0,0,0,0,0,0,0,0,0,0,0,0,0,0,0,0~
,0,0,0,BM61,0,0,0,0,0)';$S;
    'VSS512':'(0,0,0,0,0,0,0,0,0,0,0,0,0,0,0,0,0,0,0,0,0,0,0,0,0,0,0,0,0,0,0,0,0~
,0,0,0,BM4,0,0,0,0,0)';$S;
    'VSS511':'(0,0,0,0,0,0,0,0,0,0,0,0,0,0,0,0,0,0,0,0,0,0,0,0,0,0,0,0,0,0,0,0,0~
,0,0,0,BM26,0,0,0,0,0)';$S;
    'VSS510':'(0,0,0,0,0,0,0,0,0,0,0,0,0,0,0,0,0,0,0,0,0,0,0,0,0,0,0,0,0,0,0,0,0~
,0,0,0,BM24,0,0,0,0,0)';$S;
    'VSS509':'(0,0,0,0,0,0,0,0,0,0,0,0,0,0,0,0,0,0,0,0,0,0,0,0,0,0,0,0,0,0,0,0,0~
,0,0,0,BM22,0,0,0,0,0)';$S;
    'VSS508':'(0,0,0,0,0,0,0,0,0,0,0,0,0,0,0,0,0,0,0,0,0,0,0,0,0,0,0,0,0,0,0,0,0~
,0,0,0,BM20,0,0,0,0,0)';$S;
    'VSS507':'(0,0,0,0,0,0,0,0,0,0,0,0,0,0,0,0,0,0,0,0,0,0,0,0,0,0,0,0,0,0,0,0,0~
,0,0,0,BM16,0,0,0,0,0)';$S;
    'VSS506':'(0,0,0,0,0,0,0,0,0,0,0,0,0,0,0,0,0,0,0,0,0,0,0,0,0,0,0,0,0,0,0,0,0~
,0,0,0,BM12,0,0,0,0,0)';$S;
    'VSS505':'(0,0,0,0,0,0,0,0,0,0,0,0,0,0,0,0,0,0,0,0,0,0,0,0,0,0,0,0,0,0,0,0,0~
,0,0,0,BL9,0,0,0,0,0)';$S;
    'VSS504':'(0,0,0,0,0,0,0,0,0,0,0,0,0,0,0,0,0,0,0,0,0,0,0,0,0,0,0,0,0,0,0,0,0~
,0,0,0,BL78,0,0,0,0,0)';$S;
    'VSS503':'(0,0,0,0,0,0,0,0,0,0,0,0,0,0,0,0,0,0,0,0,0,0,0,0,0,0,0,0,0,0,0,0,0~
,0,0,0,BL72,0,0,0,0,0)';$S;
    'VSS502':'(0,0,0,0,0,0,0,0,0,0,0,0,0,0,0,0,0,0,0,0,0,0,0,0,0,0,0,0,0,0,0,0,0~
,0,0,0,BL70,0,0,0,0,0)';$S;
    'VSS501':'(0,0,0,0,0,0,0,0,0,0,0,0,0,0,0,0,0,0,0,0,0,0,0,0,0,0,0,0,0,0,0,0,0~
,0,0,0,BL68,0,0,0,0,0)';$S;
    'VSS500':'(0,0,0,0,0,0,0,0,0,0,0,0,0,0,0,0,0,0,0,0,0,0,0,0,0,0,0,0,0,0,0,0,0~
,0,0,0,BL5,0,0,0,0,0)';$S;
    'VSS499':'(0,0,0,0,0,0,0,0,0,0,0,0,0,0,0,0,0,0,0,0,0,0,0,0,0,0,0,0,0,0,0,0,0~
,0,0,0,BL17,0,0,0,0,0)';$S;
    'VSS498':'(0,0,0,0,0,0,0,0,0,0,0,0,0,0,0,0,0,0,0,0,0,0,0,0,0,0,0,0,0,0,0,0,0~
,0,0,0,BL13,0,0,0,0,0)';$S;
    'VSS497':'(0,0,0,0,0,0,0,0,0,0,0,0,0,0,0,0,0,0,0,0,0,0,0,0,0,0,0,0,0,0,0,0,0~
,0,0,0,BL1,0,0,0,0,0)';$S;
    'VSS496':'(0,0,0,0,0,0,0,0,0,0,0,0,0,0,0,0,0,0,0,0,0,0,0,0,0,0,0,0,0,0,0,0,0~
,0,0,0,BK8,0,0,0,0,0)';$S;
    'VSS495':'(0,0,0,0,0,0,0,0,0,0,0,0,0,0,0,0,0,0,0,0,0,0,0,0,0,0,0,0,0,0,0,0,0~
,0,0,0,BK79,0,0,0,0,0)';$S;
    'VSS494':'(0,0,0,0,0,0,0,0,0,0,0,0,0,0,0,0,0,0,0,0,0,0,0,0,0,0,0,0,0,0,0,0,0~
,0,0,0,BK75,0,0,0,0,0)';$S;
    'VSS492':'(0,0,0,0,0,0,0,0,0,0,0,0,0,0,0,0,0,0,0,0,0,0,0,0,0,0,0,0,0,0,0,0,0~
,0,0,0,BK71,0,0,0,0,0)';$S;
    'VSS491':'(0,0,0,0,0,0,0,0,0,0,0,0,0,0,0,0,0,0,0,0,0,0,0,0,0,0,0,0,0,0,0,0,0~
,0,0,0,BK65,0,0,0,0,0)';$S;
    'VSS490':'(0,0,0,0,0,0,0,0,0,0,0,0,0,0,0,0,0,0,0,0,0,0,0,0,0,0,0,0,0,0,0,0,0~
,0,0,0,BK4,0,0,0,0,0)';$S;
    'VSS489':'(0,0,0,0,0,0,0,0,0,0,0,0,0,0,0,0,0,0,0,0,0,0,0,0,0,0,0,0,0,0,0,0,0~
,0,0,0,BK20,0,0,0,0,0)';$S;
    'VSS488':'(0,0,0,0,0,0,0,0,0,0,0,0,0,0,0,0,0,0,0,0,0,0,0,0,0,0,0,0,0,0,0,0,0~
,0,0,0,BK16,0,0,0,0,0)';$S;
    'VSS487':'(0,0,0,0,0,0,0,0,0,0,0,0,0,0,0,0,0,0,0,0,0,0,0,0,0,0,0,0,0,0,0,0,0~
,0,0,0,BK12,0,0,0,0,0)';$S;
    'VSS486':'(0,0,0,0,0,0,0,0,0,0,0,0,0,0,0,0,0,0,0,0,0,0,0,0,0,0,0,0,0,0,0,0,0~
,0,0,0,BJ90,0,0,0,0,0)';$S;
    'VSS485':'(0,0,0,0,0,0,0,0,0,0,0,0,0,0,0,0,0,0,0,0,0,0,0,0,0,0,0,0,0,0,0,0,0~
,0,0,0,BJ88,0,0,0,0,0)';$S;
    'VSS484':'(0,0,0,0,0,0,0,0,0,0,0,0,0,0,0,0,0,0,0,0,0,0,0,0,0,0,0,0,0,0,0,0,0~
,0,0,0,BJ86,0,0,0,0,0)';$S;
    'VSS483':'(0,0,0,0,0,0,0,0,0,0,0,0,0,0,0,0,0,0,0,0,0,0,0,0,0,0,0,0,0,0,0,0,0~
,0,0,0,BJ84,0,0,0,0,0)';$S;
    'VSS482':'(0,0,0,0,0,0,0,0,0,0,0,0,0,0,0,0,0,0,0,0,0,0,0,0,0,0,0,0,0,0,0,0,0~
,0,0,0,BJ82,0,0,0,0,0)';$S;
    'VSS481':'(0,0,0,0,0,0,0,0,0,0,0,0,0,0,0,0,0,0,0,0,0,0,0,0,0,0,0,0,0,0,0,0,0~
,0,0,0,BJ80,0,0,0,0,0)';$S;
    'VSS480':'(0,0,0,0,0,0,0,0,0,0,0,0,0,0,0,0,0,0,0,0,0,0,0,0,0,0,0,0,0,0,0,0,0~
,0,0,0,BJ68,0,0,0,0,0)';$S;
    'VSS479':'(0,0,0,0,0,0,0,0,0,0,0,0,0,0,0,0,0,0,0,0,0,0,0,0,0,0,0,0,0,0,0,0,0~
,0,0,0,BJ62,0,0,0,0,0)';$S;
    'VSS477':'(0,0,0,0,0,0,0,0,0,0,0,0,0,0,0,0,0,0,0,0,0,0,0,0,0,0,0,0,0,0,0,0,0~
,0,0,0,BH83,0,0,0,0,0)';$S;
    'VSS476':'(0,0,0,0,0,0,0,0,0,0,0,0,0,0,0,0,0,0,0,0,0,0,0,0,0,0,0,0,0,0,0,0,0~
,0,0,0,BH81,0,0,0,0,0)';$S;
    'VSS475':'(0,0,0,0,0,0,0,0,0,0,0,0,0,0,0,0,0,0,0,0,0,0,0,0,0,0,0,0,0,0,0,0,0~
,0,0,0,BH8,0,0,0,0,0)';$S;
    'VSS474':'(0,0,0,0,0,0,0,0,0,0,0,0,0,0,0,0,0,0,0,0,0,0,0,0,0,0,0,0,0,0,0,0,0~
,0,0,0,BH77,0,0,0,0,0)';$S;
    'VSS473':'(0,0,0,0,0,0,0,0,0,0,0,0,0,0,0,0,0,0,0,0,0,0,0,0,0,0,0,0,0,0,0,0,0~
,0,0,0,BH73,0,0,0,0,0)';$S;
    'VSS472':'(0,0,0,0,0,0,0,0,0,0,0,0,0,0,0,0,0,0,0,0,0,0,0,0,0,0,0,0,0,0,0,0,0~
,0,0,0,BH67,0,0,0,0,0)';$S;
    'VSS470':'(0,0,0,0,0,0,0,0,0,0,0,0,0,0,0,0,0,0,0,0,0,0,0,0,0,0,0,0,0,0,0,0,0~
,0,0,0,BH4,0,0,0,0,0)';$S;
    'VSS469':'(0,0,0,0,0,0,0,0,0,0,0,0,0,0,0,0,0,0,0,0,0,0,0,0,0,0,0,0,0,0,0,0,0~
,0,0,0,BH20,0,0,0,0,0)';$S;
    'VSS468':'(0,0,0,0,0,0,0,0,0,0,0,0,0,0,0,0,0,0,0,0,0,0,0,0,0,0,0,0,0,0,0,0,0~
,0,0,0,BH16,0,0,0,0,0)';$S;
    'VSS467':'(0,0,0,0,0,0,0,0,0,0,0,0,0,0,0,0,0,0,0,0,0,0,0,0,0,0,0,0,0,0,0,0,0~
,0,0,0,BH12,0,0,0,0,0)';$S;
    'VSS466':'(0,0,0,0,0,0,0,0,0,0,0,0,0,0,0,0,0,0,0,0,0,0,0,0,0,0,0,0,0,0,0,0,0~
,0,0,0,BG9,0,0,0,0,0)';$S;
    'VSS465':'(0,0,0,0,0,0,0,0,0,0,0,0,0,0,0,0,0,0,0,0,0,0,0,0,0,0,0,0,0,0,0,0,0~
,0,0,0,BG70,0,0,0,0,0)';$S;
    'VSS464':'(0,0,0,0,0,0,0,0,0,0,0,0,0,0,0,0,0,0,0,0,0,0,0,0,0,0,0,0,0,0,0,0,0~
,0,0,0,BG5,0,0,0,0,0)';$S;
    'VSS463':'(0,0,0,0,0,0,0,0,0,0,0,0,0,0,0,0,0,0,0,0,0,0,0,0,0,0,0,0,0,0,0,0,0~
,0,0,0,BG25,0,0,0,0,0)';$S;
    'VSS462':'(0,0,0,0,0,0,0,0,0,0,0,0,0,0,0,0,0,0,0,0,0,0,0,0,0,0,0,0,0,0,0,0,0~
,0,0,0,BG23,0,0,0,0,0)';$S;
    'VSS461':'(0,0,0,0,0,0,0,0,0,0,0,0,0,0,0,0,0,0,0,0,0,0,0,0,0,0,0,0,0,0,0,0,0~
,0,0,0,BG21,0,0,0,0,0)';$S;
    'VSS460':'(0,0,0,0,0,0,0,0,0,0,0,0,0,0,0,0,0,0,0,0,0,0,0,0,0,0,0,0,0,0,0,0,0~
,0,0,0,BG17,0,0,0,0,0)';$S;
    'VSS459':'(0,0,0,0,0,0,0,0,0,0,0,0,0,0,0,0,0,0,0,0,0,0,0,0,0,0,0,0,0,0,0,0,0~
,0,0,0,BG13,0,0,0,0,0)';$S;
    'VSS458':'(0,0,0,0,0,0,0,0,0,0,0,0,0,0,0,0,0,0,0,0,0,0,0,0,0,0,0,0,0,0,0,0,0~
,0,0,0,BG1,0,0,0,0,0)';$S;
    'VSS457':'(0,0,0,0,0,0,0,0,0,0,0,0,0,0,0,0,0,0,0,0,0,0,0,0,0,0,0,0,0,0,0,0,0~
,0,0,0,BF83,0,0,0,0,0)';$S;
    'VSS456':'(0,0,0,0,0,0,0,0,0,0,0,0,0,0,0,0,0,0,0,0,0,0,0,0,0,0,0,0,0,0,0,0,0~
,0,0,0,BF8,0,0,0,0,0)';$S;
    'VSS455':'(0,0,0,0,0,0,0,0,0,0,0,0,0,0,0,0,0,0,0,0,0,0,0,0,0,0,0,0,0,0,0,0,0~
,0,0,0,BF79,0,0,0,0,0)';$S;
    'VSS454':'(0,0,0,0,0,0,0,0,0,0,0,0,0,0,0,0,0,0,0,0,0,0,0,0,0,0,0,0,0,0,0,0,0~
,0,0,0,BF75,0,0,0,0,0)';$S;
    'VSS453':'(0,0,0,0,0,0,0,0,0,0,0,0,0,0,0,0,0,0,0,0,0,0,0,0,0,0,0,0,0,0,0,0,0~
,0,0,0,BF73,0,0,0,0,0)';$S;
    'VSS452':'(0,0,0,0,0,0,0,0,0,0,0,0,0,0,0,0,0,0,0,0,0,0,0,0,0,0,0,0,0,0,0,0,0~
,0,0,0,BF63,0,0,0,0,0)';$S;
    'VSS451':'(0,0,0,0,0,0,0,0,0,0,0,0,0,0,0,0,0,0,0,0,0,0,0,0,0,0,0,0,0,0,0,0,0~
,0,0,0,BF61,0,0,0,0,0)';$S;
    'VSS450':'(0,0,0,0,0,0,0,0,0,0,0,0,0,0,0,0,0,0,0,0,0,0,0,0,0,0,0,0,0,0,0,0,0~
,0,0,0,BF4,0,0,0,0,0)';$S;
    'VSS449':'(0,0,0,0,0,0,0,0,0,0,0,0,0,0,0,0,0,0,0,0,0,0,0,0,0,0,0,0,0,0,0,0,0~
,0,0,0,BF20,0,0,0,0,0)';$S;
    'VSS448':'(0,0,0,0,0,0,0,0,0,0,0,0,0,0,0,0,0,0,0,0,0,0,0,0,0,0,0,0,0,0,0,0,0~
,0,0,0,BF16,0,0,0,0,0)';$S;
    'VSS447':'(0,0,0,0,0,0,0,0,0,0,0,0,0,0,0,0,0,0,0,0,0,0,0,0,0,0,0,0,0,0,0,0,0~
,0,0,0,BF12,0,0,0,0,0)';$S;
    'VSS446':'(0,0,0,0,0,0,0,0,0,0,0,0,0,0,0,0,0,0,0,0,0,0,0,0,0,0,0,0,0,0,0,0,0~
,0,0,0,BE84,0,0,0,0,0)';$S;
    'VSS445':'(0,0,0,0,0,0,0,0,0,0,0,0,0,0,0,0,0,0,0,0,0,0,0,0,0,0,0,0,0,0,0,0,0~
,0,0,0,BE78,0,0,0,0,0)';$S;
    'VSS444':'(0,0,0,0,0,0,0,0,0,0,0,0,0,0,0,0,0,0,0,0,0,0,0,0,0,0,0,0,0,0,0,0,0~
,0,0,0,BE76,0,0,0,0,0)';$S;
    'VSS443':'(0,0,0,0,0,0,0,0,0,0,0,0,0,0,0,0,0,0,0,0,0,0,0,0,0,0,0,0,0,0,0,0,0~
,0,0,0,BE74,0,0,0,0,0)';$S;
    'VSS442':'(0,0,0,0,0,0,0,0,0,0,0,0,0,0,0,0,0,0,0,0,0,0,0,0,0,0,0,0,0,0,0,0,0~
,0,0,0,BE68,0,0,0,0,0)';$S;
    'VSS441':'(0,0,0,0,0,0,0,0,0,0,0,0,0,0,0,0,0,0,0,0,0,0,0,0,0,0,0,0,0,0,0,0,0~
,0,0,0,BE66,0,0,0,0,0)';$S;
    'VSS440':'(0,0,0,0,0,0,0,0,0,0,0,0,0,0,0,0,0,0,0,0,0,0,0,0,0,0,0,0,0,0,0,0,0~
,0,0,0,BE64,0,0,0,0,0)';$S;
    'VSS439':'(0,0,0,0,0,0,0,0,0,0,0,0,0,0,0,0,0,0,0,0,0,0,0,0,0,0,0,0,0,0,0,0,0~
,0,0,0,BD89,0,0,0,0,0)';$S;
    'VSS437':'(0,0,0,0,0,0,0,0,0,0,0,0,0,0,0,0,0,0,0,0,0,0,0,0,0,0,0,0,0,0,0,0,0~
,0,0,0,BD85,0,0,0,0,0)';$S;
    'VSS435':'(0,0,0,0,0,0,0,0,0,0,0,0,0,0,0,0,0,0,0,0,0,0,0,0,0,0,0,0,0,0,0,0,0~
,0,0,0,BD81,0,0,0,0,0)';$S;
    'VSS434':'(0,0,0,0,0,0,0,0,0,0,0,0,0,0,0,0,0,0,0,0,0,0,0,0,0,0,0,0,0,0,0,0,0~
,0,0,0,BD8,0,0,0,0,0)';$S;
    'VSS433':'(0,0,0,0,0,0,0,0,0,0,0,0,0,0,0,0,0,0,0,0,0,0,0,0,0,0,0,0,0,0,0,0,0~
,0,0,0,BD4,0,0,0,0,0)';$S;
    'VSS432':'(0,0,0,0,0,0,0,0,0,0,0,0,0,0,0,0,0,0,0,0,0,0,0,0,0,0,0,0,0,0,0,0,0~
,0,0,0,BD20,0,0,0,0,0)';$S;
    'VSS431':'(0,0,0,0,0,0,0,0,0,0,0,0,0,0,0,0,0,0,0,0,0,0,0,0,0,0,0,0,0,0,0,0,0~
,0,0,0,BD16,0,0,0,0,0)';$S;
    'VSS430':'(0,0,0,0,0,0,0,0,0,0,0,0,0,0,0,0,0,0,0,0,0,0,0,0,0,0,0,0,0,0,0,0,0~
,0,0,0,BD12,0,0,0,0,0)';$S;
    'VSS429':'(0,0,0,0,0,0,0,0,0,0,0,0,0,0,0,0,0,0,0,0,0,0,0,0,0,0,0,0,0,0,0,0,0~
,0,0,0,BC9,0,0,0,0,0)';$S;
    'VSS428':'(0,0,0,0,0,0,0,0,0,0,0,0,0,0,0,0,0,0,0,0,0,0,0,0,0,0,0,0,0,0,0,0,0~
,0,0,0,BC88,0,0,0,0,0)';$S;
    'VSS427':'(0,0,0,0,0,0,0,0,0,0,0,0,0,0,0,0,0,0,0,0,0,0,0,0,0,0,0,0,0,0,0,0,0~
,0,0,0,BC86,0,0,0,0,0)';$S;
    'VSS426':'(0,0,0,0,0,0,0,0,0,0,0,0,0,0,0,0,0,0,0,0,0,0,0,0,0,0,0,0,0,0,0,0,0~
,0,0,0,BC84,0,0,0,0,0)';$S;
    'VSS425':'(0,0,0,0,0,0,0,0,0,0,0,0,0,0,0,0,0,0,0,0,0,0,0,0,0,0,0,0,0,0,0,0,0~
,0,0,0,BC78,0,0,0,0,0)';$S;
    'VSS424':'(0,0,0,0,0,0,0,0,0,0,0,0,0,0,0,0,0,0,0,0,0,0,0,0,0,0,0,0,0,0,0,0,0~
,0,0,0,BC76,0,0,0,0,0)';$S;
    'VSS423':'(0,0,0,0,0,0,0,0,0,0,0,0,0,0,0,0,0,0,0,0,0,0,0,0,0,0,0,0,0,0,0,0,0~
,0,0,0,BC72,0,0,0,0,0)';$S;
    'VSS422':'(0,0,0,0,0,0,0,0,0,0,0,0,0,0,0,0,0,0,0,0,0,0,0,0,0,0,0,0,0,0,0,0,0~
,0,0,0,BC66,0,0,0,0,0)';$S;
    'VSS421':'(0,0,0,0,0,0,0,0,0,0,0,0,0,0,0,0,0,0,0,0,0,0,0,0,0,0,0,0,0,0,0,0,0~
,0,0,0,BC62,0,0,0,0,0)';$S;
    'VSS420':'(0,0,0,0,0,0,0,0,0,0,0,0,0,0,0,0,0,0,0,0,0,0,0,0,0,0,0,0,0,0,0,0,0~
,0,0,0,BC5,0,0,0,0,0)';$S;
    'VSS419':'(0,0,0,0,0,0,0,0,0,0,0,0,0,0,0,0,0,0,0,0,0,0,0,0,0,0,0,0,0,0,0,0,0~
,0,0,0,BC17,0,0,0,0,0)';$S;
    'VSS418':'(0,0,0,0,0,0,0,0,0,0,0,0,0,0,0,0,0,0,0,0,0,0,0,0,0,0,0,0,0,0,0,0,0~
,0,0,0,BC13,0,0,0,0,0)';$S;
    'VSS417':'(0,0,0,0,0,0,0,0,0,0,0,0,0,0,0,0,0,0,0,0,0,0,0,0,0,0,0,0,0,0,0,0,0~
,0,0,0,BC1,0,0,0,0,0)';$S;
    'VSS416':'(0,0,0,0,0,0,0,0,0,0,0,0,0,0,0,0,0,0,0,0,0,0,0,0,0,0,0,0,0,0,0,0,0~
,0,0,0,BB91,0,0,0,0,0)';$S;
    'VSS415':'(0,0,0,0,0,0,0,0,0,0,0,0,0,0,0,0,0,0,0,0,0,0,0,0,0,0,0,0,0,0,0,0,0~
,0,0,0,BB87,0,0,0,0,0)';$S;
    'VSS414':'(0,0,0,0,0,0,0,0,0,0,0,0,0,0,0,0,0,0,0,0,0,0,0,0,0,0,0,0,0,0,0,0,0~
,0,0,0,BB83,0,0,0,0,0)';$S;
    'VSS413':'(0,0,0,0,0,0,0,0,0,0,0,0,0,0,0,0,0,0,0,0,0,0,0,0,0,0,0,0,0,0,0,0,0~
,0,0,0,BB8,0,0,0,0,0)';$S;
    'VSS412':'(0,0,0,0,0,0,0,0,0,0,0,0,0,0,0,0,0,0,0,0,0,0,0,0,0,0,0,0,0,0,0,0,0~
,0,0,0,BB79,0,0,0,0,0)';$S;
    'VSS411':'(0,0,0,0,0,0,0,0,0,0,0,0,0,0,0,0,0,0,0,0,0,0,0,0,0,0,0,0,0,0,0,0,0~
,0,0,0,BB77,0,0,0,0,0)';$S;
    'VSS410':'(0,0,0,0,0,0,0,0,0,0,0,0,0,0,0,0,0,0,0,0,0,0,0,0,0,0,0,0,0,0,0,0,0~
,0,0,0,BB71,0,0,0,0,0)';$S;
    'VSS409':'(0,0,0,0,0,0,0,0,0,0,0,0,0,0,0,0,0,0,0,0,0,0,0,0,0,0,0,0,0,0,0,0,0~
,0,0,0,BB69,0,0,0,0,0)';$S;
    'VSS408':'(0,0,0,0,0,0,0,0,0,0,0,0,0,0,0,0,0,0,0,0,0,0,0,0,0,0,0,0,0,0,0,0,0~
,0,0,0,BB63,0,0,0,0,0)';$S;
    'VSS407':'(0,0,0,0,0,0,0,0,0,0,0,0,0,0,0,0,0,0,0,0,0,0,0,0,0,0,0,0,0,0,0,0,0~
,0,0,0,BB4,0,0,0,0,0)';$S;
    'VSS406':'(0,0,0,0,0,0,0,0,0,0,0,0,0,0,0,0,0,0,0,0,0,0,0,0,0,0,0,0,0,0,0,0,0~
,0,0,0,BB26,0,0,0,0,0)';$S;
    'VSS405':'(0,0,0,0,0,0,0,0,0,0,0,0,0,0,0,0,0,0,0,0,0,0,0,0,0,0,0,0,0,0,0,0,0~
,0,0,0,BB24,0,0,0,0,0)';$S;
    'VSS404':'(0,0,0,0,0,0,0,0,0,0,0,0,0,0,0,0,0,0,0,0,0,0,0,0,0,0,0,0,0,0,0,0,0~
,0,0,0,BB22,0,0,0,0,0)';$S;
    'VSS403':'(0,0,0,0,0,0,0,0,0,0,0,0,0,0,0,0,0,0,0,0,0,0,0,0,0,0,0,0,0,0,0,0,0~
,0,0,0,BB20,0,0,0,0,0)';$S;
    'VSS402':'(0,0,0,0,0,0,0,0,0,0,0,0,0,0,0,0,0,0,0,0,0,0,0,0,0,0,0,0,0,0,0,0,0~
,0,0,0,BB16,0,0,0,0,0)';$S;
    'VSS401':'(0,0,0,0,0,0,0,0,0,0,0,0,0,0,0,0,0,0,0,0,0,0,0,0,0,0,0,0,0,0,0,0,0~
,0,0,0,BB12,0,0,0,0,0)';$S;
    'VSS400':'(0,0,0,0,0,0,0,0,0,0,0,0,0,0,0,0,0,0,0,0,0,0,0,0,0,0,0,0,0,0,0,0,0~
,0,0,0,BB10,0,0,0,0,0)';$S;
    'VSS399':'(0,0,0,0,0,0,0,0,0,0,0,0,0,0,0,0,0,0,0,0,0,0,0,0,0,0,0,0,0,0,0,0,0~
,0,0,0,BA88,0,0,0,0,0)';$S;
    'VSS398':'(0,0,0,0,0,0,0,0,0,0,0,0,0,0,0,0,0,0,0,0,0,0,0,0,0,0,0,0,0,0,0,0,0~
,0,0,0,BA84,0,0,0,0,0)';$S;
    'VSS397':'(0,0,0,0,0,0,0,0,0,0,0,0,0,0,0,0,0,0,0,0,0,0,0,0,0,0,0,0,0,0,0,0,0~
,0,0,0,BA74,0,0,0,0,0)';$S;
    'VSS395':'(0,0,0,0,0,0,0,0,0,0,0,0,0,0,0,0,0,0,0,0,0,0,0,0,0,0,0,0,0,0,0,0,0~
,0,0,0,BA64,0,0,0,0,0)';$S;
    'VSS394':'(0,0,0,0,0,0,0,0,0,0,0,0,0,0,0,0,0,0,0,0,0,0,0,0,0,0,0,0,0,0,0,0,0~
,0,0,0,BA60,0,0,0,0,0)';$S;
    'VSS393':'(0,0,0,0,0,0,0,0,0,0,0,0,0,0,0,0,0,0,0,0,0,0,0,0,0,0,0,0,0,0,0,0,0~
,0,0,0,BA17,0,0,0,0,0)';$S;
    'VSS377':'(0,0,0,0,0,0,0,0,0,0,0,0,0,0,0,0,0,0,0,0,0,0,0,0,0,0,0,0,0,0,0,0,0~
,0,0,0,AY83,0,0,0,0,0)';$S;
    'VSS376':'(0,0,0,0,0,0,0,0,0,0,0,0,0,0,0,0,0,0,0,0,0,0,0,0,0,0,0,0,0,0,0,0,0~
,0,0,0,AY81,0,0,0,0,0)';$S;
    'VSS375':'(0,0,0,0,0,0,0,0,0,0,0,0,0,0,0,0,0,0,0,0,0,0,0,0,0,0,0,0,0,0,0,0,0~
,0,0,0,AY8,0,0,0,0,0)';$S;
    'VSS374':'(0,0,0,0,0,0,0,0,0,0,0,0,0,0,0,0,0,0,0,0,0,0,0,0,0,0,0,0,0,0,0,0,0~
,0,0,0,AY79,0,0,0,0,0)';$S;
    'VSS373':'(0,0,0,0,0,0,0,0,0,0,0,0,0,0,0,0,0,0,0,0,0,0,0,0,0,0,0,0,0,0,0,0,0~
,0,0,0,AY77,0,0,0,0,0)';$S;
    'VSS372':'(0,0,0,0,0,0,0,0,0,0,0,0,0,0,0,0,0,0,0,0,0,0,0,0,0,0,0,0,0,0,0,0,0~
,0,0,0,AY71,0,0,0,0,0)';$S;
    'VSS371':'(0,0,0,0,0,0,0,0,0,0,0,0,0,0,0,0,0,0,0,0,0,0,0,0,0,0,0,0,0,0,0,0,0~
,0,0,0,AY4,0,0,0,0,0)';$S;
    'VSS370':'(0,0,0,0,0,0,0,0,0,0,0,0,0,0,0,0,0,0,0,0,0,0,0,0,0,0,0,0,0,0,0,0,0~
,0,0,0,AY16,0,0,0,0,0)';$S;
    'VSS369':'(0,0,0,0,0,0,0,0,0,0,0,0,0,0,0,0,0,0,0,0,0,0,0,0,0,0,0,0,0,0,0,0,0~
,0,0,0,AY12,0,0,0,0,0)';$S;
    'VSS367':'(0,0,0,0,0,0,0,0,0,0,0,0,0,0,0,0,0,0,0,0,0,0,0,0,0,0,0,0,0,0,0,0,0~
,0,0,0,AW88,0,0,0,0,0)';$S;
    'VSS366':'(0,0,0,0,0,0,0,0,0,0,0,0,0,0,0,0,0,0,0,0,0,0,0,0,0,0,0,0,0,0,0,0,0~
,0,0,0,AW84,0,0,0,0,0)';$S;
    'VSS365':'(0,0,0,0,0,0,0,0,0,0,0,0,0,0,0,0,0,0,0,0,0,0,0,0,0,0,0,0,0,0,0,0,0~
,0,0,0,AW82,0,0,0,0,0)';$S;
    'VSS364':'(0,0,0,0,0,0,0,0,0,0,0,0,0,0,0,0,0,0,0,0,0,0,0,0,0,0,0,0,0,0,0,0,0~
,0,0,0,AW80,0,0,0,0,0)';$S;
    'VSS363':'(0,0,0,0,0,0,0,0,0,0,0,0,0,0,0,0,0,0,0,0,0,0,0,0,0,0,0,0,0,0,0,0,0~
,0,0,0,AW72,0,0,0,0,0)';$S;
    'VSS362':'(0,0,0,0,0,0,0,0,0,0,0,0,0,0,0,0,0,0,0,0,0,0,0,0,0,0,0,0,0,0,0,0,0~
,0,0,0,AW68,0,0,0,0,0)';$S;
    'VSS361':'(0,0,0,0,0,0,0,0,0,0,0,0,0,0,0,0,0,0,0,0,0,0,0,0,0,0,0,0,0,0,0,0,0~
,0,0,0,AW66,0,0,0,0,0)';$S;
    'VSS360':'(0,0,0,0,0,0,0,0,0,0,0,0,0,0,0,0,0,0,0,0,0,0,0,0,0,0,0,0,0,0,0,0,0~
,0,0,0,AW62,0,0,0,0,0)';$S;
    'VSS358':'(0,0,0,0,0,0,0,0,0,0,0,0,0,0,0,0,0,0,0,0,0,0,0,0,0,0,0,0,0,0,0,0,0~
,0,0,0,AW25,0,0,0,0,0)';$S;
    'VSS357':'(0,0,0,0,0,0,0,0,0,0,0,0,0,0,0,0,0,0,0,0,0,0,0,0,0,0,0,0,0,0,0,0,0~
,0,0,0,AW23,0,0,0,0,0)';$S;
    'VSS356':'(0,0,0,0,0,0,0,0,0,0,0,0,0,0,0,0,0,0,0,0,0,0,0,0,0,0,0,0,0,0,0,0,0~
,0,0,0,AW21,0,0,0,0,0)';$S;
    'VSS0':'(0,0,0,0,0,0,0,0,0,0,0,0,0,0,0,0,0,0,0,0,0,0,0,0,0,0,0,0,0,0,0,0,0,0~
,0,0,BR5,0,0,0,0,0)';$S;
    'VSS368':'(0,0,0,0,0,0,0,0,0,0,0,0,0,0,0,0,0,0,0,0,0,0,0,0,0,0,0,0,0,0,0,0,0~
,0,0,0,0,AW9,0,0,0,0)';$S;
    'VSS359':'(0,0,0,0,0,0,0,0,0,0,0,0,0,0,0,0,0,0,0,0,0,0,0,0,0,0,0,0,0,0,0,0,0~
,0,0,0,0,AW5,0,0,0,0)';$S;
    'VSS355':'(0,0,0,0,0,0,0,0,0,0,0,0,0,0,0,0,0,0,0,0,0,0,0,0,0,0,0,0,0,0,0,0,0~
,0,0,0,0,AW13,0,0,0,0)';$S;
    'VSS354':'(0,0,0,0,0,0,0,0,0,0,0,0,0,0,0,0,0,0,0,0,0,0,0,0,0,0,0,0,0,0,0,0,0~
,0,0,0,0,AW1,0,0,0,0)';$S;
    'VSS353':'(0,0,0,0,0,0,0,0,0,0,0,0,0,0,0,0,0,0,0,0,0,0,0,0,0,0,0,0,0,0,0,0,0~
,0,0,0,0,AV91,0,0,0,0)';$S;
    'VSS352':'(0,0,0,0,0,0,0,0,0,0,0,0,0,0,0,0,0,0,0,0,0,0,0,0,0,0,0,0,0,0,0,0,0~
,0,0,0,0,AV87,0,0,0,0)';$S;
    'VSS351':'(0,0,0,0,0,0,0,0,0,0,0,0,0,0,0,0,0,0,0,0,0,0,0,0,0,0,0,0,0,0,0,0,0~
,0,0,0,0,AV8,0,0,0,0)';$S;
    'VSS350':'(0,0,0,0,0,0,0,0,0,0,0,0,0,0,0,0,0,0,0,0,0,0,0,0,0,0,0,0,0,0,0,0,0~
,0,0,0,0,AV77,0,0,0,0)';$S;
    'VSS349':'(0,0,0,0,0,0,0,0,0,0,0,0,0,0,0,0,0,0,0,0,0,0,0,0,0,0,0,0,0,0,0,0,0~
,0,0,0,0,AV4,0,0,0,0)';$S;
    'VSS348':'(0,0,0,0,0,0,0,0,0,0,0,0,0,0,0,0,0,0,0,0,0,0,0,0,0,0,0,0,0,0,0,0,0~
,0,0,0,0,AV16,0,0,0,0)';$S;
    'VSS347':'(0,0,0,0,0,0,0,0,0,0,0,0,0,0,0,0,0,0,0,0,0,0,0,0,0,0,0,0,0,0,0,0,0~
,0,0,0,0,AV12,0,0,0,0)';$S;
    'VSS346':'(0,0,0,0,0,0,0,0,0,0,0,0,0,0,0,0,0,0,0,0,0,0,0,0,0,0,0,0,0,0,0,0,0~
,0,0,0,0,AU88,0,0,0,0)';$S;
    'VSS345':'(0,0,0,0,0,0,0,0,0,0,0,0,0,0,0,0,0,0,0,0,0,0,0,0,0,0,0,0,0,0,0,0,0~
,0,0,0,0,AU84,0,0,0,0)';$S;
    'VSS344':'(0,0,0,0,0,0,0,0,0,0,0,0,0,0,0,0,0,0,0,0,0,0,0,0,0,0,0,0,0,0,0,0,0~
,0,0,0,0,AU80,0,0,0,0)';$S;
    'VSS343':'(0,0,0,0,0,0,0,0,0,0,0,0,0,0,0,0,0,0,0,0,0,0,0,0,0,0,0,0,0,0,0,0,0~
,0,0,0,0,AU76,0,0,0,0)';$S;
    'VSS342':'(0,0,0,0,0,0,0,0,0,0,0,0,0,0,0,0,0,0,0,0,0,0,0,0,0,0,0,0,0,0,0,0,0~
,0,0,0,0,AU74,0,0,0,0)';$S;
    'VSS341':'(0,0,0,0,0,0,0,0,0,0,0,0,0,0,0,0,0,0,0,0,0,0,0,0,0,0,0,0,0,0,0,0,0~
,0,0,0,0,AU72,0,0,0,0)';$S;
    'VSS340':'(0,0,0,0,0,0,0,0,0,0,0,0,0,0,0,0,0,0,0,0,0,0,0,0,0,0,0,0,0,0,0,0,0~
,0,0,0,0,AU70,0,0,0,0)';$S;
    'VSS339':'(0,0,0,0,0,0,0,0,0,0,0,0,0,0,0,0,0,0,0,0,0,0,0,0,0,0,0,0,0,0,0,0,0~
,0,0,0,0,AU48,0,0,0,0)';$S;
    'VSS338':'(0,0,0,0,0,0,0,0,0,0,0,0,0,0,0,0,0,0,0,0,0,0,0,0,0,0,0,0,0,0,0,0,0~
,0,0,0,0,AU45,0,0,0,0)';$S;
    'VSS337':'(0,0,0,0,0,0,0,0,0,0,0,0,0,0,0,0,0,0,0,0,0,0,0,0,0,0,0,0,0,0,0,0,0~
,0,0,0,0,AU41,0,0,0,0)';$S;
    'VSS336':'(0,0,0,0,0,0,0,0,0,0,0,0,0,0,0,0,0,0,0,0,0,0,0,0,0,0,0,0,0,0,0,0,0~
,0,0,0,0,AU39,0,0,0,0)';$S;
    'VSS335':'(0,0,0,0,0,0,0,0,0,0,0,0,0,0,0,0,0,0,0,0,0,0,0,0,0,0,0,0,0,0,0,0,0~
,0,0,0,0,AU37,0,0,0,0)';$S;
    'VSS334':'(0,0,0,0,0,0,0,0,0,0,0,0,0,0,0,0,0,0,0,0,0,0,0,0,0,0,0,0,0,0,0,0,0~
,0,0,0,0,AU31,0,0,0,0)';$S;
    'VSS333':'(0,0,0,0,0,0,0,0,0,0,0,0,0,0,0,0,0,0,0,0,0,0,0,0,0,0,0,0,0,0,0,0,0~
,0,0,0,0,AU27,0,0,0,0)';$S;
    'VSS332':'(0,0,0,0,0,0,0,0,0,0,0,0,0,0,0,0,0,0,0,0,0,0,0,0,0,0,0,0,0,0,0,0,0~
,0,0,0,0,AT8,0,0,0,0)';$S;
    'VSS331':'(0,0,0,0,0,0,0,0,0,0,0,0,0,0,0,0,0,0,0,0,0,0,0,0,0,0,0,0,0,0,0,0,0~
,0,0,0,0,AT79,0,0,0,0)';$S;
    'VSS330':'(0,0,0,0,0,0,0,0,0,0,0,0,0,0,0,0,0,0,0,0,0,0,0,0,0,0,0,0,0,0,0,0,0~
,0,0,0,0,AT77,0,0,0,0)';$S;
    'VSS329':'(0,0,0,0,0,0,0,0,0,0,0,0,0,0,0,0,0,0,0,0,0,0,0,0,0,0,0,0,0,0,0,0,0~
,0,0,0,0,AT75,0,0,0,0)';$S;
    'VSS328':'(0,0,0,0,0,0,0,0,0,0,0,0,0,0,0,0,0,0,0,0,0,0,0,0,0,0,0,0,0,0,0,0,0~
,0,0,0,0,AT71,0,0,0,0)';$S;
    'VSS327':'(0,0,0,0,0,0,0,0,0,0,0,0,0,0,0,0,0,0,0,0,0,0,0,0,0,0,0,0,0,0,0,0,0~
,0,0,0,0,AT69,0,0,0,0)';$S;
    'VSS326':'(0,0,0,0,0,0,0,0,0,0,0,0,0,0,0,0,0,0,0,0,0,0,0,0,0,0,0,0,0,0,0,0,0~
,0,0,0,0,AT65,0,0,0,0)';$S;
    'VSS325':'(0,0,0,0,0,0,0,0,0,0,0,0,0,0,0,0,0,0,0,0,0,0,0,0,0,0,0,0,0,0,0,0,0~
,0,0,0,0,AT63,0,0,0,0)';$S;
    'VSS324':'(0,0,0,0,0,0,0,0,0,0,0,0,0,0,0,0,0,0,0,0,0,0,0,0,0,0,0,0,0,0,0,0,0~
,0,0,0,0,AT59,0,0,0,0)';$S;
    'VSS323':'(0,0,0,0,0,0,0,0,0,0,0,0,0,0,0,0,0,0,0,0,0,0,0,0,0,0,0,0,0,0,0,0,0~
,0,0,0,0,AT57,0,0,0,0)';$S;
    'VSS322':'(0,0,0,0,0,0,0,0,0,0,0,0,0,0,0,0,0,0,0,0,0,0,0,0,0,0,0,0,0,0,0,0,0~
,0,0,0,0,AT53,0,0,0,0)';$S;
    'VSS321':'(0,0,0,0,0,0,0,0,0,0,0,0,0,0,0,0,0,0,0,0,0,0,0,0,0,0,0,0,0,0,0,0,0~
,0,0,0,0,AT51,0,0,0,0)';$S;
    'VSS320':'(0,0,0,0,0,0,0,0,0,0,0,0,0,0,0,0,0,0,0,0,0,0,0,0,0,0,0,0,0,0,0,0,0~
,0,0,0,0,AT44,0,0,0,0)';$S;
    'VSS319':'(0,0,0,0,0,0,0,0,0,0,0,0,0,0,0,0,0,0,0,0,0,0,0,0,0,0,0,0,0,0,0,0,0~
,0,0,0,0,AT40,0,0,0,0)';$S;
    'VSS318':'(0,0,0,0,0,0,0,0,0,0,0,0,0,0,0,0,0,0,0,0,0,0,0,0,0,0,0,0,0,0,0,0,0~
,0,0,0,0,AT4,0,0,0,0)';$S;
    'VSS317':'(0,0,0,0,0,0,0,0,0,0,0,0,0,0,0,0,0,0,0,0,0,0,0,0,0,0,0,0,0,0,0,0,0~
,0,0,0,0,AT38,0,0,0,0)';$S;
    'VSS316':'(0,0,0,0,0,0,0,0,0,0,0,0,0,0,0,0,0,0,0,0,0,0,0,0,0,0,0,0,0,0,0,0,0~
,0,0,0,0,AT34,0,0,0,0)';$S;
    'VSS315':'(0,0,0,0,0,0,0,0,0,0,0,0,0,0,0,0,0,0,0,0,0,0,0,0,0,0,0,0,0,0,0,0,0~
,0,0,0,0,AT32,0,0,0,0)';$S;
    'VSS314':'(0,0,0,0,0,0,0,0,0,0,0,0,0,0,0,0,0,0,0,0,0,0,0,0,0,0,0,0,0,0,0,0,0~
,0,0,0,0,AT28,0,0,0,0)';$S;
    'VSS313':'(0,0,0,0,0,0,0,0,0,0,0,0,0,0,0,0,0,0,0,0,0,0,0,0,0,0,0,0,0,0,0,0,0~
,0,0,0,0,AT26,0,0,0,0)';$S;
    'VSS312':'(0,0,0,0,0,0,0,0,0,0,0,0,0,0,0,0,0,0,0,0,0,0,0,0,0,0,0,0,0,0,0,0,0~
,0,0,0,0,AT22,0,0,0,0)';$S;
    'VSS311':'(0,0,0,0,0,0,0,0,0,0,0,0,0,0,0,0,0,0,0,0,0,0,0,0,0,0,0,0,0,0,0,0,0~
,0,0,0,0,AT20,0,0,0,0)';$S;
    'VSS310':'(0,0,0,0,0,0,0,0,0,0,0,0,0,0,0,0,0,0,0,0,0,0,0,0,0,0,0,0,0,0,0,0,0~
,0,0,0,0,AT16,0,0,0,0)';$S;
    'VSS309':'(0,0,0,0,0,0,0,0,0,0,0,0,0,0,0,0,0,0,0,0,0,0,0,0,0,0,0,0,0,0,0,0,0~
,0,0,0,0,AT12,0,0,0,0)';$S;
    'VSS308':'(0,0,0,0,0,0,0,0,0,0,0,0,0,0,0,0,0,0,0,0,0,0,0,0,0,0,0,0,0,0,0,0,0~
,0,0,0,0,AR9,0,0,0,0)';$S;
    'VSS307':'(0,0,0,0,0,0,0,0,0,0,0,0,0,0,0,0,0,0,0,0,0,0,0,0,0,0,0,0,0,0,0,0,0~
,0,0,0,0,AR88,0,0,0,0)';$S;
    'VSS306':'(0,0,0,0,0,0,0,0,0,0,0,0,0,0,0,0,0,0,0,0,0,0,0,0,0,0,0,0,0,0,0,0,0~
,0,0,0,0,AR84,0,0,0,0)';$S;
    'VSS305':'(0,0,0,0,0,0,0,0,0,0,0,0,0,0,0,0,0,0,0,0,0,0,0,0,0,0,0,0,0,0,0,0,0~
,0,0,0,0,AR82,0,0,0,0)';$S;
    'VSS304':'(0,0,0,0,0,0,0,0,0,0,0,0,0,0,0,0,0,0,0,0,0,0,0,0,0,0,0,0,0,0,0,0,0~
,0,0,0,0,AR78,0,0,0,0)';$S;
    'VSS303':'(0,0,0,0,0,0,0,0,0,0,0,0,0,0,0,0,0,0,0,0,0,0,0,0,0,0,0,0,0,0,0,0,0~
,0,0,0,0,AR74,0,0,0,0)';$S;
    'VSS302':'(0,0,0,0,0,0,0,0,0,0,0,0,0,0,0,0,0,0,0,0,0,0,0,0,0,0,0,0,0,0,0,0,0~
,0,0,0,0,AR72,0,0,0,0)';$S;
    'VSS301':'(0,0,0,0,0,0,0,0,0,0,0,0,0,0,0,0,0,0,0,0,0,0,0,0,0,0,0,0,0,0,0,0,0~
,0,0,0,0,AR68,0,0,0,0)';$S;
    'VSS300':'(0,0,0,0,0,0,0,0,0,0,0,0,0,0,0,0,0,0,0,0,0,0,0,0,0,0,0,0,0,0,0,0,0~
,0,0,0,0,AR66,0,0,0,0)';$S;
    'VSS299':'(0,0,0,0,0,0,0,0,0,0,0,0,0,0,0,0,0,0,0,0,0,0,0,0,0,0,0,0,0,0,0,0,0~
,0,0,0,0,AR62,0,0,0,0)';$S;
    'VSS298':'(0,0,0,0,0,0,0,0,0,0,0,0,0,0,0,0,0,0,0,0,0,0,0,0,0,0,0,0,0,0,0,0,0~
,0,0,0,0,AR60,0,0,0,0)';$S;
    'VSS297':'(0,0,0,0,0,0,0,0,0,0,0,0,0,0,0,0,0,0,0,0,0,0,0,0,0,0,0,0,0,0,0,0,0~
,0,0,0,0,AR56,0,0,0,0)';$S;
    'VSS296':'(0,0,0,0,0,0,0,0,0,0,0,0,0,0,0,0,0,0,0,0,0,0,0,0,0,0,0,0,0,0,0,0,0~
,0,0,0,0,AR54,0,0,0,0)';$S;
    'VSS295':'(0,0,0,0,0,0,0,0,0,0,0,0,0,0,0,0,0,0,0,0,0,0,0,0,0,0,0,0,0,0,0,0,0~
,0,0,0,0,AR50,0,0,0,0)';$S;
    'VSS294':'(0,0,0,0,0,0,0,0,0,0,0,0,0,0,0,0,0,0,0,0,0,0,0,0,0,0,0,0,0,0,0,0,0~
,0,0,0,0,AR5,0,0,0,0)';$S;
    'VSS293':'(0,0,0,0,0,0,0,0,0,0,0,0,0,0,0,0,0,0,0,0,0,0,0,0,0,0,0,0,0,0,0,0,0~
,0,0,0,0,AR48,0,0,0,0)';$S;
    'VSS292':'(0,0,0,0,0,0,0,0,0,0,0,0,0,0,0,0,0,0,0,0,0,0,0,0,0,0,0,0,0,0,0,0,0~
,0,0,0,0,AR43,0,0,0,0)';$S;
    'VSS291':'(0,0,0,0,0,0,0,0,0,0,0,0,0,0,0,0,0,0,0,0,0,0,0,0,0,0,0,0,0,0,0,0,0~
,0,0,0,0,AR41,0,0,0,0)';$S;
    'VSS290':'(0,0,0,0,0,0,0,0,0,0,0,0,0,0,0,0,0,0,0,0,0,0,0,0,0,0,0,0,0,0,0,0,0~
,0,0,0,0,AR37,0,0,0,0)';$S;
    'VSS289':'(0,0,0,0,0,0,0,0,0,0,0,0,0,0,0,0,0,0,0,0,0,0,0,0,0,0,0,0,0,0,0,0,0~
,0,0,0,0,AR35,0,0,0,0)';$S;
    'VSS288':'(0,0,0,0,0,0,0,0,0,0,0,0,0,0,0,0,0,0,0,0,0,0,0,0,0,0,0,0,0,0,0,0,0~
,0,0,0,0,AR31,0,0,0,0)';$S;
    'VSS287':'(0,0,0,0,0,0,0,0,0,0,0,0,0,0,0,0,0,0,0,0,0,0,0,0,0,0,0,0,0,0,0,0,0~
,0,0,0,0,AR29,0,0,0,0)';$S;
    'VSS286':'(0,0,0,0,0,0,0,0,0,0,0,0,0,0,0,0,0,0,0,0,0,0,0,0,0,0,0,0,0,0,0,0,0~
,0,0,0,0,AR25,0,0,0,0)';$S;
    'VSS285':'(0,0,0,0,0,0,0,0,0,0,0,0,0,0,0,0,0,0,0,0,0,0,0,0,0,0,0,0,0,0,0,0,0~
,0,0,0,0,AR23,0,0,0,0)';$S;
    'VSS284':'(0,0,0,0,0,0,0,0,0,0,0,0,0,0,0,0,0,0,0,0,0,0,0,0,0,0,0,0,0,0,0,0,0~
,0,0,0,0,AR19,0,0,0,0)';$S;
    'VSS283':'(0,0,0,0,0,0,0,0,0,0,0,0,0,0,0,0,0,0,0,0,0,0,0,0,0,0,0,0,0,0,0,0,0~
,0,0,0,0,AR13,0,0,0,0)';$S;
    'VSS282':'(0,0,0,0,0,0,0,0,0,0,0,0,0,0,0,0,0,0,0,0,0,0,0,0,0,0,0,0,0,0,0,0,0~
,0,0,0,0,AR1,0,0,0,0)';$S;
    'VSS281':'(0,0,0,0,0,0,0,0,0,0,0,0,0,0,0,0,0,0,0,0,0,0,0,0,0,0,0,0,0,0,0,0,0~
,0,0,0,0,AP91,0,0,0,0)';$S;
    'VSS280':'(0,0,0,0,0,0,0,0,0,0,0,0,0,0,0,0,0,0,0,0,0,0,0,0,0,0,0,0,0,0,0,0,0~
,0,0,0,0,AP87,0,0,0,0)';$S;
    'VSS279':'(0,0,0,0,0,0,0,0,0,0,0,0,0,0,0,0,0,0,0,0,0,0,0,0,0,0,0,0,0,0,0,0,0~
,0,0,0,0,AP83,0,0,0,0)';$S;
    'VSS278':'(0,0,0,0,0,0,0,0,0,0,0,0,0,0,0,0,0,0,0,0,0,0,0,0,0,0,0,0,0,0,0,0,0~
,0,0,0,0,AP8,0,0,0,0)';$S;
    'VSS277':'(0,0,0,0,0,0,0,0,0,0,0,0,0,0,0,0,0,0,0,0,0,0,0,0,0,0,0,0,0,0,0,0,0~
,0,0,0,0,AP79,0,0,0,0)';$S;
    'VSS276':'(0,0,0,0,0,0,0,0,0,0,0,0,0,0,0,0,0,0,0,0,0,0,0,0,0,0,0,0,0,0,0,0,0~
,0,0,0,0,AP73,0,0,0,0)';$S;
    'VSS275':'(0,0,0,0,0,0,0,0,0,0,0,0,0,0,0,0,0,0,0,0,0,0,0,0,0,0,0,0,0,0,0,0,0~
,0,0,0,0,AP67,0,0,0,0)';$S;
    'VSS274':'(0,0,0,0,0,0,0,0,0,0,0,0,0,0,0,0,0,0,0,0,0,0,0,0,0,0,0,0,0,0,0,0,0~
,0,0,0,0,AP61,0,0,0,0)';$S;
    'VSS273':'(0,0,0,0,0,0,0,0,0,0,0,0,0,0,0,0,0,0,0,0,0,0,0,0,0,0,0,0,0,0,0,0,0~
,0,0,0,0,AP55,0,0,0,0)';$S;
    'VSS272':'(0,0,0,0,0,0,0,0,0,0,0,0,0,0,0,0,0,0,0,0,0,0,0,0,0,0,0,0,0,0,0,0,0~
,0,0,0,0,AP49,0,0,0,0)';$S;
    'VSS271':'(0,0,0,0,0,0,0,0,0,0,0,0,0,0,0,0,0,0,0,0,0,0,0,0,0,0,0,0,0,0,0,0,0~
,0,0,0,0,AP42,0,0,0,0)';$S;
    'VSS270':'(0,0,0,0,0,0,0,0,0,0,0,0,0,0,0,0,0,0,0,0,0,0,0,0,0,0,0,0,0,0,0,0,0~
,0,0,0,0,AP4,0,0,0,0)';$S;
    'VSS269':'(0,0,0,0,0,0,0,0,0,0,0,0,0,0,0,0,0,0,0,0,0,0,0,0,0,0,0,0,0,0,0,0,0~
,0,0,0,0,AP36,0,0,0,0)';$S;
    'VSS268':'(0,0,0,0,0,0,0,0,0,0,0,0,0,0,0,0,0,0,0,0,0,0,0,0,0,0,0,0,0,0,0,0,0~
,0,0,0,0,AP30,0,0,0,0)';$S;
    'VSS267':'(0,0,0,0,0,0,0,0,0,0,0,0,0,0,0,0,0,0,0,0,0,0,0,0,0,0,0,0,0,0,0,0,0~
,0,0,0,0,AP24,0,0,0,0)';$S;
    'VSS266':'(0,0,0,0,0,0,0,0,0,0,0,0,0,0,0,0,0,0,0,0,0,0,0,0,0,0,0,0,0,0,0,0,0~
,0,0,0,0,AP18,0,0,0,0)';$S;
    'VSS265':'(0,0,0,0,0,0,0,0,0,0,0,0,0,0,0,0,0,0,0,0,0,0,0,0,0,0,0,0,0,0,0,0,0~
,0,0,0,0,AP16,0,0,0,0)';$S;
    'VSS264':'(0,0,0,0,0,0,0,0,0,0,0,0,0,0,0,0,0,0,0,0,0,0,0,0,0,0,0,0,0,0,0,0,0~
,0,0,0,0,AP12,0,0,0,0)';$S;
    'VSS263':'(0,0,0,0,0,0,0,0,0,0,0,0,0,0,0,0,0,0,0,0,0,0,0,0,0,0,0,0,0,0,0,0,0~
,0,0,0,0,AN88,0,0,0,0)';$S;
    'VSS262':'(0,0,0,0,0,0,0,0,0,0,0,0,0,0,0,0,0,0,0,0,0,0,0,0,0,0,0,0,0,0,0,0,0~
,0,0,0,0,AN84,0,0,0,0)';$S;
    'VSS261':'(0,0,0,0,0,0,0,0,0,0,0,0,0,0,0,0,0,0,0,0,0,0,0,0,0,0,0,0,0,0,0,0,0~
,0,0,0,0,AN52,0,0,0,0)';$S;
    'VSS260':'(0,0,0,0,0,0,0,0,0,0,0,0,0,0,0,0,0,0,0,0,0,0,0,0,0,0,0,0,0,0,0,0,0~
,0,0,0,0,AM8,0,0,0,0)';$S;
    'VSS259':'(0,0,0,0,0,0,0,0,0,0,0,0,0,0,0,0,0,0,0,0,0,0,0,0,0,0,0,0,0,0,0,0,0~
,0,0,0,0,AM77,0,0,0,0)';$S;
    'VSS258':'(0,0,0,0,0,0,0,0,0,0,0,0,0,0,0,0,0,0,0,0,0,0,0,0,0,0,0,0,0,0,0,0,0~
,0,0,0,0,AM75,0,0,0,0)';$S;
    'VSS257':'(0,0,0,0,0,0,0,0,0,0,0,0,0,0,0,0,0,0,0,0,0,0,0,0,0,0,0,0,0,0,0,0,0~
,0,0,0,0,AM73,0,0,0,0)';$S;
    'VSS256':'(0,0,0,0,0,0,0,0,0,0,0,0,0,0,0,0,0,0,0,0,0,0,0,0,0,0,0,0,0,0,0,0,0~
,0,0,0,0,AM71,0,0,0,0)';$S;
    'VSS255':'(0,0,0,0,0,0,0,0,0,0,0,0,0,0,0,0,0,0,0,0,0,0,0,0,0,0,0,0,0,0,0,0,0~
,0,0,0,0,AM69,0,0,0,0)';$S;
    'VSS254':'(0,0,0,0,0,0,0,0,0,0,0,0,0,0,0,0,0,0,0,0,0,0,0,0,0,0,0,0,0,0,0,0,0~
,0,0,0,0,AM67,0,0,0,0)';$S;
    'VSS253':'(0,0,0,0,0,0,0,0,0,0,0,0,0,0,0,0,0,0,0,0,0,0,0,0,0,0,0,0,0,0,0,0,0~
,0,0,0,0,AM65,0,0,0,0)';$S;
    'VSS252':'(0,0,0,0,0,0,0,0,0,0,0,0,0,0,0,0,0,0,0,0,0,0,0,0,0,0,0,0,0,0,0,0,0~
,0,0,0,0,AM63,0,0,0,0)';$S;
    'VSS251':'(0,0,0,0,0,0,0,0,0,0,0,0,0,0,0,0,0,0,0,0,0,0,0,0,0,0,0,0,0,0,0,0,0~
,0,0,0,0,AM61,0,0,0,0)';$S;
    'VSS250':'(0,0,0,0,0,0,0,0,0,0,0,0,0,0,0,0,0,0,0,0,0,0,0,0,0,0,0,0,0,0,0,0,0~
,0,0,0,0,AM59,0,0,0,0)';$S;
    'VSS249':'(0,0,0,0,0,0,0,0,0,0,0,0,0,0,0,0,0,0,0,0,0,0,0,0,0,0,0,0,0,0,0,0,0~
,0,0,0,0,AM57,0,0,0,0)';$S;
    'VSS248':'(0,0,0,0,0,0,0,0,0,0,0,0,0,0,0,0,0,0,0,0,0,0,0,0,0,0,0,0,0,0,0,0,0~
,0,0,0,0,AM55,0,0,0,0)';$S;
    'VSS247':'(0,0,0,0,0,0,0,0,0,0,0,0,0,0,0,0,0,0,0,0,0,0,0,0,0,0,0,0,0,0,0,0,0~
,0,0,0,0,AM53,0,0,0,0)';$S;
    'VSS246':'(0,0,0,0,0,0,0,0,0,0,0,0,0,0,0,0,0,0,0,0,0,0,0,0,0,0,0,0,0,0,0,0,0~
,0,0,0,0,AM51,0,0,0,0)';$S;
    'VSS245':'(0,0,0,0,0,0,0,0,0,0,0,0,0,0,0,0,0,0,0,0,0,0,0,0,0,0,0,0,0,0,0,0,0~
,0,0,0,0,AM49,0,0,0,0)';$S;
    'VSS244':'(0,0,0,0,0,0,0,0,0,0,0,0,0,0,0,0,0,0,0,0,0,0,0,0,0,0,0,0,0,0,0,0,0~
,0,0,0,0,AM47,0,0,0,0)';$S;
    'VSS243':'(0,0,0,0,0,0,0,0,0,0,0,0,0,0,0,0,0,0,0,0,0,0,0,0,0,0,0,0,0,0,0,0,0~
,0,0,0,0,AM44,0,0,0,0)';$S;
    'VSS242':'(0,0,0,0,0,0,0,0,0,0,0,0,0,0,0,0,0,0,0,0,0,0,0,0,0,0,0,0,0,0,0,0,0~
,0,0,0,0,AM42,0,0,0,0)';$S;
    'VSS241':'(0,0,0,0,0,0,0,0,0,0,0,0,0,0,0,0,0,0,0,0,0,0,0,0,0,0,0,0,0,0,0,0,0~
,0,0,0,0,AM40,0,0,0,0)';$S;
    'VSS240':'(0,0,0,0,0,0,0,0,0,0,0,0,0,0,0,0,0,0,0,0,0,0,0,0,0,0,0,0,0,0,0,0,0~
,0,0,0,0,AM4,0,0,0,0)';$S;
    'VSS239':'(0,0,0,0,0,0,0,0,0,0,0,0,0,0,0,0,0,0,0,0,0,0,0,0,0,0,0,0,0,0,0,0,0~
,0,0,0,0,AM38,0,0,0,0)';$S;
    'VSS238':'(0,0,0,0,0,0,0,0,0,0,0,0,0,0,0,0,0,0,0,0,0,0,0,0,0,0,0,0,0,0,0,0,0~
,0,0,0,0,AM36,0,0,0,0)';$S;
    'VSS237':'(0,0,0,0,0,0,0,0,0,0,0,0,0,0,0,0,0,0,0,0,0,0,0,0,0,0,0,0,0,0,0,0,0~
,0,0,0,0,AM34,0,0,0,0)';$S;
    'VSS236':'(0,0,0,0,0,0,0,0,0,0,0,0,0,0,0,0,0,0,0,0,0,0,0,0,0,0,0,0,0,0,0,0,0~
,0,0,0,0,AM32,0,0,0,0)';$S;
    'VSS235':'(0,0,0,0,0,0,0,0,0,0,0,0,0,0,0,0,0,0,0,0,0,0,0,0,0,0,0,0,0,0,0,0,0~
,0,0,0,0,AM30,0,0,0,0)';$S;
    'VSS234':'(0,0,0,0,0,0,0,0,0,0,0,0,0,0,0,0,0,0,0,0,0,0,0,0,0,0,0,0,0,0,0,0,0~
,0,0,0,0,AM28,0,0,0,0)';$S;
    'VSS233':'(0,0,0,0,0,0,0,0,0,0,0,0,0,0,0,0,0,0,0,0,0,0,0,0,0,0,0,0,0,0,0,0,0~
,0,0,0,0,AM26,0,0,0,0)';$S;
    'VSS232':'(0,0,0,0,0,0,0,0,0,0,0,0,0,0,0,0,0,0,0,0,0,0,0,0,0,0,0,0,0,0,0,0,0~
,0,0,0,0,AM24,0,0,0,0)';$S;
    'VSS231':'(0,0,0,0,0,0,0,0,0,0,0,0,0,0,0,0,0,0,0,0,0,0,0,0,0,0,0,0,0,0,0,0,0~
,0,0,0,0,AM22,0,0,0,0)';$S;
    'VSS230':'(0,0,0,0,0,0,0,0,0,0,0,0,0,0,0,0,0,0,0,0,0,0,0,0,0,0,0,0,0,0,0,0,0~
,0,0,0,0,AM20,0,0,0,0)';$S;
    'VSS229':'(0,0,0,0,0,0,0,0,0,0,0,0,0,0,0,0,0,0,0,0,0,0,0,0,0,0,0,0,0,0,0,0,0~
,0,0,0,0,AM18,0,0,0,0)';$S;
    'VSS228':'(0,0,0,0,0,0,0,0,0,0,0,0,0,0,0,0,0,0,0,0,0,0,0,0,0,0,0,0,0,0,0,0,0~
,0,0,0,0,AM16,0,0,0,0)';$S;
    'VSS227':'(0,0,0,0,0,0,0,0,0,0,0,0,0,0,0,0,0,0,0,0,0,0,0,0,0,0,0,0,0,0,0,0,0~
,0,0,0,0,AM12,0,0,0,0)';$S;
    'VSS226':'(0,0,0,0,0,0,0,0,0,0,0,0,0,0,0,0,0,0,0,0,0,0,0,0,0,0,0,0,0,0,0,0,0~
,0,0,0,0,AL9,0,0,0,0)';$S;
    'VSS225':'(0,0,0,0,0,0,0,0,0,0,0,0,0,0,0,0,0,0,0,0,0,0,0,0,0,0,0,0,0,0,0,0,0~
,0,0,0,0,AL88,0,0,0,0)';$S;
    'VSS224':'(0,0,0,0,0,0,0,0,0,0,0,0,0,0,0,0,0,0,0,0,0,0,0,0,0,0,0,0,0,0,0,0,0~
,0,0,0,0,AL84,0,0,0,0)';$S;
    'VSS223':'(0,0,0,0,0,0,0,0,0,0,0,0,0,0,0,0,0,0,0,0,0,0,0,0,0,0,0,0,0,0,0,0,0~
,0,0,0,0,AL82,0,0,0,0)';$S;
    'VSS222':'(0,0,0,0,0,0,0,0,0,0,0,0,0,0,0,0,0,0,0,0,0,0,0,0,0,0,0,0,0,0,0,0,0~
,0,0,0,0,AL80,0,0,0,0)';$S;
    'VSS221':'(0,0,0,0,0,0,0,0,0,0,0,0,0,0,0,0,0,0,0,0,0,0,0,0,0,0,0,0,0,0,0,0,0~
,0,0,0,0,AL52,0,0,0,0)';$S;
    'VSS220':'(0,0,0,0,0,0,0,0,0,0,0,0,0,0,0,0,0,0,0,0,0,0,0,0,0,0,0,0,0,0,0,0,0~
,0,0,0,0,AL5,0,0,0,0)';$S;
    'VSS219':'(0,0,0,0,0,0,0,0,0,0,0,0,0,0,0,0,0,0,0,0,0,0,0,0,0,0,0,0,0,0,0,0,0~
,0,0,0,0,AL17,0,0,0,0)';$S;
    'VSS218':'(0,0,0,0,0,0,0,0,0,0,0,0,0,0,0,0,0,0,0,0,0,0,0,0,0,0,0,0,0,0,0,0,0~
,0,0,0,0,AL13,0,0,0,0)';$S;
    'VSS217':'(0,0,0,0,0,0,0,0,0,0,0,0,0,0,0,0,0,0,0,0,0,0,0,0,0,0,0,0,0,0,0,0,0~
,0,0,0,0,AL1,0,0,0,0)';$S;
    'VSS216':'(0,0,0,0,0,0,0,0,0,0,0,0,0,0,0,0,0,0,0,0,0,0,0,0,0,0,0,0,0,0,0,0,0~
,0,0,0,0,AK91,0,0,0,0)';$S;
    'VSS215':'(0,0,0,0,0,0,0,0,0,0,0,0,0,0,0,0,0,0,0,0,0,0,0,0,0,0,0,0,0,0,0,0,0~
,0,0,0,0,AK87,0,0,0,0)';$S;
    'VSS214':'(0,0,0,0,0,0,0,0,0,0,0,0,0,0,0,0,0,0,0,0,0,0,0,0,0,0,0,0,0,0,0,0,0~
,0,0,0,0,AK83,0,0,0,0)';$S;
    'VSS213':'(0,0,0,0,0,0,0,0,0,0,0,0,0,0,0,0,0,0,0,0,0,0,0,0,0,0,0,0,0,0,0,0,0~
,0,0,0,0,AK81,0,0,0,0)';$S;
    'VSS212':'(0,0,0,0,0,0,0,0,0,0,0,0,0,0,0,0,0,0,0,0,0,0,0,0,0,0,0,0,0,0,0,0,0~
,0,0,0,0,AK8,0,0,0,0)';$S;
    'VSS211':'(0,0,0,0,0,0,0,0,0,0,0,0,0,0,0,0,0,0,0,0,0,0,0,0,0,0,0,0,0,0,0,0,0~
,0,0,0,0,AK79,0,0,0,0)';$S;
    'VSS210':'(0,0,0,0,0,0,0,0,0,0,0,0,0,0,0,0,0,0,0,0,0,0,0,0,0,0,0,0,0,0,0,0,0~
,0,0,0,0,AK73,0,0,0,0)';$S;
    'VSS209':'(0,0,0,0,0,0,0,0,0,0,0,0,0,0,0,0,0,0,0,0,0,0,0,0,0,0,0,0,0,0,0,0,0~
,0,0,0,0,AK67,0,0,0,0)';$S;
    'VSS208':'(0,0,0,0,0,0,0,0,0,0,0,0,0,0,0,0,0,0,0,0,0,0,0,0,0,0,0,0,0,0,0,0,0~
,0,0,0,0,AK61,0,0,0,0)';$S;
    'VSS207':'(0,0,0,0,0,0,0,0,0,0,0,0,0,0,0,0,0,0,0,0,0,0,0,0,0,0,0,0,0,0,0,0,0~
,0,0,0,0,AK55,0,0,0,0)';$S;
    'VSS206':'(0,0,0,0,0,0,0,0,0,0,0,0,0,0,0,0,0,0,0,0,0,0,0,0,0,0,0,0,0,0,0,0,0~
,0,0,0,0,AK49,0,0,0,0)';$S;
    'VSS205':'(0,0,0,0,0,0,0,0,0,0,0,0,0,0,0,0,0,0,0,0,0,0,0,0,0,0,0,0,0,0,0,0,0~
,0,0,0,0,AK42,0,0,0,0)';$S;
    'VSS204':'(0,0,0,0,0,0,0,0,0,0,0,0,0,0,0,0,0,0,0,0,0,0,0,0,0,0,0,0,0,0,0,0,0~
,0,0,0,0,AK4,0,0,0,0)';$S;
    'VSS203':'(0,0,0,0,0,0,0,0,0,0,0,0,0,0,0,0,0,0,0,0,0,0,0,0,0,0,0,0,0,0,0,0,0~
,0,0,0,0,AK36,0,0,0,0)';$S;
    'VSS202':'(0,0,0,0,0,0,0,0,0,0,0,0,0,0,0,0,0,0,0,0,0,0,0,0,0,0,0,0,0,0,0,0,0~
,0,0,0,0,AK30,0,0,0,0)';$S;
    'VSS201':'(0,0,0,0,0,0,0,0,0,0,0,0,0,0,0,0,0,0,0,0,0,0,0,0,0,0,0,0,0,0,0,0,0~
,0,0,0,0,AK24,0,0,0,0)';$S;
    'VSS200':'(0,0,0,0,0,0,0,0,0,0,0,0,0,0,0,0,0,0,0,0,0,0,0,0,0,0,0,0,0,0,0,0,0~
,0,0,0,0,AK18,0,0,0,0)';$S;
    'VSS199':'(0,0,0,0,0,0,0,0,0,0,0,0,0,0,0,0,0,0,0,0,0,0,0,0,0,0,0,0,0,0,0,0,0~
,0,0,0,0,AK16,0,0,0,0)';$S;
    'VSS198':'(0,0,0,0,0,0,0,0,0,0,0,0,0,0,0,0,0,0,0,0,0,0,0,0,0,0,0,0,0,0,0,0,0~
,0,0,0,0,AK12,0,0,0,0)';$S;
    'VSS197':'(0,0,0,0,0,0,0,0,0,0,0,0,0,0,0,0,0,0,0,0,0,0,0,0,0,0,0,0,0,0,0,0,0~
,0,0,0,0,0,AJ88,0,0,0)';$S;
    'VSS196':'(0,0,0,0,0,0,0,0,0,0,0,0,0,0,0,0,0,0,0,0,0,0,0,0,0,0,0,0,0,0,0,0,0~
,0,0,0,0,0,AJ84,0,0,0)';$S;
    'VSS195':'(0,0,0,0,0,0,0,0,0,0,0,0,0,0,0,0,0,0,0,0,0,0,0,0,0,0,0,0,0,0,0,0,0~
,0,0,0,0,0,AJ78,0,0,0)';$S;
    'VSS194':'(0,0,0,0,0,0,0,0,0,0,0,0,0,0,0,0,0,0,0,0,0,0,0,0,0,0,0,0,0,0,0,0,0~
,0,0,0,0,0,AJ74,0,0,0)';$S;
    'VSS193':'(0,0,0,0,0,0,0,0,0,0,0,0,0,0,0,0,0,0,0,0,0,0,0,0,0,0,0,0,0,0,0,0,0~
,0,0,0,0,0,AJ72,0,0,0)';$S;
    'VSS192':'(0,0,0,0,0,0,0,0,0,0,0,0,0,0,0,0,0,0,0,0,0,0,0,0,0,0,0,0,0,0,0,0,0~
,0,0,0,0,0,AJ68,0,0,0)';$S;
    'VSS191':'(0,0,0,0,0,0,0,0,0,0,0,0,0,0,0,0,0,0,0,0,0,0,0,0,0,0,0,0,0,0,0,0,0~
,0,0,0,0,0,AJ66,0,0,0)';$S;
    'VSS190':'(0,0,0,0,0,0,0,0,0,0,0,0,0,0,0,0,0,0,0,0,0,0,0,0,0,0,0,0,0,0,0,0,0~
,0,0,0,0,0,AJ62,0,0,0)';$S;
    'VSS189':'(0,0,0,0,0,0,0,0,0,0,0,0,0,0,0,0,0,0,0,0,0,0,0,0,0,0,0,0,0,0,0,0,0~
,0,0,0,0,0,AJ60,0,0,0)';$S;
    'VSS188':'(0,0,0,0,0,0,0,0,0,0,0,0,0,0,0,0,0,0,0,0,0,0,0,0,0,0,0,0,0,0,0,0,0~
,0,0,0,0,0,AJ56,0,0,0)';$S;
    'VSS187':'(0,0,0,0,0,0,0,0,0,0,0,0,0,0,0,0,0,0,0,0,0,0,0,0,0,0,0,0,0,0,0,0,0~
,0,0,0,0,0,AJ54,0,0,0)';$S;
    'VSS186':'(0,0,0,0,0,0,0,0,0,0,0,0,0,0,0,0,0,0,0,0,0,0,0,0,0,0,0,0,0,0,0,0,0~
,0,0,0,0,0,AJ50,0,0,0)';$S;
    'VSS185':'(0,0,0,0,0,0,0,0,0,0,0,0,0,0,0,0,0,0,0,0,0,0,0,0,0,0,0,0,0,0,0,0,0~
,0,0,0,0,0,AJ48,0,0,0)';$S;
    'VSS184':'(0,0,0,0,0,0,0,0,0,0,0,0,0,0,0,0,0,0,0,0,0,0,0,0,0,0,0,0,0,0,0,0,0~
,0,0,0,0,0,AJ43,0,0,0)';$S;
    'VSS183':'(0,0,0,0,0,0,0,0,0,0,0,0,0,0,0,0,0,0,0,0,0,0,0,0,0,0,0,0,0,0,0,0,0~
,0,0,0,0,0,AJ41,0,0,0)';$S;
    'VSS182':'(0,0,0,0,0,0,0,0,0,0,0,0,0,0,0,0,0,0,0,0,0,0,0,0,0,0,0,0,0,0,0,0,0~
,0,0,0,0,0,AJ37,0,0,0)';$S;
    'VSS181':'(0,0,0,0,0,0,0,0,0,0,0,0,0,0,0,0,0,0,0,0,0,0,0,0,0,0,0,0,0,0,0,0,0~
,0,0,0,0,0,AJ35,0,0,0)';$S;
    'VSS180':'(0,0,0,0,0,0,0,0,0,0,0,0,0,0,0,0,0,0,0,0,0,0,0,0,0,0,0,0,0,0,0,0,0~
,0,0,0,0,0,AJ31,0,0,0)';$S;
    'VSS179':'(0,0,0,0,0,0,0,0,0,0,0,0,0,0,0,0,0,0,0,0,0,0,0,0,0,0,0,0,0,0,0,0,0~
,0,0,0,0,0,AJ29,0,0,0)';$S;
    'VSS178':'(0,0,0,0,0,0,0,0,0,0,0,0,0,0,0,0,0,0,0,0,0,0,0,0,0,0,0,0,0,0,0,0,0~
,0,0,0,0,0,AJ25,0,0,0)';$S;
    'VSS177':'(0,0,0,0,0,0,0,0,0,0,0,0,0,0,0,0,0,0,0,0,0,0,0,0,0,0,0,0,0,0,0,0,0~
,0,0,0,0,0,AJ23,0,0,0)';$S;
    'VSS176':'(0,0,0,0,0,0,0,0,0,0,0,0,0,0,0,0,0,0,0,0,0,0,0,0,0,0,0,0,0,0,0,0,0~
,0,0,0,0,0,AJ19,0,0,0)';$S;
    'VSS175':'(0,0,0,0,0,0,0,0,0,0,0,0,0,0,0,0,0,0,0,0,0,0,0,0,0,0,0,0,0,0,0,0,0~
,0,0,0,0,0,AH83,0,0,0)';$S;
    'VSS174':'(0,0,0,0,0,0,0,0,0,0,0,0,0,0,0,0,0,0,0,0,0,0,0,0,0,0,0,0,0,0,0,0,0~
,0,0,0,0,0,AH8,0,0,0)';$S;
    'VSS173':'(0,0,0,0,0,0,0,0,0,0,0,0,0,0,0,0,0,0,0,0,0,0,0,0,0,0,0,0,0,0,0,0,0~
,0,0,0,0,0,AH79,0,0,0)';$S;
    'VSS172':'(0,0,0,0,0,0,0,0,0,0,0,0,0,0,0,0,0,0,0,0,0,0,0,0,0,0,0,0,0,0,0,0,0~
,0,0,0,0,0,AH77,0,0,0)';$S;
    'VSS171':'(0,0,0,0,0,0,0,0,0,0,0,0,0,0,0,0,0,0,0,0,0,0,0,0,0,0,0,0,0,0,0,0,0~
,0,0,0,0,0,AH75,0,0,0)';$S;
    'VSS170':'(0,0,0,0,0,0,0,0,0,0,0,0,0,0,0,0,0,0,0,0,0,0,0,0,0,0,0,0,0,0,0,0,0~
,0,0,0,0,0,AH71,0,0,0)';$S;
    'VSS169':'(0,0,0,0,0,0,0,0,0,0,0,0,0,0,0,0,0,0,0,0,0,0,0,0,0,0,0,0,0,0,0,0,0~
,0,0,0,0,0,AH69,0,0,0)';$S;
    'VSS168':'(0,0,0,0,0,0,0,0,0,0,0,0,0,0,0,0,0,0,0,0,0,0,0,0,0,0,0,0,0,0,0,0,0~
,0,0,0,0,0,AH65,0,0,0)';$S;
    'VSS167':'(0,0,0,0,0,0,0,0,0,0,0,0,0,0,0,0,0,0,0,0,0,0,0,0,0,0,0,0,0,0,0,0,0~
,0,0,0,0,0,AH63,0,0,0)';$S;
    'VSS166':'(0,0,0,0,0,0,0,0,0,0,0,0,0,0,0,0,0,0,0,0,0,0,0,0,0,0,0,0,0,0,0,0,0~
,0,0,0,0,0,AH59,0,0,0)';$S;
    'VSS165':'(0,0,0,0,0,0,0,0,0,0,0,0,0,0,0,0,0,0,0,0,0,0,0,0,0,0,0,0,0,0,0,0,0~
,0,0,0,0,0,AH57,0,0,0)';$S;
    'VSS164':'(0,0,0,0,0,0,0,0,0,0,0,0,0,0,0,0,0,0,0,0,0,0,0,0,0,0,0,0,0,0,0,0,0~
,0,0,0,0,0,AH53,0,0,0)';$S;
    'VSS163':'(0,0,0,0,0,0,0,0,0,0,0,0,0,0,0,0,0,0,0,0,0,0,0,0,0,0,0,0,0,0,0,0,0~
,0,0,0,0,0,AH51,0,0,0)';$S;
    'VSS162':'(0,0,0,0,0,0,0,0,0,0,0,0,0,0,0,0,0,0,0,0,0,0,0,0,0,0,0,0,0,0,0,0,0~
,0,0,0,0,0,AH47,0,0,0)';$S;
    'VSS161':'(0,0,0,0,0,0,0,0,0,0,0,0,0,0,0,0,0,0,0,0,0,0,0,0,0,0,0,0,0,0,0,0,0~
,0,0,0,0,0,AH44,0,0,0)';$S;
    'VSS160':'(0,0,0,0,0,0,0,0,0,0,0,0,0,0,0,0,0,0,0,0,0,0,0,0,0,0,0,0,0,0,0,0,0~
,0,0,0,0,0,AH40,0,0,0)';$S;
    'VSS159':'(0,0,0,0,0,0,0,0,0,0,0,0,0,0,0,0,0,0,0,0,0,0,0,0,0,0,0,0,0,0,0,0,0~
,0,0,0,0,0,AH4,0,0,0)';$S;
    'VSS158':'(0,0,0,0,0,0,0,0,0,0,0,0,0,0,0,0,0,0,0,0,0,0,0,0,0,0,0,0,0,0,0,0,0~
,0,0,0,0,0,AH38,0,0,0)';$S;
    'VSS157':'(0,0,0,0,0,0,0,0,0,0,0,0,0,0,0,0,0,0,0,0,0,0,0,0,0,0,0,0,0,0,0,0,0~
,0,0,0,0,0,AH34,0,0,0)';$S;
    'VSS156':'(0,0,0,0,0,0,0,0,0,0,0,0,0,0,0,0,0,0,0,0,0,0,0,0,0,0,0,0,0,0,0,0,0~
,0,0,0,0,0,AH32,0,0,0)';$S;
    'VSS155':'(0,0,0,0,0,0,0,0,0,0,0,0,0,0,0,0,0,0,0,0,0,0,0,0,0,0,0,0,0,0,0,0,0~
,0,0,0,0,0,AH28,0,0,0)';$S;
    'VSS154':'(0,0,0,0,0,0,0,0,0,0,0,0,0,0,0,0,0,0,0,0,0,0,0,0,0,0,0,0,0,0,0,0,0~
,0,0,0,0,0,AH26,0,0,0)';$S;
    'VSS153':'(0,0,0,0,0,0,0,0,0,0,0,0,0,0,0,0,0,0,0,0,0,0,0,0,0,0,0,0,0,0,0,0,0~
,0,0,0,0,0,AH22,0,0,0)';$S;
    'VSS152':'(0,0,0,0,0,0,0,0,0,0,0,0,0,0,0,0,0,0,0,0,0,0,0,0,0,0,0,0,0,0,0,0,0~
,0,0,0,0,0,AH20,0,0,0)';$S;
    'VSS151':'(0,0,0,0,0,0,0,0,0,0,0,0,0,0,0,0,0,0,0,0,0,0,0,0,0,0,0,0,0,0,0,0,0~
,0,0,0,0,0,AH16,0,0,0)';$S;
    'VSS150':'(0,0,0,0,0,0,0,0,0,0,0,0,0,0,0,0,0,0,0,0,0,0,0,0,0,0,0,0,0,0,0,0,0~
,0,0,0,0,0,AH12,0,0,0)';$S;
    'VSS149':'(0,0,0,0,0,0,0,0,0,0,0,0,0,0,0,0,0,0,0,0,0,0,0,0,0,0,0,0,0,0,0,0,0~
,0,0,0,0,0,AG9,0,0,0)';$S;
    'VSS148':'(0,0,0,0,0,0,0,0,0,0,0,0,0,0,0,0,0,0,0,0,0,0,0,0,0,0,0,0,0,0,0,0,0~
,0,0,0,0,0,AG88,0,0,0)';$S;
    'VSS147':'(0,0,0,0,0,0,0,0,0,0,0,0,0,0,0,0,0,0,0,0,0,0,0,0,0,0,0,0,0,0,0,0,0~
,0,0,0,0,0,AG84,0,0,0)';$S;
    'VSS146':'(0,0,0,0,0,0,0,0,0,0,0,0,0,0,0,0,0,0,0,0,0,0,0,0,0,0,0,0,0,0,0,0,0~
,0,0,0,0,0,AG76,0,0,0)';$S;
    'VSS145':'(0,0,0,0,0,0,0,0,0,0,0,0,0,0,0,0,0,0,0,0,0,0,0,0,0,0,0,0,0,0,0,0,0~
,0,0,0,0,0,AG70,0,0,0)';$S;
    'VSS144':'(0,0,0,0,0,0,0,0,0,0,0,0,0,0,0,0,0,0,0,0,0,0,0,0,0,0,0,0,0,0,0,0,0~
,0,0,0,0,0,AG64,0,0,0)';$S;
    'VSS143':'(0,0,0,0,0,0,0,0,0,0,0,0,0,0,0,0,0,0,0,0,0,0,0,0,0,0,0,0,0,0,0,0,0~
,0,0,0,0,0,AG58,0,0,0)';$S;
    'VSS142':'(0,0,0,0,0,0,0,0,0,0,0,0,0,0,0,0,0,0,0,0,0,0,0,0,0,0,0,0,0,0,0,0,0~
,0,0,0,0,0,AG52,0,0,0)';$S;
    'VSS141':'(0,0,0,0,0,0,0,0,0,0,0,0,0,0,0,0,0,0,0,0,0,0,0,0,0,0,0,0,0,0,0,0,0~
,0,0,0,0,0,AG5,0,0,0)';$S;
    'VSS140':'(0,0,0,0,0,0,0,0,0,0,0,0,0,0,0,0,0,0,0,0,0,0,0,0,0,0,0,0,0,0,0,0,0~
,0,0,0,0,0,AG45,0,0,0)';$S;
    'VSS139':'(0,0,0,0,0,0,0,0,0,0,0,0,0,0,0,0,0,0,0,0,0,0,0,0,0,0,0,0,0,0,0,0,0~
,0,0,0,0,0,AG39,0,0,0)';$S;
    'VSS138':'(0,0,0,0,0,0,0,0,0,0,0,0,0,0,0,0,0,0,0,0,0,0,0,0,0,0,0,0,0,0,0,0,0~
,0,0,0,0,0,AG33,0,0,0)';$S;
    'VSS137':'(0,0,0,0,0,0,0,0,0,0,0,0,0,0,0,0,0,0,0,0,0,0,0,0,0,0,0,0,0,0,0,0,0~
,0,0,0,0,0,AG27,0,0,0)';$S;
    'VSS136':'(0,0,0,0,0,0,0,0,0,0,0,0,0,0,0,0,0,0,0,0,0,0,0,0,0,0,0,0,0,0,0,0,0~
,0,0,0,0,0,AG21,0,0,0)';$S;
    'VSS135':'(0,0,0,0,0,0,0,0,0,0,0,0,0,0,0,0,0,0,0,0,0,0,0,0,0,0,0,0,0,0,0,0,0~
,0,0,0,0,0,AG13,0,0,0)';$S;
    'VSS134':'(0,0,0,0,0,0,0,0,0,0,0,0,0,0,0,0,0,0,0,0,0,0,0,0,0,0,0,0,0,0,0,0,0~
,0,0,0,0,0,AG1,0,0,0)';$S;
    'VSS133':'(0,0,0,0,0,0,0,0,0,0,0,0,0,0,0,0,0,0,0,0,0,0,0,0,0,0,0,0,0,0,0,0,0~
,0,0,0,0,0,AF91,0,0,0)';$S;
    'VSS132':'(0,0,0,0,0,0,0,0,0,0,0,0,0,0,0,0,0,0,0,0,0,0,0,0,0,0,0,0,0,0,0,0,0~
,0,0,0,0,0,AF87,0,0,0)';$S;
    'VSS131':'(0,0,0,0,0,0,0,0,0,0,0,0,0,0,0,0,0,0,0,0,0,0,0,0,0,0,0,0,0,0,0,0,0~
,0,0,0,0,0,AF81,0,0,0)';$S;
    'VSS130':'(0,0,0,0,0,0,0,0,0,0,0,0,0,0,0,0,0,0,0,0,0,0,0,0,0,0,0,0,0,0,0,0,0~
,0,0,0,0,0,AF8,0,0,0)';$S;
    'VSS129':'(0,0,0,0,0,0,0,0,0,0,0,0,0,0,0,0,0,0,0,0,0,0,0,0,0,0,0,0,0,0,0,0,0~
,0,0,0,0,0,AF42,0,0,0)';$S;
    'VSS128':'(0,0,0,0,0,0,0,0,0,0,0,0,0,0,0,0,0,0,0,0,0,0,0,0,0,0,0,0,0,0,0,0,0~
,0,0,0,0,0,AF4,0,0,0)';$S;
    'VSS127':'(0,0,0,0,0,0,0,0,0,0,0,0,0,0,0,0,0,0,0,0,0,0,0,0,0,0,0,0,0,0,0,0,0~
,0,0,0,0,0,AF16,0,0,0)';$S;
    'VSS126':'(0,0,0,0,0,0,0,0,0,0,0,0,0,0,0,0,0,0,0,0,0,0,0,0,0,0,0,0,0,0,0,0,0~
,0,0,0,0,0,AF12,0,0,0)';$S;
    'VSS125':'(0,0,0,0,0,0,0,0,0,0,0,0,0,0,0,0,0,0,0,0,0,0,0,0,0,0,0,0,0,0,0,0,0~
,0,0,0,0,0,AE88,0,0,0)';$S;
    'VSS124':'(0,0,0,0,0,0,0,0,0,0,0,0,0,0,0,0,0,0,0,0,0,0,0,0,0,0,0,0,0,0,0,0,0~
,0,0,0,0,0,AE84,0,0,0)';$S;
    'VSS123':'(0,0,0,0,0,0,0,0,0,0,0,0,0,0,0,0,0,0,0,0,0,0,0,0,0,0,0,0,0,0,0,0,0~
,0,0,0,0,0,AE78,0,0,0)';$S;
    'VSS122':'(0,0,0,0,0,0,0,0,0,0,0,0,0,0,0,0,0,0,0,0,0,0,0,0,0,0,0,0,0,0,0,0,0~
,0,0,0,0,0,AE76,0,0,0)';$S;
    'VSS121':'(0,0,0,0,0,0,0,0,0,0,0,0,0,0,0,0,0,0,0,0,0,0,0,0,0,0,0,0,0,0,0,0,0~
,0,0,0,0,0,AE74,0,0,0)';$S;
    'VSS120':'(0,0,0,0,0,0,0,0,0,0,0,0,0,0,0,0,0,0,0,0,0,0,0,0,0,0,0,0,0,0,0,0,0~
,0,0,0,0,0,AE72,0,0,0)';$S;
    'VSS119':'(0,0,0,0,0,0,0,0,0,0,0,0,0,0,0,0,0,0,0,0,0,0,0,0,0,0,0,0,0,0,0,0,0~
,0,0,0,0,0,AE70,0,0,0)';$S;
    'VSS118':'(0,0,0,0,0,0,0,0,0,0,0,0,0,0,0,0,0,0,0,0,0,0,0,0,0,0,0,0,0,0,0,0,0~
,0,0,0,0,0,AE68,0,0,0)';$S;
    'VSS117':'(0,0,0,0,0,0,0,0,0,0,0,0,0,0,0,0,0,0,0,0,0,0,0,0,0,0,0,0,0,0,0,0,0~
,0,0,0,0,0,AE66,0,0,0)';$S;
    'VSS116':'(0,0,0,0,0,0,0,0,0,0,0,0,0,0,0,0,0,0,0,0,0,0,0,0,0,0,0,0,0,0,0,0,0~
,0,0,0,0,0,AE64,0,0,0)';$S;
    'VSS115':'(0,0,0,0,0,0,0,0,0,0,0,0,0,0,0,0,0,0,0,0,0,0,0,0,0,0,0,0,0,0,0,0,0~
,0,0,0,0,0,AE62,0,0,0)';$S;
    'VSS114':'(0,0,0,0,0,0,0,0,0,0,0,0,0,0,0,0,0,0,0,0,0,0,0,0,0,0,0,0,0,0,0,0,0~
,0,0,0,0,0,AE60,0,0,0)';$S;
    'VSS113':'(0,0,0,0,0,0,0,0,0,0,0,0,0,0,0,0,0,0,0,0,0,0,0,0,0,0,0,0,0,0,0,0,0~
,0,0,0,0,0,AE58,0,0,0)';$S;
    'VSS112':'(0,0,0,0,0,0,0,0,0,0,0,0,0,0,0,0,0,0,0,0,0,0,0,0,0,0,0,0,0,0,0,0,0~
,0,0,0,0,0,AE56,0,0,0)';$S;
    'VSS111':'(0,0,0,0,0,0,0,0,0,0,0,0,0,0,0,0,0,0,0,0,0,0,0,0,0,0,0,0,0,0,0,0,0~
,0,0,0,0,0,AE54,0,0,0)';$S;
    'VSS110':'(0,0,0,0,0,0,0,0,0,0,0,0,0,0,0,0,0,0,0,0,0,0,0,0,0,0,0,0,0,0,0,0,0~
,0,0,0,0,0,AE52,0,0,0)';$S;
    'VSS109':'(0,0,0,0,0,0,0,0,0,0,0,0,0,0,0,0,0,0,0,0,0,0,0,0,0,0,0,0,0,0,0,0,0~
,0,0,0,0,0,AE50,0,0,0)';$S;
    'VSS108':'(0,0,0,0,0,0,0,0,0,0,0,0,0,0,0,0,0,0,0,0,0,0,0,0,0,0,0,0,0,0,0,0,0~
,0,0,0,0,0,AE48,0,0,0)';$S;
    'VSS107':'(0,0,0,0,0,0,0,0,0,0,0,0,0,0,0,0,0,0,0,0,0,0,0,0,0,0,0,0,0,0,0,0,0~
,0,0,0,0,0,AE45,0,0,0)';$S;
    'VSS106':'(0,0,0,0,0,0,0,0,0,0,0,0,0,0,0,0,0,0,0,0,0,0,0,0,0,0,0,0,0,0,0,0,0~
,0,0,0,0,0,AE43,0,0,0)';$S;
    'VSS105':'(0,0,0,0,0,0,0,0,0,0,0,0,0,0,0,0,0,0,0,0,0,0,0,0,0,0,0,0,0,0,0,0,0~
,0,0,0,0,0,AE41,0,0,0)';$S;
    'VSS104':'(0,0,0,0,0,0,0,0,0,0,0,0,0,0,0,0,0,0,0,0,0,0,0,0,0,0,0,0,0,0,0,0,0~
,0,0,0,0,0,AE39,0,0,0)';$S;
    'VSS103':'(0,0,0,0,0,0,0,0,0,0,0,0,0,0,0,0,0,0,0,0,0,0,0,0,0,0,0,0,0,0,0,0,0~
,0,0,0,0,0,AE37,0,0,0)';$S;
    'VSS102':'(0,0,0,0,0,0,0,0,0,0,0,0,0,0,0,0,0,0,0,0,0,0,0,0,0,0,0,0,0,0,0,0,0~
,0,0,0,0,0,AE35,0,0,0)';$S;
    'VSS101':'(0,0,0,0,0,0,0,0,0,0,0,0,0,0,0,0,0,0,0,0,0,0,0,0,0,0,0,0,0,0,0,0,0~
,0,0,0,0,0,AE33,0,0,0)';$S;
    'VSS100':'(0,0,0,0,0,0,0,0,0,0,0,0,0,0,0,0,0,0,0,0,0,0,0,0,0,0,0,0,0,0,0,0,0~
,0,0,0,0,0,AE31,0,0,0)';$S;
    'VSS99':'(0,0,0,0,0,0,0,0,0,0,0,0,0,0,0,0,0,0,0,0,0,0,0,0,0,0,0,0,0,0,0,0,0,~
0,0,0,0,0,AE29,0,0,0)';$S;
    'VSS98':'(0,0,0,0,0,0,0,0,0,0,0,0,0,0,0,0,0,0,0,0,0,0,0,0,0,0,0,0,0,0,0,0,0,~
0,0,0,0,0,AE27,0,0,0)';$S;
    'VSS97':'(0,0,0,0,0,0,0,0,0,0,0,0,0,0,0,0,0,0,0,0,0,0,0,0,0,0,0,0,0,0,0,0,0,~
0,0,0,0,0,AE25,0,0,0)';$S;
    'VSS96':'(0,0,0,0,0,0,0,0,0,0,0,0,0,0,0,0,0,0,0,0,0,0,0,0,0,0,0,0,0,0,0,0,0,~
0,0,0,0,0,AE23,0,0,0)';$S;
    'VSS95':'(0,0,0,0,0,0,0,0,0,0,0,0,0,0,0,0,0,0,0,0,0,0,0,0,0,0,0,0,0,0,0,0,0,~
0,0,0,0,0,AE21,0,0,0)';$S;
    'VSS94':'(0,0,0,0,0,0,0,0,0,0,0,0,0,0,0,0,0,0,0,0,0,0,0,0,0,0,0,0,0,0,0,0,0,~
0,0,0,0,0,AE19,0,0,0)';$S;
    'VSS93':'(0,0,0,0,0,0,0,0,0,0,0,0,0,0,0,0,0,0,0,0,0,0,0,0,0,0,0,0,0,0,0,0,0,~
0,0,0,0,0,AE17,0,0,0)';$S;
    'VSS92':'(0,0,0,0,0,0,0,0,0,0,0,0,0,0,0,0,0,0,0,0,0,0,0,0,0,0,0,0,0,0,0,0,0,~
0,0,0,0,0,AD83,0,0,0)';$S;
    'VSS91':'(0,0,0,0,0,0,0,0,0,0,0,0,0,0,0,0,0,0,0,0,0,0,0,0,0,0,0,0,0,0,0,0,0,~
0,0,0,0,0,AD8,0,0,0)';$S;
    'VSS90':'(0,0,0,0,0,0,0,0,0,0,0,0,0,0,0,0,0,0,0,0,0,0,0,0,0,0,0,0,0,0,0,0,0,~
0,0,0,0,0,AD79,0,0,0)';$S;
    'VSS89':'(0,0,0,0,0,0,0,0,0,0,0,0,0,0,0,0,0,0,0,0,0,0,0,0,0,0,0,0,0,0,0,0,0,~
0,0,0,0,0,AD42,0,0,0)';$S;
    'VSS88':'(0,0,0,0,0,0,0,0,0,0,0,0,0,0,0,0,0,0,0,0,0,0,0,0,0,0,0,0,0,0,0,0,0,~
0,0,0,0,0,AD4,0,0,0)';$S;
    'VSS87':'(0,0,0,0,0,0,0,0,0,0,0,0,0,0,0,0,0,0,0,0,0,0,0,0,0,0,0,0,0,0,0,0,0,~
0,0,0,0,0,AD16,0,0,0)';$S;
    'VSS86':'(0,0,0,0,0,0,0,0,0,0,0,0,0,0,0,0,0,0,0,0,0,0,0,0,0,0,0,0,0,0,0,0,0,~
0,0,0,0,0,AD12,0,0,0)';$S;
    'VSS85':'(0,0,0,0,0,0,0,0,0,0,0,0,0,0,0,0,0,0,0,0,0,0,0,0,0,0,0,0,0,0,0,0,0,~
0,0,0,0,0,AC9,0,0,0)';$S;
    'VSS84':'(0,0,0,0,0,0,0,0,0,0,0,0,0,0,0,0,0,0,0,0,0,0,0,0,0,0,0,0,0,0,0,0,0,~
0,0,0,0,0,AC88,0,0,0)';$S;
    'VSS83':'(0,0,0,0,0,0,0,0,0,0,0,0,0,0,0,0,0,0,0,0,0,0,0,0,0,0,0,0,0,0,0,0,0,~
0,0,0,0,0,AC84,0,0,0)';$S;
    'VSS82':'(0,0,0,0,0,0,0,0,0,0,0,0,0,0,0,0,0,0,0,0,0,0,0,0,0,0,0,0,0,0,0,0,0,~
0,0,0,0,0,AC76,0,0,0)';$S;
    'VSS81':'(0,0,0,0,0,0,0,0,0,0,0,0,0,0,0,0,0,0,0,0,0,0,0,0,0,0,0,0,0,0,0,0,0,~
0,0,0,0,0,AC70,0,0,0)';$S;
    'VSS80':'(0,0,0,0,0,0,0,0,0,0,0,0,0,0,0,0,0,0,0,0,0,0,0,0,0,0,0,0,0,0,0,0,0,~
0,0,0,0,0,AC64,0,0,0)';$S;
    'VSS79':'(0,0,0,0,0,0,0,0,0,0,0,0,0,0,0,0,0,0,0,0,0,0,0,0,0,0,0,0,0,0,0,0,0,~
0,0,0,0,0,AC58,0,0,0)';$S;
    'VSS78':'(0,0,0,0,0,0,0,0,0,0,0,0,0,0,0,0,0,0,0,0,0,0,0,0,0,0,0,0,0,0,0,0,0,~
0,0,0,0,0,AC52,0,0,0)';$S;
    'VSS77':'(0,0,0,0,0,0,0,0,0,0,0,0,0,0,0,0,0,0,0,0,0,0,0,0,0,0,0,0,0,0,0,0,0,~
0,0,0,0,0,AC5,0,0,0)';$S;
    'VSS76':'(0,0,0,0,0,0,0,0,0,0,0,0,0,0,0,0,0,0,0,0,0,0,0,0,0,0,0,0,0,0,0,0,0,~
0,0,0,0,0,AC45,0,0,0)';$S;
    'VSS75':'(0,0,0,0,0,0,0,0,0,0,0,0,0,0,0,0,0,0,0,0,0,0,0,0,0,0,0,0,0,0,0,0,0,~
0,0,0,0,0,AC39,0,0,0)';$S;
    'VSS74':'(0,0,0,0,0,0,0,0,0,0,0,0,0,0,0,0,0,0,0,0,0,0,0,0,0,0,0,0,0,0,0,0,0,~
0,0,0,0,0,AC33,0,0,0)';$S;
    'VSS73':'(0,0,0,0,0,0,0,0,0,0,0,0,0,0,0,0,0,0,0,0,0,0,0,0,0,0,0,0,0,0,0,0,0,~
0,0,0,0,0,AC27,0,0,0)';$S;
    'VSS72':'(0,0,0,0,0,0,0,0,0,0,0,0,0,0,0,0,0,0,0,0,0,0,0,0,0,0,0,0,0,0,0,0,0,~
0,0,0,0,0,AC21,0,0,0)';$S;
    'VSS71':'(0,0,0,0,0,0,0,0,0,0,0,0,0,0,0,0,0,0,0,0,0,0,0,0,0,0,0,0,0,0,0,0,0,~
0,0,0,0,0,AC13,0,0,0)';$S;
    'VSS70':'(0,0,0,0,0,0,0,0,0,0,0,0,0,0,0,0,0,0,0,0,0,0,0,0,0,0,0,0,0,0,0,0,0,~
0,0,0,0,0,AC1,0,0,0)';$S;
    'VSS69':'(0,0,0,0,0,0,0,0,0,0,0,0,0,0,0,0,0,0,0,0,0,0,0,0,0,0,0,0,0,0,0,0,0,~
0,0,0,0,0,AB91,0,0,0)';$S;
    'VSS68':'(0,0,0,0,0,0,0,0,0,0,0,0,0,0,0,0,0,0,0,0,0,0,0,0,0,0,0,0,0,0,0,0,0,~
0,0,0,0,0,AB87,0,0,0)';$S;
    'VSS67':'(0,0,0,0,0,0,0,0,0,0,0,0,0,0,0,0,0,0,0,0,0,0,0,0,0,0,0,0,0,0,0,0,0,~
0,0,0,0,0,AB83,0,0,0)';$S;
    'VSS66':'(0,0,0,0,0,0,0,0,0,0,0,0,0,0,0,0,0,0,0,0,0,0,0,0,0,0,0,0,0,0,0,0,0,~
0,0,0,0,0,AB81,0,0,0)';$S;
    'VSS65':'(0,0,0,0,0,0,0,0,0,0,0,0,0,0,0,0,0,0,0,0,0,0,0,0,0,0,0,0,0,0,0,0,0,~
0,0,0,0,0,AB8,0,0,0)';$S;
    'VSS64':'(0,0,0,0,0,0,0,0,0,0,0,0,0,0,0,0,0,0,0,0,0,0,0,0,0,0,0,0,0,0,0,0,0,~
0,0,0,0,0,AB79,0,0,0)';$S;
    'VSS63':'(0,0,0,0,0,0,0,0,0,0,0,0,0,0,0,0,0,0,0,0,0,0,0,0,0,0,0,0,0,0,0,0,0,~
0,0,0,0,0,AB77,0,0,0)';$S;
    'VSS62':'(0,0,0,0,0,0,0,0,0,0,0,0,0,0,0,0,0,0,0,0,0,0,0,0,0,0,0,0,0,0,0,0,0,~
0,0,0,0,0,AB75,0,0,0)';$S;
    'VSS61':'(0,0,0,0,0,0,0,0,0,0,0,0,0,0,0,0,0,0,0,0,0,0,0,0,0,0,0,0,0,0,0,0,0,~
0,0,0,0,0,AB71,0,0,0)';$S;
    'VSS60':'(0,0,0,0,0,0,0,0,0,0,0,0,0,0,0,0,0,0,0,0,0,0,0,0,0,0,0,0,0,0,0,0,0,~
0,0,0,0,0,AB69,0,0,0)';$S;
    'VSS59':'(0,0,0,0,0,0,0,0,0,0,0,0,0,0,0,0,0,0,0,0,0,0,0,0,0,0,0,0,0,0,0,0,0,~
0,0,0,0,0,AB65,0,0,0)';$S;
    'VSS58':'(0,0,0,0,0,0,0,0,0,0,0,0,0,0,0,0,0,0,0,0,0,0,0,0,0,0,0,0,0,0,0,0,0,~
0,0,0,0,0,AB63,0,0,0)';$S;
    'VSS57':'(0,0,0,0,0,0,0,0,0,0,0,0,0,0,0,0,0,0,0,0,0,0,0,0,0,0,0,0,0,0,0,0,0,~
0,0,0,0,0,AB59,0,0,0)';$S;
    'VSS56':'(0,0,0,0,0,0,0,0,0,0,0,0,0,0,0,0,0,0,0,0,0,0,0,0,0,0,0,0,0,0,0,0,0,~
0,0,0,0,0,AB57,0,0,0)';$S;
    'VSS55':'(0,0,0,0,0,0,0,0,0,0,0,0,0,0,0,0,0,0,0,0,0,0,0,0,0,0,0,0,0,0,0,0,0,~
0,0,0,0,0,AB53,0,0,0)';$S;
    'VSS54':'(0,0,0,0,0,0,0,0,0,0,0,0,0,0,0,0,0,0,0,0,0,0,0,0,0,0,0,0,0,0,0,0,0,~
0,0,0,0,0,AB51,0,0,0)';$S;
    'VSS53':'(0,0,0,0,0,0,0,0,0,0,0,0,0,0,0,0,0,0,0,0,0,0,0,0,0,0,0,0,0,0,0,0,0,~
0,0,0,0,0,AB47,0,0,0)';$S;
    'VSS52':'(0,0,0,0,0,0,0,0,0,0,0,0,0,0,0,0,0,0,0,0,0,0,0,0,0,0,0,0,0,0,0,0,0,~
0,0,0,0,0,AB44,0,0,0)';$S;
    'VSS51':'(0,0,0,0,0,0,0,0,0,0,0,0,0,0,0,0,0,0,0,0,0,0,0,0,0,0,0,0,0,0,0,0,0,~
0,0,0,0,0,AB40,0,0,0)';$S;
    'VSS50':'(0,0,0,0,0,0,0,0,0,0,0,0,0,0,0,0,0,0,0,0,0,0,0,0,0,0,0,0,0,0,0,0,0,~
0,0,0,0,0,AB4,0,0,0)';$S;
    'VSS49':'(0,0,0,0,0,0,0,0,0,0,0,0,0,0,0,0,0,0,0,0,0,0,0,0,0,0,0,0,0,0,0,0,0,~
0,0,0,0,0,AB38,0,0,0)';$S;
    'VSS48':'(0,0,0,0,0,0,0,0,0,0,0,0,0,0,0,0,0,0,0,0,0,0,0,0,0,0,0,0,0,0,0,0,0,~
0,0,0,0,0,AB34,0,0,0)';$S;
    'VSS47':'(0,0,0,0,0,0,0,0,0,0,0,0,0,0,0,0,0,0,0,0,0,0,0,0,0,0,0,0,0,0,0,0,0,~
0,0,0,0,0,AB32,0,0,0)';$S;
    'VSS46':'(0,0,0,0,0,0,0,0,0,0,0,0,0,0,0,0,0,0,0,0,0,0,0,0,0,0,0,0,0,0,0,0,0,~
0,0,0,0,0,AB28,0,0,0)';$S;
    'VSS45':'(0,0,0,0,0,0,0,0,0,0,0,0,0,0,0,0,0,0,0,0,0,0,0,0,0,0,0,0,0,0,0,0,0,~
0,0,0,0,0,AB26,0,0,0)';$S;
    'VSS44':'(0,0,0,0,0,0,0,0,0,0,0,0,0,0,0,0,0,0,0,0,0,0,0,0,0,0,0,0,0,0,0,0,0,~
0,0,0,0,0,AB22,0,0,0)';$S;
    'VSS43':'(0,0,0,0,0,0,0,0,0,0,0,0,0,0,0,0,0,0,0,0,0,0,0,0,0,0,0,0,0,0,0,0,0,~
0,0,0,0,0,AB20,0,0,0)';$S;
    'VSS42':'(0,0,0,0,0,0,0,0,0,0,0,0,0,0,0,0,0,0,0,0,0,0,0,0,0,0,0,0,0,0,0,0,0,~
0,0,0,0,0,AB16,0,0,0)';$S;
    'VSS41':'(0,0,0,0,0,0,0,0,0,0,0,0,0,0,0,0,0,0,0,0,0,0,0,0,0,0,0,0,0,0,0,0,0,~
0,0,0,0,0,AB12,0,0,0)';$S;
    'VSS40':'(0,0,0,0,0,0,0,0,0,0,0,0,0,0,0,0,0,0,0,0,0,0,0,0,0,0,0,0,0,0,0,0,0,~
0,0,0,0,0,AA88,0,0,0)';$S;
    'VSS39':'(0,0,0,0,0,0,0,0,0,0,0,0,0,0,0,0,0,0,0,0,0,0,0,0,0,0,0,0,0,0,0,0,0,~
0,0,0,0,0,AA84,0,0,0)';$S;
    'VSS38':'(0,0,0,0,0,0,0,0,0,0,0,0,0,0,0,0,0,0,0,0,0,0,0,0,0,0,0,0,0,0,0,0,0,~
0,0,0,0,0,AA82,0,0,0)';$S;
    'VSS1833':'(0,0,0,0,0,0,0,0,0,0,0,0,0,0,0,0,0,0,0,0,0,0,0,0,0,0,0,0,0,0,0,0,~
0,0,0,0,0,0,0,Y73,0,0)';$S;
    'VSS1832':'(0,0,0,0,0,0,0,0,0,0,0,0,0,0,0,0,0,0,0,0,0,0,0,0,0,0,0,0,0,0,0,0,~
0,0,0,0,0,0,0,Y8,0,0)';$S;
    'VSS1831':'(0,0,0,0,0,0,0,0,0,0,0,0,0,0,0,0,0,0,0,0,0,0,0,0,0,0,0,0,0,0,0,0,~
0,0,0,0,0,0,0,Y55,0,0)';$S;
    'VSS1830':'(0,0,0,0,0,0,0,0,0,0,0,0,0,0,0,0,0,0,0,0,0,0,0,0,0,0,0,0,0,0,0,0,~
0,0,0,0,0,0,0,Y49,0,0)';$S;
    'VSS1829':'(0,0,0,0,0,0,0,0,0,0,0,0,0,0,0,0,0,0,0,0,0,0,0,0,0,0,0,0,0,0,0,0,~
0,0,0,0,0,0,0,Y67,0,0)';$S;
    'VSS1828':'(0,0,0,0,0,0,0,0,0,0,0,0,0,0,0,0,0,0,0,0,0,0,0,0,0,0,0,0,0,0,0,0,~
0,0,0,0,0,0,0,Y61,0,0)';$S;
    'VSS1827':'(0,0,0,0,0,0,0,0,0,0,0,0,0,0,0,0,0,0,0,0,0,0,0,0,0,0,0,0,0,0,0,0,~
0,0,0,0,0,0,0,Y42,0,0)';$S;
    'VSS1826':'(0,0,0,0,0,0,0,0,0,0,0,0,0,0,0,0,0,0,0,0,0,0,0,0,0,0,0,0,0,0,0,0,~
0,0,0,0,0,0,0,Y4,0,0)';$S;
    'VSS1825':'(0,0,0,0,0,0,0,0,0,0,0,0,0,0,0,0,0,0,0,0,0,0,0,0,0,0,0,0,0,0,0,0,~
0,0,0,0,0,0,0,Y36,0,0)';$S;
    'VSS1824':'(0,0,0,0,0,0,0,0,0,0,0,0,0,0,0,0,0,0,0,0,0,0,0,0,0,0,0,0,0,0,0,0,~
0,0,0,0,0,0,0,Y30,0,0)';$S;
    'VSS1823':'(0,0,0,0,0,0,0,0,0,0,0,0,0,0,0,0,0,0,0,0,0,0,0,0,0,0,0,0,0,0,0,0,~
0,0,0,0,0,0,0,Y24,0,0)';$S;
    'VSS1822':'(0,0,0,0,0,0,0,0,0,0,0,0,0,0,0,0,0,0,0,0,0,0,0,0,0,0,0,0,0,0,0,0,~
0,0,0,0,0,0,0,Y18,0,0)';$S;
    'VSS1821':'(0,0,0,0,0,0,0,0,0,0,0,0,0,0,0,0,0,0,0,0,0,0,0,0,0,0,0,0,0,0,0,0,~
0,0,0,0,0,0,0,Y16,0,0)';$S;
    'VSS1820':'(0,0,0,0,0,0,0,0,0,0,0,0,0,0,0,0,0,0,0,0,0,0,0,0,0,0,0,0,0,0,0,0,~
0,0,0,0,0,0,0,Y12,0,0)';$S;
    'VSS1819':'(0,0,0,0,0,0,0,0,0,0,0,0,0,0,0,0,0,0,0,0,0,0,0,0,0,0,0,0,0,0,0,0,~
0,0,0,0,0,0,0,W9,0,0)';$S;
    'VSS1818':'(0,0,0,0,0,0,0,0,0,0,0,0,0,0,0,0,0,0,0,0,0,0,0,0,0,0,0,0,0,0,0,0,~
0,0,0,0,0,0,0,W88,0,0)';$S;
    'VSS1817':'(0,0,0,0,0,0,0,0,0,0,0,0,0,0,0,0,0,0,0,0,0,0,0,0,0,0,0,0,0,0,0,0,~
0,0,0,0,0,0,0,W84,0,0)';$S;
    'VSS1816':'(0,0,0,0,0,0,0,0,0,0,0,0,0,0,0,0,0,0,0,0,0,0,0,0,0,0,0,0,0,0,0,0,~
0,0,0,0,0,0,0,W39,0,0)';$S;
    'VSS1815':'(0,0,0,0,0,0,0,0,0,0,0,0,0,0,0,0,0,0,0,0,0,0,0,0,0,0,0,0,0,0,0,0,~
0,0,0,0,0,0,0,W52,0,0)';$S;
    'VSS1814':'(0,0,0,0,0,0,0,0,0,0,0,0,0,0,0,0,0,0,0,0,0,0,0,0,0,0,0,0,0,0,0,0,~
0,0,0,0,0,0,0,W5,0,0)';$S;
    'VSS1813':'(0,0,0,0,0,0,0,0,0,0,0,0,0,0,0,0,0,0,0,0,0,0,0,0,0,0,0,0,0,0,0,0,~
0,0,0,0,0,0,0,V87,0,0)';$S;
    'VSS1812':'(0,0,0,0,0,0,0,0,0,0,0,0,0,0,0,0,0,0,0,0,0,0,0,0,0,0,0,0,0,0,0,0,~
0,0,0,0,0,0,0,V8,0,0)';$S;
    'VSS1811':'(0,0,0,0,0,0,0,0,0,0,0,0,0,0,0,0,0,0,0,0,0,0,0,0,0,0,0,0,0,0,0,0,~
0,0,0,0,0,0,0,V79,0,0)';$S;
    'VSS1810':'(0,0,0,0,0,0,0,0,0,0,0,0,0,0,0,0,0,0,0,0,0,0,0,0,0,0,0,0,0,0,0,0,~
0,0,0,0,0,0,0,V77,0,0)';$S;
    'VSS1809':'(0,0,0,0,0,0,0,0,0,0,0,0,0,0,0,0,0,0,0,0,0,0,0,0,0,0,0,0,0,0,0,0,~
0,0,0,0,0,0,0,W13,0,0)';$S;
    'VSS1808':'(0,0,0,0,0,0,0,0,0,0,0,0,0,0,0,0,0,0,0,0,0,0,0,0,0,0,0,0,0,0,0,0,~
0,0,0,0,0,0,0,W1,0,0)';$S;
    'VSS1807':'(0,0,0,0,0,0,0,0,0,0,0,0,0,0,0,0,0,0,0,0,0,0,0,0,0,0,0,0,0,0,0,0,~
0,0,0,0,0,0,0,V91,0,0)';$S;
    'VSS1806':'(0,0,0,0,0,0,0,0,0,0,0,0,0,0,0,0,0,0,0,0,0,0,0,0,0,0,0,0,0,0,0,0,~
0,0,0,0,0,0,0,V75,0,0)';$S;
    'VSS1805':'(0,0,0,0,0,0,0,0,0,0,0,0,0,0,0,0,0,0,0,0,0,0,0,0,0,0,0,0,0,0,0,0,~
0,0,0,0,0,0,0,V69,0,0)';$S;
    'VSS1804':'(0,0,0,0,0,0,0,0,0,0,0,0,0,0,0,0,0,0,0,0,0,0,0,0,0,0,0,0,0,0,0,0,~
0,0,0,0,0,0,0,V67,0,0)';$S;
    'VSS1803':'(0,0,0,0,0,0,0,0,0,0,0,0,0,0,0,0,0,0,0,0,0,0,0,0,0,0,0,0,0,0,0,0,~
0,0,0,0,0,0,0,V65,0,0)';$S;
    'VSS1802':'(0,0,0,0,0,0,0,0,0,0,0,0,0,0,0,0,0,0,0,0,0,0,0,0,0,0,0,0,0,0,0,0,~
0,0,0,0,0,0,0,V63,0,0)';$S;
    'VSS1801':'(0,0,0,0,0,0,0,0,0,0,0,0,0,0,0,0,0,0,0,0,0,0,0,0,0,0,0,0,0,0,0,0,~
0,0,0,0,0,0,0,V73,0,0)';$S;
    'VSS1800':'(0,0,0,0,0,0,0,0,0,0,0,0,0,0,0,0,0,0,0,0,0,0,0,0,0,0,0,0,0,0,0,0,~
0,0,0,0,0,0,0,V71,0,0)';$S;
    'VSS1799':'(0,0,0,0,0,0,0,0,0,0,0,0,0,0,0,0,0,0,0,0,0,0,0,0,0,0,0,0,0,0,0,0,~
0,0,0,0,0,0,0,V61,0,0)';$S;
    'VSS1798':'(0,0,0,0,0,0,0,0,0,0,0,0,0,0,0,0,0,0,0,0,0,0,0,0,0,0,0,0,0,0,0,0,~
0,0,0,0,0,0,0,V59,0,0)';$S;
    'VSS1797':'(0,0,0,0,0,0,0,0,0,0,0,0,0,0,0,0,0,0,0,0,0,0,0,0,0,0,0,0,0,0,0,0,~
0,0,0,0,0,0,0,V57,0,0)';$S;
    'VSS1796':'(0,0,0,0,0,0,0,0,0,0,0,0,0,0,0,0,0,0,0,0,0,0,0,0,0,0,0,0,0,0,0,0,~
0,0,0,0,0,0,0,V55,0,0)';$S;
    'VSS1795':'(0,0,0,0,0,0,0,0,0,0,0,0,0,0,0,0,0,0,0,0,0,0,0,0,0,0,0,0,0,0,0,0,~
0,0,0,0,0,0,0,V53,0,0)';$S;
    'VSS1794':'(0,0,0,0,0,0,0,0,0,0,0,0,0,0,0,0,0,0,0,0,0,0,0,0,0,0,0,0,0,0,0,0,~
0,0,0,0,0,0,0,V51,0,0)';$S;
    'VSS1793':'(0,0,0,0,0,0,0,0,0,0,0,0,0,0,0,0,0,0,0,0,0,0,0,0,0,0,0,0,0,0,0,0,~
0,0,0,0,0,0,0,V47,0,0)';$S;
    'VSS1792':'(0,0,0,0,0,0,0,0,0,0,0,0,0,0,0,0,0,0,0,0,0,0,0,0,0,0,0,0,0,0,0,0,~
0,0,0,0,0,0,0,V44,0,0)';$S;
    'VSS1791':'(0,0,0,0,0,0,0,0,0,0,0,0,0,0,0,0,0,0,0,0,0,0,0,0,0,0,0,0,0,0,0,0,~
0,0,0,0,0,0,0,V42,0,0)';$S;
    'VSS1790':'(0,0,0,0,0,0,0,0,0,0,0,0,0,0,0,0,0,0,0,0,0,0,0,0,0,0,0,0,0,0,0,0,~
0,0,0,0,0,0,0,V40,0,0)';$S;
    'VSS1789':'(0,0,0,0,0,0,0,0,0,0,0,0,0,0,0,0,0,0,0,0,0,0,0,0,0,0,0,0,0,0,0,0,~
0,0,0,0,0,0,0,V49,0,0)';$S;
    'VSS1788':'(0,0,0,0,0,0,0,0,0,0,0,0,0,0,0,0,0,0,0,0,0,0,0,0,0,0,0,0,0,0,0,0,~
0,0,0,0,0,0,0,V4,0,0)';$S;
    'VSS1787':'(0,0,0,0,0,0,0,0,0,0,0,0,0,0,0,0,0,0,0,0,0,0,0,0,0,0,0,0,0,0,0,0,~
0,0,0,0,0,0,0,V38,0,0)';$S;
    'VSS1786':'(0,0,0,0,0,0,0,0,0,0,0,0,0,0,0,0,0,0,0,0,0,0,0,0,0,0,0,0,0,0,0,0,~
0,0,0,0,0,0,0,V36,0,0)';$S;
    'VSS1785':'(0,0,0,0,0,0,0,0,0,0,0,0,0,0,0,0,0,0,0,0,0,0,0,0,0,0,0,0,0,0,0,0,~
0,0,0,0,0,0,0,V34,0,0)';$S;
    'VSS1784':'(0,0,0,0,0,0,0,0,0,0,0,0,0,0,0,0,0,0,0,0,0,0,0,0,0,0,0,0,0,0,0,0,~
0,0,0,0,0,0,0,V32,0,0)';$S;
    'VSS1783':'(0,0,0,0,0,0,0,0,0,0,0,0,0,0,0,0,0,0,0,0,0,0,0,0,0,0,0,0,0,0,0,0,~
0,0,0,0,0,0,0,V30,0,0)';$S;
    'VSS1782':'(0,0,0,0,0,0,0,0,0,0,0,0,0,0,0,0,0,0,0,0,0,0,0,0,0,0,0,0,0,0,0,0,~
0,0,0,0,0,0,0,V28,0,0)';$S;
    'VSS1781':'(0,0,0,0,0,0,0,0,0,0,0,0,0,0,0,0,0,0,0,0,0,0,0,0,0,0,0,0,0,0,0,0,~
0,0,0,0,0,0,0,V26,0,0)';$S;
    'VSS1780':'(0,0,0,0,0,0,0,0,0,0,0,0,0,0,0,0,0,0,0,0,0,0,0,0,0,0,0,0,0,0,0,0,~
0,0,0,0,0,0,0,V24,0,0)';$S;
    'VSS1779':'(0,0,0,0,0,0,0,0,0,0,0,0,0,0,0,0,0,0,0,0,0,0,0,0,0,0,0,0,0,0,0,0,~
0,0,0,0,0,0,0,V22,0,0)';$S;
    'VSS1778':'(0,0,0,0,0,0,0,0,0,0,0,0,0,0,0,0,0,0,0,0,0,0,0,0,0,0,0,0,0,0,0,0,~
0,0,0,0,0,0,0,V20,0,0)';$S;
    'VSS1777':'(0,0,0,0,0,0,0,0,0,0,0,0,0,0,0,0,0,0,0,0,0,0,0,0,0,0,0,0,0,0,0,0,~
0,0,0,0,0,0,0,V18,0,0)';$S;
    'VSS1776':'(0,0,0,0,0,0,0,0,0,0,0,0,0,0,0,0,0,0,0,0,0,0,0,0,0,0,0,0,0,0,0,0,~
0,0,0,0,0,0,0,V16,0,0)';$S;
    'VSS1775':'(0,0,0,0,0,0,0,0,0,0,0,0,0,0,0,0,0,0,0,0,0,0,0,0,0,0,0,0,0,0,0,0,~
0,0,0,0,0,0,0,V12,0,0)';$S;
    'VSS1774':'(0,0,0,0,0,0,0,0,0,0,0,0,0,0,0,0,0,0,0,0,0,0,0,0,0,0,0,0,0,0,0,0,~
0,0,0,0,0,0,0,U88,0,0)';$S;
    'VSS1773':'(0,0,0,0,0,0,0,0,0,0,0,0,0,0,0,0,0,0,0,0,0,0,0,0,0,0,0,0,0,0,0,0,~
0,0,0,0,0,0,0,U84,0,0)';$S;
    'VSS1772':'(0,0,0,0,0,0,0,0,0,0,0,0,0,0,0,0,0,0,0,0,0,0,0,0,0,0,0,0,0,0,0,0,~
0,0,0,0,0,0,0,U82,0,0)';$S;
    'VSS1771':'(0,0,0,0,0,0,0,0,0,0,0,0,0,0,0,0,0,0,0,0,0,0,0,0,0,0,0,0,0,0,0,0,~
0,0,0,0,0,0,0,U39,0,0)';$S;
    'VSS1770':'(0,0,0,0,0,0,0,0,0,0,0,0,0,0,0,0,0,0,0,0,0,0,0,0,0,0,0,0,0,0,0,0,~
0,0,0,0,0,0,0,T83,0,0)';$S;
    'VSS1769':'(0,0,0,0,0,0,0,0,0,0,0,0,0,0,0,0,0,0,0,0,0,0,0,0,0,0,0,0,0,0,0,0,~
0,0,0,0,0,0,0,T8,0,0)';$S;
    'VSS1768':'(0,0,0,0,0,0,0,0,0,0,0,0,0,0,0,0,0,0,0,0,0,0,0,0,0,0,0,0,0,0,0,0,~
0,0,0,0,0,0,0,T79,0,0)';$S;
    'VSS1767':'(0,0,0,0,0,0,0,0,0,0,0,0,0,0,0,0,0,0,0,0,0,0,0,0,0,0,0,0,0,0,0,0,~
0,0,0,0,0,0,0,T73,0,0)';$S;
    'VSS1766':'(0,0,0,0,0,0,0,0,0,0,0,0,0,0,0,0,0,0,0,0,0,0,0,0,0,0,0,0,0,0,0,0,~
0,0,0,0,0,0,0,U52,0,0)';$S;
    'VSS1765':'(0,0,0,0,0,0,0,0,0,0,0,0,0,0,0,0,0,0,0,0,0,0,0,0,0,0,0,0,0,0,0,0,~
0,0,0,0,0,0,0,T67,0,0)';$S;
    'VSS1764':'(0,0,0,0,0,0,0,0,0,0,0,0,0,0,0,0,0,0,0,0,0,0,0,0,0,0,0,0,0,0,0,0,~
0,0,0,0,0,0,0,T61,0,0)';$S;
    'VSS1763':'(0,0,0,0,0,0,0,0,0,0,0,0,0,0,0,0,0,0,0,0,0,0,0,0,0,0,0,0,0,0,0,0,~
0,0,0,0,0,0,0,T42,0,0)';$S;
    'VSS1762':'(0,0,0,0,0,0,0,0,0,0,0,0,0,0,0,0,0,0,0,0,0,0,0,0,0,0,0,0,0,0,0,0,~
0,0,0,0,0,0,0,T4,0,0)';$S;
    'VSS1761':'(0,0,0,0,0,0,0,0,0,0,0,0,0,0,0,0,0,0,0,0,0,0,0,0,0,0,0,0,0,0,0,0,~
0,0,0,0,0,0,0,T30,0,0)';$S;
    'VSS1760':'(0,0,0,0,0,0,0,0,0,0,0,0,0,0,0,0,0,0,0,0,0,0,0,0,0,0,0,0,0,0,0,0,~
0,0,0,0,0,0,0,T24,0,0)';$S;
    'VSS1759':'(0,0,0,0,0,0,0,0,0,0,0,0,0,0,0,0,0,0,0,0,0,0,0,0,0,0,0,0,0,0,0,0,~
0,0,0,0,0,0,0,R9,0,0)';$S;
    'VSS1758':'(0,0,0,0,0,0,0,0,0,0,0,0,0,0,0,0,0,0,0,0,0,0,0,0,0,0,0,0,0,0,0,0,~
0,0,0,0,0,0,0,R88,0,0)';$S;
    'VSS1757':'(0,0,0,0,0,0,0,0,0,0,0,0,0,0,0,0,0,0,0,0,0,0,0,0,0,0,0,0,0,0,0,0,~
0,0,0,0,0,0,0,R84,0,0)';$S;
    'VSS1756':'(0,0,0,0,0,0,0,0,0,0,0,0,0,0,0,0,0,0,0,0,0,0,0,0,0,0,0,0,0,0,0,0,~
0,0,0,0,0,0,0,R78,0,0)';$S;
    'VSS1755':'(0,0,0,0,0,0,0,0,0,0,0,0,0,0,0,0,0,0,0,0,0,0,0,0,0,0,0,0,0,0,0,0,~
0,0,0,0,0,0,0,R74,0,0)';$S;
    'VSS1754':'(0,0,0,0,0,0,0,0,0,0,0,0,0,0,0,0,0,0,0,0,0,0,0,0,0,0,0,0,0,0,0,0,~
0,0,0,0,0,0,0,R72,0,0)';$S;
    'VSS1753':'(0,0,0,0,0,0,0,0,0,0,0,0,0,0,0,0,0,0,0,0,0,0,0,0,0,0,0,0,0,0,0,0,~
0,0,0,0,0,0,0,R68,0,0)';$S;
    'VSS1752':'(0,0,0,0,0,0,0,0,0,0,0,0,0,0,0,0,0,0,0,0,0,0,0,0,0,0,0,0,0,0,0,0,~
0,0,0,0,0,0,0,R62,0,0)';$S;
    'VSS1751':'(0,0,0,0,0,0,0,0,0,0,0,0,0,0,0,0,0,0,0,0,0,0,0,0,0,0,0,0,0,0,0,0,~
0,0,0,0,0,0,0,R56,0,0)';$S;
    'VSS1750':'(0,0,0,0,0,0,0,0,0,0,0,0,0,0,0,0,0,0,0,0,0,0,0,0,0,0,0,0,0,0,0,0,~
0,0,0,0,0,0,0,T55,0,0)';$S;
    'VSS1749':'(0,0,0,0,0,0,0,0,0,0,0,0,0,0,0,0,0,0,0,0,0,0,0,0,0,0,0,0,0,0,0,0,~
0,0,0,0,0,0,0,T49,0,0)';$S;
    'VSS1748':'(0,0,0,0,0,0,0,0,0,0,0,0,0,0,0,0,0,0,0,0,0,0,0,0,0,0,0,0,0,0,0,0,~
0,0,0,0,0,0,0,R54,0,0)';$S;
    'VSS1747':'(0,0,0,0,0,0,0,0,0,0,0,0,0,0,0,0,0,0,0,0,0,0,0,0,0,0,0,0,0,0,0,0,~
0,0,0,0,0,0,0,R50,0,0)';$S;
    'VSS1746':'(0,0,0,0,0,0,0,0,0,0,0,0,0,0,0,0,0,0,0,0,0,0,0,0,0,0,0,0,0,0,0,0,~
0,0,0,0,0,0,0,T36,0,0)';$S;
    'VSS1745':'(0,0,0,0,0,0,0,0,0,0,0,0,0,0,0,0,0,0,0,0,0,0,0,0,0,0,0,0,0,0,0,0,~
0,0,0,0,0,0,0,R5,0,0)';$S;
    'VSS1744':'(0,0,0,0,0,0,0,0,0,0,0,0,0,0,0,0,0,0,0,0,0,0,0,0,0,0,0,0,0,0,0,0,~
0,0,0,0,0,0,0,R43,0,0)';$S;
    'VSS1743':'(0,0,0,0,0,0,0,0,0,0,0,0,0,0,0,0,0,0,0,0,0,0,0,0,0,0,0,0,0,0,0,0,~
0,0,0,0,0,0,0,R41,0,0)';$S;
    'VSS1742':'(0,0,0,0,0,0,0,0,0,0,0,0,0,0,0,0,0,0,0,0,0,0,0,0,0,0,0,0,0,0,0,0,~
0,0,0,0,0,0,0,R37,0,0)';$S;
    'VSS1741':'(0,0,0,0,0,0,0,0,0,0,0,0,0,0,0,0,0,0,0,0,0,0,0,0,0,0,0,0,0,0,0,0,~
0,0,0,0,0,0,0,T18,0,0)';$S;
    'VSS1740':'(0,0,0,0,0,0,0,0,0,0,0,0,0,0,0,0,0,0,0,0,0,0,0,0,0,0,0,0,0,0,0,0,~
0,0,0,0,0,0,0,T16,0,0)';$S;
    'VSS1739':'(0,0,0,0,0,0,0,0,0,0,0,0,0,0,0,0,0,0,0,0,0,0,0,0,0,0,0,0,0,0,0,0,~
0,0,0,0,0,0,0,T12,0,0)';$S;
    'VSS1738':'(0,0,0,0,0,0,0,0,0,0,0,0,0,0,0,0,0,0,0,0,0,0,0,0,0,0,0,0,0,0,0,0,~
0,0,0,0,0,0,0,R35,0,0)';$S;
    'VSS1737':'(0,0,0,0,0,0,0,0,0,0,0,0,0,0,0,0,0,0,0,0,0,0,0,0,0,0,0,0,0,0,0,0,~
0,0,0,0,0,0,0,R31,0,0)';$S;
    'VSS1736':'(0,0,0,0,0,0,0,0,0,0,0,0,0,0,0,0,0,0,0,0,0,0,0,0,0,0,0,0,0,0,0,0,~
0,0,0,0,0,0,0,R29,0,0)';$S;
    'VSS1735':'(0,0,0,0,0,0,0,0,0,0,0,0,0,0,0,0,0,0,0,0,0,0,0,0,0,0,0,0,0,0,0,0,~
0,0,0,0,0,0,0,R25,0,0)';$S;
    'VSS1734':'(0,0,0,0,0,0,0,0,0,0,0,0,0,0,0,0,0,0,0,0,0,0,0,0,0,0,0,0,0,0,0,0,~
0,0,0,0,0,0,0,R17,0,0)';$S;
    'VSS1733':'(0,0,0,0,0,0,0,0,0,0,0,0,0,0,0,0,0,0,0,0,0,0,0,0,0,0,0,0,0,0,0,0,~
0,0,0,0,0,0,0,R13,0,0)';$S;
    'VSS1732':'(0,0,0,0,0,0,0,0,0,0,0,0,0,0,0,0,0,0,0,0,0,0,0,0,0,0,0,0,0,0,0,0,~
0,0,0,0,0,0,0,P91,0,0)';$S;
    'VSS1731':'(0,0,0,0,0,0,0,0,0,0,0,0,0,0,0,0,0,0,0,0,0,0,0,0,0,0,0,0,0,0,0,0,~
0,0,0,0,0,0,0,P87,0,0)';$S;
    'VSS1730':'(0,0,0,0,0,0,0,0,0,0,0,0,0,0,0,0,0,0,0,0,0,0,0,0,0,0,0,0,0,0,0,0,~
0,0,0,0,0,0,0,R66,0,0)';$S;
    'VSS1729':'(0,0,0,0,0,0,0,0,0,0,0,0,0,0,0,0,0,0,0,0,0,0,0,0,0,0,0,0,0,0,0,0,~
0,0,0,0,0,0,0,P8,0,0)';$S;
    'VSS1728':'(0,0,0,0,0,0,0,0,0,0,0,0,0,0,0,0,0,0,0,0,0,0,0,0,0,0,0,0,0,0,0,0,~
0,0,0,0,0,0,0,R60,0,0)';$S;
    'VSS1727':'(0,0,0,0,0,0,0,0,0,0,0,0,0,0,0,0,0,0,0,0,0,0,0,0,0,0,0,0,0,0,0,0,~
0,0,0,0,0,0,0,P77,0,0)';$S;
    'VSS1726':'(0,0,0,0,0,0,0,0,0,0,0,0,0,0,0,0,0,0,0,0,0,0,0,0,0,0,0,0,0,0,0,0,~
0,0,0,0,0,0,0,P75,0,0)';$S;
    'VSS1725':'(0,0,0,0,0,0,0,0,0,0,0,0,0,0,0,0,0,0,0,0,0,0,0,0,0,0,0,0,0,0,0,0,~
0,0,0,0,0,0,0,P69,0,0)';$S;
    'VSS1724':'(0,0,0,0,0,0,0,0,0,0,0,0,0,0,0,0,0,0,0,0,0,0,0,0,0,0,0,0,0,0,0,0,~
0,0,0,0,0,0,0,P65,0,0)';$S;
    'VSS1723':'(0,0,0,0,0,0,0,0,0,0,0,0,0,0,0,0,0,0,0,0,0,0,0,0,0,0,0,0,0,0,0,0,~
0,0,0,0,0,0,0,R48,0,0)';$S;
    'VSS1722':'(0,0,0,0,0,0,0,0,0,0,0,0,0,0,0,0,0,0,0,0,0,0,0,0,0,0,0,0,0,0,0,0,~
0,0,0,0,0,0,0,P63,0,0)';$S;
    'VSS1721':'(0,0,0,0,0,0,0,0,0,0,0,0,0,0,0,0,0,0,0,0,0,0,0,0,0,0,0,0,0,0,0,0,~
0,0,0,0,0,0,0,P59,0,0)';$S;
    'VSS1720':'(0,0,0,0,0,0,0,0,0,0,0,0,0,0,0,0,0,0,0,0,0,0,0,0,0,0,0,0,0,0,0,0,~
0,0,0,0,0,0,0,P53,0,0)';$S;
    'VSS1719':'(0,0,0,0,0,0,0,0,0,0,0,0,0,0,0,0,0,0,0,0,0,0,0,0,0,0,0,0,0,0,0,0,~
0,0,0,0,0,0,0,P47,0,0)';$S;
    'VSS1718':'(0,0,0,0,0,0,0,0,0,0,0,0,0,0,0,0,0,0,0,0,0,0,0,0,0,0,0,0,0,0,0,0,~
0,0,0,0,0,0,0,P44,0,0)';$S;
    'VSS1717':'(0,0,0,0,0,0,0,0,0,0,0,0,0,0,0,0,0,0,0,0,0,0,0,0,0,0,0,0,0,0,0,0,~
0,0,0,0,0,0,0,P40,0,0)';$S;
    'VSS1716':'(0,0,0,0,0,0,0,0,0,0,0,0,0,0,0,0,0,0,0,0,0,0,0,0,0,0,0,0,0,0,0,0,~
0,0,0,0,0,0,0,P4,0,0)';$S;
    'VSS1715':'(0,0,0,0,0,0,0,0,0,0,0,0,0,0,0,0,0,0,0,0,0,0,0,0,0,0,0,0,0,0,0,0,~
0,0,0,0,0,0,0,R23,0,0)';$S;
    'VSS1714':'(0,0,0,0,0,0,0,0,0,0,0,0,0,0,0,0,0,0,0,0,0,0,0,0,0,0,0,0,0,0,0,0,~
0,0,0,0,0,0,0,R19,0,0)';$S;
    'VSS1713':'(0,0,0,0,0,0,0,0,0,0,0,0,0,0,0,0,0,0,0,0,0,0,0,0,0,0,0,0,0,0,0,0,~
0,0,0,0,0,0,0,P38,0,0)';$S;
    'VSS1712':'(0,0,0,0,0,0,0,0,0,0,0,0,0,0,0,0,0,0,0,0,0,0,0,0,0,0,0,0,0,0,0,0,~
0,0,0,0,0,0,0,P34,0,0)';$S;
    'VSS1711':'(0,0,0,0,0,0,0,0,0,0,0,0,0,0,0,0,0,0,0,0,0,0,0,0,0,0,0,0,0,0,0,0,~
0,0,0,0,0,0,0,R1,0,0)';$S;
    'VSS1710':'(0,0,0,0,0,0,0,0,0,0,0,0,0,0,0,0,0,0,0,0,0,0,0,0,0,0,0,0,0,0,0,0,~
0,0,0,0,0,0,0,P28,0,0)';$S;
    'VSS1709':'(0,0,0,0,0,0,0,0,0,0,0,0,0,0,0,0,0,0,0,0,0,0,0,0,0,0,0,0,0,0,0,0,~
0,0,0,0,0,0,0,P26,0,0)';$S;
    'VSS1708':'(0,0,0,0,0,0,0,0,0,0,0,0,0,0,0,0,0,0,0,0,0,0,0,0,0,0,0,0,0,0,0,0,~
0,0,0,0,0,0,0,P22,0,0)';$S;
    'VSS1707':'(0,0,0,0,0,0,0,0,0,0,0,0,0,0,0,0,0,0,0,0,0,0,0,0,0,0,0,0,0,0,0,0,~
0,0,0,0,0,0,0,P20,0,0)';$S;
    'VSS1706':'(0,0,0,0,0,0,0,0,0,0,0,0,0,0,0,0,0,0,0,0,0,0,0,0,0,0,0,0,0,0,0,0,~
0,0,0,0,0,0,0,P16,0,0)';$S;
    'VSS1705':'(0,0,0,0,0,0,0,0,0,0,0,0,0,0,0,0,0,0,0,0,0,0,0,0,0,0,0,0,0,0,0,0,~
0,0,0,0,0,0,0,P12,0,0)';$S;
    'VSS1704':'(0,0,0,0,0,0,0,0,0,0,0,0,0,0,0,0,0,0,0,0,0,0,0,0,0,0,0,0,0,0,0,0,~
0,0,0,0,0,0,0,P71,0,0)';$S;
    'VSS1703':'(0,0,0,0,0,0,0,0,0,0,0,0,0,0,0,0,0,0,0,0,0,0,0,0,0,0,0,0,0,0,0,0,~
0,0,0,0,0,0,0,N88,0,0)';$S;
    'VSS1702':'(0,0,0,0,0,0,0,0,0,0,0,0,0,0,0,0,0,0,0,0,0,0,0,0,0,0,0,0,0,0,0,0,~
0,0,0,0,0,0,0,N84,0,0)';$S;
    'VSS1701':'(0,0,0,0,0,0,0,0,0,0,0,0,0,0,0,0,0,0,0,0,0,0,0,0,0,0,0,0,0,0,0,0,~
0,0,0,0,0,0,0,N82,0,0)';$S;
    'VSS1700':'(0,0,0,0,0,0,0,0,0,0,0,0,0,0,0,0,0,0,0,0,0,0,0,0,0,0,0,0,0,0,0,0,~
0,0,0,0,0,0,0,N80,0,0)';$S;
    'VSS1699':'(0,0,0,0,0,0,0,0,0,0,0,0,0,0,0,0,0,0,0,0,0,0,0,0,0,0,0,0,0,0,0,0,~
0,0,0,0,0,0,0,P57,0,0)';$S;
    'VSS1698':'(0,0,0,0,0,0,0,0,0,0,0,0,0,0,0,0,0,0,0,0,0,0,0,0,0,0,0,0,0,0,0,0,~
0,0,0,0,0,0,0,N78,0,0)';$S;
    'VSS1697':'(0,0,0,0,0,0,0,0,0,0,0,0,0,0,0,0,0,0,0,0,0,0,0,0,0,0,0,0,0,0,0,0,~
0,0,0,0,0,0,0,P51,0,0)';$S;
    'VSS1696':'(0,0,0,0,0,0,0,0,0,0,0,0,0,0,0,0,0,0,0,0,0,0,0,0,0,0,0,0,0,0,0,0,~
0,0,0,0,0,0,0,N76,0,0)';$S;
    'VSS1690':'(0,0,0,0,0,0,0,0,0,0,0,0,0,0,0,0,0,0,0,0,0,0,0,0,0,0,0,0,0,0,0,0,~
0,0,0,0,0,0,0,P32,0,0)';$S;
    'VSS37':'(0,0,0,0,0,0,0,0,0,0,0,0,0,0,0,0,0,0,0,0,0,0,0,0,0,0,0,0,0,0,0,0,0,~
0,0,0,0,0,0,AA80,0,0)';$S;
    'VSS36':'(0,0,0,0,0,0,0,0,0,0,0,0,0,0,0,0,0,0,0,0,0,0,0,0,0,0,0,0,0,0,0,0,0,~
0,0,0,0,0,0,AA78,0,0)';$S;
    'VSS35':'(0,0,0,0,0,0,0,0,0,0,0,0,0,0,0,0,0,0,0,0,0,0,0,0,0,0,0,0,0,0,0,0,0,~
0,0,0,0,0,0,AA74,0,0)';$S;
    'VSS34':'(0,0,0,0,0,0,0,0,0,0,0,0,0,0,0,0,0,0,0,0,0,0,0,0,0,0,0,0,0,0,0,0,0,~
0,0,0,0,0,0,AA72,0,0)';$S;
    'VSS33':'(0,0,0,0,0,0,0,0,0,0,0,0,0,0,0,0,0,0,0,0,0,0,0,0,0,0,0,0,0,0,0,0,0,~
0,0,0,0,0,0,AA68,0,0)';$S;
    'VSS32':'(0,0,0,0,0,0,0,0,0,0,0,0,0,0,0,0,0,0,0,0,0,0,0,0,0,0,0,0,0,0,0,0,0,~
0,0,0,0,0,0,AA66,0,0)';$S;
    'VSS31':'(0,0,0,0,0,0,0,0,0,0,0,0,0,0,0,0,0,0,0,0,0,0,0,0,0,0,0,0,0,0,0,0,0,~
0,0,0,0,0,0,AA62,0,0)';$S;
    'VSS30':'(0,0,0,0,0,0,0,0,0,0,0,0,0,0,0,0,0,0,0,0,0,0,0,0,0,0,0,0,0,0,0,0,0,~
0,0,0,0,0,0,AA60,0,0)';$S;
    'VSS29':'(0,0,0,0,0,0,0,0,0,0,0,0,0,0,0,0,0,0,0,0,0,0,0,0,0,0,0,0,0,0,0,0,0,~
0,0,0,0,0,0,AA56,0,0)';$S;
    'VSS28':'(0,0,0,0,0,0,0,0,0,0,0,0,0,0,0,0,0,0,0,0,0,0,0,0,0,0,0,0,0,0,0,0,0,~
0,0,0,0,0,0,AA54,0,0)';$S;
    'VSS27':'(0,0,0,0,0,0,0,0,0,0,0,0,0,0,0,0,0,0,0,0,0,0,0,0,0,0,0,0,0,0,0,0,0,~
0,0,0,0,0,0,AA50,0,0)';$S;
    'VSS26':'(0,0,0,0,0,0,0,0,0,0,0,0,0,0,0,0,0,0,0,0,0,0,0,0,0,0,0,0,0,0,0,0,0,~
0,0,0,0,0,0,AA48,0,0)';$S;
    'VSS25':'(0,0,0,0,0,0,0,0,0,0,0,0,0,0,0,0,0,0,0,0,0,0,0,0,0,0,0,0,0,0,0,0,0,~
0,0,0,0,0,0,AA43,0,0)';$S;
    'VSS24':'(0,0,0,0,0,0,0,0,0,0,0,0,0,0,0,0,0,0,0,0,0,0,0,0,0,0,0,0,0,0,0,0,0,~
0,0,0,0,0,0,AA41,0,0)';$S;
    'VSS23':'(0,0,0,0,0,0,0,0,0,0,0,0,0,0,0,0,0,0,0,0,0,0,0,0,0,0,0,0,0,0,0,0,0,~
0,0,0,0,0,0,AA37,0,0)';$S;
    'VSS22':'(0,0,0,0,0,0,0,0,0,0,0,0,0,0,0,0,0,0,0,0,0,0,0,0,0,0,0,0,0,0,0,0,0,~
0,0,0,0,0,0,AA35,0,0)';$S;
    'VSS21':'(0,0,0,0,0,0,0,0,0,0,0,0,0,0,0,0,0,0,0,0,0,0,0,0,0,0,0,0,0,0,0,0,0,~
0,0,0,0,0,0,AA31,0,0)';$S;
    'VSS20':'(0,0,0,0,0,0,0,0,0,0,0,0,0,0,0,0,0,0,0,0,0,0,0,0,0,0,0,0,0,0,0,0,0,~
0,0,0,0,0,0,AA29,0,0)';$S;
    'VSS19':'(0,0,0,0,0,0,0,0,0,0,0,0,0,0,0,0,0,0,0,0,0,0,0,0,0,0,0,0,0,0,0,0,0,~
0,0,0,0,0,0,AA25,0,0)';$S;
    'VSS18':'(0,0,0,0,0,0,0,0,0,0,0,0,0,0,0,0,0,0,0,0,0,0,0,0,0,0,0,0,0,0,0,0,0,~
0,0,0,0,0,0,AA23,0,0)';$S;
    'VSS17':'(0,0,0,0,0,0,0,0,0,0,0,0,0,0,0,0,0,0,0,0,0,0,0,0,0,0,0,0,0,0,0,0,0,~
0,0,0,0,0,0,AA19,0,0)';$S;
    'VSS1695':'(0,0,0,0,0,0,0,0,0,0,0,0,0,0,0,0,0,0,0,0,0,0,0,0,0,0,0,0,0,0,0,0,~
0,0,0,0,0,0,0,0,N70,0)';$S;
    'VSS1694':'(0,0,0,0,0,0,0,0,0,0,0,0,0,0,0,0,0,0,0,0,0,0,0,0,0,0,0,0,0,0,0,0,~
0,0,0,0,0,0,0,0,N58,0)';$S;
    'VSS1693':'(0,0,0,0,0,0,0,0,0,0,0,0,0,0,0,0,0,0,0,0,0,0,0,0,0,0,0,0,0,0,0,0,~
0,0,0,0,0,0,0,0,N52,0)';$S;
    'VSS1692':'(0,0,0,0,0,0,0,0,0,0,0,0,0,0,0,0,0,0,0,0,0,0,0,0,0,0,0,0,0,0,0,0,~
0,0,0,0,0,0,0,0,N45,0)';$S;
    'VSS1691':'(0,0,0,0,0,0,0,0,0,0,0,0,0,0,0,0,0,0,0,0,0,0,0,0,0,0,0,0,0,0,0,0,~
0,0,0,0,0,0,0,0,N33,0)';$S;
    'VSS1689':'(0,0,0,0,0,0,0,0,0,0,0,0,0,0,0,0,0,0,0,0,0,0,0,0,0,0,0,0,0,0,0,0,~
0,0,0,0,0,0,0,0,N27,0)';$S;
    'VSS1688':'(0,0,0,0,0,0,0,0,0,0,0,0,0,0,0,0,0,0,0,0,0,0,0,0,0,0,0,0,0,0,0,0,~
0,0,0,0,0,0,0,0,N15,0)';$S;
    'VSS1687':'(0,0,0,0,0,0,0,0,0,0,0,0,0,0,0,0,0,0,0,0,0,0,0,0,0,0,0,0,0,0,0,0,~
0,0,0,0,0,0,0,0,M83,0)';$S;
    'VSS1686':'(0,0,0,0,0,0,0,0,0,0,0,0,0,0,0,0,0,0,0,0,0,0,0,0,0,0,0,0,0,0,0,0,~
0,0,0,0,0,0,0,0,M81,0)';$S;
    'VSS1685':'(0,0,0,0,0,0,0,0,0,0,0,0,0,0,0,0,0,0,0,0,0,0,0,0,0,0,0,0,0,0,0,0,~
0,0,0,0,0,0,0,0,L78,0)';$S;
    'VSS1684':'(0,0,0,0,0,0,0,0,0,0,0,0,0,0,0,0,0,0,0,0,0,0,0,0,0,0,0,0,0,0,0,0,~
0,0,0,0,0,0,0,0,L76,0)';$S;
    'VSS1683':'(0,0,0,0,0,0,0,0,0,0,0,0,0,0,0,0,0,0,0,0,0,0,0,0,0,0,0,0,0,0,0,0,~
0,0,0,0,0,0,0,0,L74,0)';$S;
    'VSS1682':'(0,0,0,0,0,0,0,0,0,0,0,0,0,0,0,0,0,0,0,0,0,0,0,0,0,0,0,0,0,0,0,0,~
0,0,0,0,0,0,0,0,L72,0)';$S;
    'VSS1681':'(0,0,0,0,0,0,0,0,0,0,0,0,0,0,0,0,0,0,0,0,0,0,0,0,0,0,0,0,0,0,0,0,~
0,0,0,0,0,0,0,0,L68,0)';$S;
    'VSS1680':'(0,0,0,0,0,0,0,0,0,0,0,0,0,0,0,0,0,0,0,0,0,0,0,0,0,0,0,0,0,0,0,0,~
0,0,0,0,0,0,0,0,L66,0)';$S;
    'VSS1679':'(0,0,0,0,0,0,0,0,0,0,0,0,0,0,0,0,0,0,0,0,0,0,0,0,0,0,0,0,0,0,0,0,~
0,0,0,0,0,0,0,0,L64,0)';$S;
    'VSS1678':'(0,0,0,0,0,0,0,0,0,0,0,0,0,0,0,0,0,0,0,0,0,0,0,0,0,0,0,0,0,0,0,0,~
0,0,0,0,0,0,0,0,L62,0)';$S;
    'VSS1677':'(0,0,0,0,0,0,0,0,0,0,0,0,0,0,0,0,0,0,0,0,0,0,0,0,0,0,0,0,0,0,0,0,~
0,0,0,0,0,0,0,0,L60,0)';$S;
    'VSS1676':'(0,0,0,0,0,0,0,0,0,0,0,0,0,0,0,0,0,0,0,0,0,0,0,0,0,0,0,0,0,0,0,0,~
0,0,0,0,0,0,0,0,L56,0)';$S;
    'VSS1675':'(0,0,0,0,0,0,0,0,0,0,0,0,0,0,0,0,0,0,0,0,0,0,0,0,0,0,0,0,0,0,0,0,~
0,0,0,0,0,0,0,0,N64,0)';$S;
    'VSS1674':'(0,0,0,0,0,0,0,0,0,0,0,0,0,0,0,0,0,0,0,0,0,0,0,0,0,0,0,0,0,0,0,0,~
0,0,0,0,0,0,0,0,L54,0)';$S;
    'VSS1673':'(0,0,0,0,0,0,0,0,0,0,0,0,0,0,0,0,0,0,0,0,0,0,0,0,0,0,0,0,0,0,0,0,~
0,0,0,0,0,0,0,0,L52,0)';$S;
    'VSS1672':'(0,0,0,0,0,0,0,0,0,0,0,0,0,0,0,0,0,0,0,0,0,0,0,0,0,0,0,0,0,0,0,0,~
0,0,0,0,0,0,0,0,L50,0)';$S;
    'VSS1671':'(0,0,0,0,0,0,0,0,0,0,0,0,0,0,0,0,0,0,0,0,0,0,0,0,0,0,0,0,0,0,0,0,~
0,0,0,0,0,0,0,0,L5,0)';$S;
    'VSS1670':'(0,0,0,0,0,0,0,0,0,0,0,0,0,0,0,0,0,0,0,0,0,0,0,0,0,0,0,0,0,0,0,0,~
0,0,0,0,0,0,0,0,L48,0)';$S;
    'VSS1669':'(0,0,0,0,0,0,0,0,0,0,0,0,0,0,0,0,0,0,0,0,0,0,0,0,0,0,0,0,0,0,0,0,~
0,0,0,0,0,0,0,0,N39,0)';$S;
    'VSS1668':'(0,0,0,0,0,0,0,0,0,0,0,0,0,0,0,0,0,0,0,0,0,0,0,0,0,0,0,0,0,0,0,0,~
0,0,0,0,0,0,0,0,L45,0)';$S;
    'VSS1667':'(0,0,0,0,0,0,0,0,0,0,0,0,0,0,0,0,0,0,0,0,0,0,0,0,0,0,0,0,0,0,0,0,~
0,0,0,0,0,0,0,0,L43,0)';$S;
    'VSS1666':'(0,0,0,0,0,0,0,0,0,0,0,0,0,0,0,0,0,0,0,0,0,0,0,0,0,0,0,0,0,0,0,0,~
0,0,0,0,0,0,0,0,L41,0)';$S;
    'VSS1665':'(0,0,0,0,0,0,0,0,0,0,0,0,0,0,0,0,0,0,0,0,0,0,0,0,0,0,0,0,0,0,0,0,~
0,0,0,0,0,0,0,0,L39,0)';$S;
    'VSS1664':'(0,0,0,0,0,0,0,0,0,0,0,0,0,0,0,0,0,0,0,0,0,0,0,0,0,0,0,0,0,0,0,0,~
0,0,0,0,0,0,0,0,N21,0)';$S;
    'VSS1663':'(0,0,0,0,0,0,0,0,0,0,0,0,0,0,0,0,0,0,0,0,0,0,0,0,0,0,0,0,0,0,0,0,~
0,0,0,0,0,0,0,0,L37,0)';$S;
    'VSS1662':'(0,0,0,0,0,0,0,0,0,0,0,0,0,0,0,0,0,0,0,0,0,0,0,0,0,0,0,0,0,0,0,0,~
0,0,0,0,0,0,0,0,L35,0)';$S;
    'VSS1661':'(0,0,0,0,0,0,0,0,0,0,0,0,0,0,0,0,0,0,0,0,0,0,0,0,0,0,0,0,0,0,0,0,~
0,0,0,0,0,0,0,0,L33,0)';$S;
    'VSS1660':'(0,0,0,0,0,0,0,0,0,0,0,0,0,0,0,0,0,0,0,0,0,0,0,0,0,0,0,0,0,0,0,0,~
0,0,0,0,0,0,0,0,L31,0)';$S;
    'VSS1659':'(0,0,0,0,0,0,0,0,0,0,0,0,0,0,0,0,0,0,0,0,0,0,0,0,0,0,0,0,0,0,0,0,~
0,0,0,0,0,0,0,0,L29,0)';$S;
    'VSS1658':'(0,0,0,0,0,0,0,0,0,0,0,0,0,0,0,0,0,0,0,0,0,0,0,0,0,0,0,0,0,0,0,0,~
0,0,0,0,0,0,0,0,L27,0)';$S;
    'VSS1657':'(0,0,0,0,0,0,0,0,0,0,0,0,0,0,0,0,0,0,0,0,0,0,0,0,0,0,0,0,0,0,0,0,~
0,0,0,0,0,0,0,0,M8,0)';$S;
    'VSS1656':'(0,0,0,0,0,0,0,0,0,0,0,0,0,0,0,0,0,0,0,0,0,0,0,0,0,0,0,0,0,0,0,0,~
0,0,0,0,0,0,0,0,L25,0)';$S;
    'VSS1655':'(0,0,0,0,0,0,0,0,0,0,0,0,0,0,0,0,0,0,0,0,0,0,0,0,0,0,0,0,0,0,0,0,~
0,0,0,0,0,0,0,0,L23,0)';$S;
    'VSS1654':'(0,0,0,0,0,0,0,0,0,0,0,0,0,0,0,0,0,0,0,0,0,0,0,0,0,0,0,0,0,0,0,0,~
0,0,0,0,0,0,0,0,M49,0)';$S;
    'VSS1653':'(0,0,0,0,0,0,0,0,0,0,0,0,0,0,0,0,0,0,0,0,0,0,0,0,0,0,0,0,0,0,0,0,~
0,0,0,0,0,0,0,0,M42,0)';$S;
    'VSS1652':'(0,0,0,0,0,0,0,0,0,0,0,0,0,0,0,0,0,0,0,0,0,0,0,0,0,0,0,0,0,0,0,0,~
0,0,0,0,0,0,0,0,M4,0)';$S;
    'VSS1651':'(0,0,0,0,0,0,0,0,0,0,0,0,0,0,0,0,0,0,0,0,0,0,0,0,0,0,0,0,0,0,0,0,~
0,0,0,0,0,0,0,0,L21,0)';$S;
    'VSS1650':'(0,0,0,0,0,0,0,0,0,0,0,0,0,0,0,0,0,0,0,0,0,0,0,0,0,0,0,0,0,0,0,0,~
0,0,0,0,0,0,0,0,L17,0)';$S;
    'VSS1649':'(0,0,0,0,0,0,0,0,0,0,0,0,0,0,0,0,0,0,0,0,0,0,0,0,0,0,0,0,0,0,0,0,~
0,0,0,0,0,0,0,0,M12,0)';$S;
    'VSS1648':'(0,0,0,0,0,0,0,0,0,0,0,0,0,0,0,0,0,0,0,0,0,0,0,0,0,0,0,0,0,0,0,0,~
0,0,0,0,0,0,0,0,L90,0)';$S;
    'VSS1647':'(0,0,0,0,0,0,0,0,0,0,0,0,0,0,0,0,0,0,0,0,0,0,0,0,0,0,0,0,0,0,0,0,~
0,0,0,0,0,0,0,0,L9,0)';$S;
    'VSS1646':'(0,0,0,0,0,0,0,0,0,0,0,0,0,0,0,0,0,0,0,0,0,0,0,0,0,0,0,0,0,0,0,0,~
0,0,0,0,0,0,0,0,L88,0)';$S;
    'VSS1645':'(0,0,0,0,0,0,0,0,0,0,0,0,0,0,0,0,0,0,0,0,0,0,0,0,0,0,0,0,0,0,0,0,~
0,0,0,0,0,0,0,0,L15,0)';$S;
    'VSS1644':'(0,0,0,0,0,0,0,0,0,0,0,0,0,0,0,0,0,0,0,0,0,0,0,0,0,0,0,0,0,0,0,0,~
0,0,0,0,0,0,0,0,L13,0)';$S;
    'VSS1643':'(0,0,0,0,0,0,0,0,0,0,0,0,0,0,0,0,0,0,0,0,0,0,0,0,0,0,0,0,0,0,0,0,~
0,0,0,0,0,0,0,0,K85,0)';$S;
    'VSS1642':'(0,0,0,0,0,0,0,0,0,0,0,0,0,0,0,0,0,0,0,0,0,0,0,0,0,0,0,0,0,0,0,0,~
0,0,0,0,0,0,0,0,K83,0)';$S;
    'VSS1641':'(0,0,0,0,0,0,0,0,0,0,0,0,0,0,0,0,0,0,0,0,0,0,0,0,0,0,0,0,0,0,0,0,~
0,0,0,0,0,0,0,0,K8,0)';$S;
    'VSS1640':'(0,0,0,0,0,0,0,0,0,0,0,0,0,0,0,0,0,0,0,0,0,0,0,0,0,0,0,0,0,0,0,0,~
0,0,0,0,0,0,0,0,L70,0)';$S;
    'VSS1639':'(0,0,0,0,0,0,0,0,0,0,0,0,0,0,0,0,0,0,0,0,0,0,0,0,0,0,0,0,0,0,0,0,~
0,0,0,0,0,0,0,0,K77,0)';$S;
    'VSS1638':'(0,0,0,0,0,0,0,0,0,0,0,0,0,0,0,0,0,0,0,0,0,0,0,0,0,0,0,0,0,0,0,0,~
0,0,0,0,0,0,0,0,J86,0)';$S;
    'VSS1637':'(0,0,0,0,0,0,0,0,0,0,0,0,0,0,0,0,0,0,0,0,0,0,0,0,0,0,0,0,0,0,0,0,~
0,0,0,0,0,0,0,0,J84,0)';$S;
    'VSS1636':'(0,0,0,0,0,0,0,0,0,0,0,0,0,0,0,0,0,0,0,0,0,0,0,0,0,0,0,0,0,0,0,0,~
0,0,0,0,0,0,0,0,J78,0)';$S;
    'VSS1635':'(0,0,0,0,0,0,0,0,0,0,0,0,0,0,0,0,0,0,0,0,0,0,0,0,0,0,0,0,0,0,0,0,~
0,0,0,0,0,0,0,0,J76,0)';$S;
    'VSS1634':'(0,0,0,0,0,0,0,0,0,0,0,0,0,0,0,0,0,0,0,0,0,0,0,0,0,0,0,0,0,0,0,0,~
0,0,0,0,0,0,0,0,L58,0)';$S;
    'VSS1633':'(0,0,0,0,0,0,0,0,0,0,0,0,0,0,0,0,0,0,0,0,0,0,0,0,0,0,0,0,0,0,0,0,~
0,0,0,0,0,0,0,0,J58,0)';$S;
    'VSS1632':'(0,0,0,0,0,0,0,0,0,0,0,0,0,0,0,0,0,0,0,0,0,0,0,0,0,0,0,0,0,0,0,0,~
0,0,0,0,0,0,0,0,J52,0)';$S;
    'VSS1631':'(0,0,0,0,0,0,0,0,0,0,0,0,0,0,0,0,0,0,0,0,0,0,0,0,0,0,0,0,0,0,0,0,~
0,0,0,0,0,0,0,0,J45,0)';$S;
    'VSS1630':'(0,0,0,0,0,0,0,0,0,0,0,0,0,0,0,0,0,0,0,0,0,0,0,0,0,0,0,0,0,0,0,0,~
0,0,0,0,0,0,0,0,J33,0)';$S;
    'VSS1629':'(0,0,0,0,0,0,0,0,0,0,0,0,0,0,0,0,0,0,0,0,0,0,0,0,0,0,0,0,0,0,0,0,~
0,0,0,0,0,0,0,0,J27,0)';$S;
    'VSS1628':'(0,0,0,0,0,0,0,0,0,0,0,0,0,0,0,0,0,0,0,0,0,0,0,0,0,0,0,0,0,0,0,0,~
0,0,0,0,0,0,0,0,J15,0)';$S;
    'VSS1627':'(0,0,0,0,0,0,0,0,0,0,0,0,0,0,0,0,0,0,0,0,0,0,0,0,0,0,0,0,0,0,0,0,~
0,0,0,0,0,0,0,0,H81,0)';$S;
    'VSS1626':'(0,0,0,0,0,0,0,0,0,0,0,0,0,0,0,0,0,0,0,0,0,0,0,0,0,0,0,0,0,0,0,0,~
0,0,0,0,0,0,0,0,H8,0)';$S;
    'VSS1625':'(0,0,0,0,0,0,0,0,0,0,0,0,0,0,0,0,0,0,0,0,0,0,0,0,0,0,0,0,0,0,0,0,~
0,0,0,0,0,0,0,0,H79,0)';$S;
    'VSS1624':'(0,0,0,0,0,0,0,0,0,0,0,0,0,0,0,0,0,0,0,0,0,0,0,0,0,0,0,0,0,0,0,0,~
0,0,0,0,0,0,0,0,H71,0)';$S;
    'VSS1623':'(0,0,0,0,0,0,0,0,0,0,0,0,0,0,0,0,0,0,0,0,0,0,0,0,0,0,0,0,0,0,0,0,~
0,0,0,0,0,0,0,0,H69,0)';$S;
    'VSS1622':'(0,0,0,0,0,0,0,0,0,0,0,0,0,0,0,0,0,0,0,0,0,0,0,0,0,0,0,0,0,0,0,0,~
0,0,0,0,0,0,0,0,H63,0)';$S;
    'VSS1621':'(0,0,0,0,0,0,0,0,0,0,0,0,0,0,0,0,0,0,0,0,0,0,0,0,0,0,0,0,0,0,0,0,~
0,0,0,0,0,0,0,0,H6,0)';$S;
    'VSS1620':'(0,0,0,0,0,0,0,0,0,0,0,0,0,0,0,0,0,0,0,0,0,0,0,0,0,0,0,0,0,0,0,0,~
0,0,0,0,0,0,0,0,H59,0)';$S;
    'VSS1619':'(0,0,0,0,0,0,0,0,0,0,0,0,0,0,0,0,0,0,0,0,0,0,0,0,0,0,0,0,0,0,0,0,~
0,0,0,0,0,0,0,0,H53,0)';$S;
    'VSS1618':'(0,0,0,0,0,0,0,0,0,0,0,0,0,0,0,0,0,0,0,0,0,0,0,0,0,0,0,0,0,0,0,0,~
0,0,0,0,0,0,0,0,H47,0)';$S;
    'VSS1617':'(0,0,0,0,0,0,0,0,0,0,0,0,0,0,0,0,0,0,0,0,0,0,0,0,0,0,0,0,0,0,0,0,~
0,0,0,0,0,0,0,0,H44,0)';$S;
    'VSS1616':'(0,0,0,0,0,0,0,0,0,0,0,0,0,0,0,0,0,0,0,0,0,0,0,0,0,0,0,0,0,0,0,0,~
0,0,0,0,0,0,0,0,H40,0)';$S;
    'VSS1615':'(0,0,0,0,0,0,0,0,0,0,0,0,0,0,0,0,0,0,0,0,0,0,0,0,0,0,0,0,0,0,0,0,~
0,0,0,0,0,0,0,0,H4,0)';$S;
    'VSS1614':'(0,0,0,0,0,0,0,0,0,0,0,0,0,0,0,0,0,0,0,0,0,0,0,0,0,0,0,0,0,0,0,0,~
0,0,0,0,0,0,0,0,L19,0)';$S;
    'VSS1613':'(0,0,0,0,0,0,0,0,0,0,0,0,0,0,0,0,0,0,0,0,0,0,0,0,0,0,0,0,0,0,0,0,~
0,0,0,0,0,0,0,0,H38,0)';$S;
    'VSS1612':'(0,0,0,0,0,0,0,0,0,0,0,0,0,0,0,0,0,0,0,0,0,0,0,0,0,0,0,0,0,0,0,0,~
0,0,0,0,0,0,0,0,H34,0)';$S;
    'VSS1611':'(0,0,0,0,0,0,0,0,0,0,0,0,0,0,0,0,0,0,0,0,0,0,0,0,0,0,0,0,0,0,0,0,~
0,0,0,0,0,0,0,0,H32,0)';$S;
    'VSS1610':'(0,0,0,0,0,0,0,0,0,0,0,0,0,0,0,0,0,0,0,0,0,0,0,0,0,0,0,0,0,0,0,0,~
0,0,0,0,0,0,0,0,H28,0)';$S;
    'VSS1609':'(0,0,0,0,0,0,0,0,0,0,0,0,0,0,0,0,0,0,0,0,0,0,0,0,0,0,0,0,0,0,0,0,~
0,0,0,0,0,0,0,0,H26,0)';$S;
    'VSS1608':'(0,0,0,0,0,0,0,0,0,0,0,0,0,0,0,0,0,0,0,0,0,0,0,0,0,0,0,0,0,0,0,0,~
0,0,0,0,0,0,0,0,H22,0)';$S;
    'VSS1607':'(0,0,0,0,0,0,0,0,0,0,0,0,0,0,0,0,0,0,0,0,0,0,0,0,0,0,0,0,0,0,0,0,~
0,0,0,0,0,0,0,0,H20,0)';$S;
    'VSS1606':'(0,0,0,0,0,0,0,0,0,0,0,0,0,0,0,0,0,0,0,0,0,0,0,0,0,0,0,0,0,0,0,0,~
0,0,0,0,0,0,0,0,H16,0)';$S;
    'VSS1605':'(0,0,0,0,0,0,0,0,0,0,0,0,0,0,0,0,0,0,0,0,0,0,0,0,0,0,0,0,0,0,0,0,~
0,0,0,0,0,0,0,0,H10,0)';$S;
    'VSS1604':'(0,0,0,0,0,0,0,0,0,0,0,0,0,0,0,0,0,0,0,0,0,0,0,0,0,0,0,0,0,0,0,0,~
0,0,0,0,0,0,0,0,G90,0)';$S;
    'VSS1603':'(0,0,0,0,0,0,0,0,0,0,0,0,0,0,0,0,0,0,0,0,0,0,0,0,0,0,0,0,0,0,0,0,~
0,0,0,0,0,0,0,0,K49,0)';$S;
    'VSS1602':'(0,0,0,0,0,0,0,0,0,0,0,0,0,0,0,0,0,0,0,0,0,0,0,0,0,0,0,0,0,0,0,0,~
0,0,0,0,0,0,0,0,K42,0)';$S;
    'VSS1601':'(0,0,0,0,0,0,0,0,0,0,0,0,0,0,0,0,0,0,0,0,0,0,0,0,0,0,0,0,0,0,0,0,~
0,0,0,0,0,0,0,0,G88,0)';$S;
    'VSS1600':'(0,0,0,0,0,0,0,0,0,0,0,0,0,0,0,0,0,0,0,0,0,0,0,0,0,0,0,0,0,0,0,0,~
0,0,0,0,0,0,0,0,G84,0)';$S;
    'VSS1599':'(0,0,0,0,0,0,0,0,0,0,0,0,0,0,0,0,0,0,0,0,0,0,0,0,0,0,0,0,0,0,0,0,~
0,0,0,0,0,0,0,0,K2,0)';$S;
    'VSS1598':'(0,0,0,0,0,0,0,0,0,0,0,0,0,0,0,0,0,0,0,0,0,0,0,0,0,0,0,0,0,0,0,0,~
0,0,0,0,0,0,0,0,K14,0)';$S;
    'VSS1597':'(0,0,0,0,0,0,0,0,0,0,0,0,0,0,0,0,0,0,0,0,0,0,0,0,0,0,0,0,0,0,0,0,~
0,0,0,0,0,0,0,0,K12,0)';$S;
    'VSS1596':'(0,0,0,0,0,0,0,0,0,0,0,0,0,0,0,0,0,0,0,0,0,0,0,0,0,0,0,0,0,0,0,0,~
0,0,0,0,0,0,0,0,J9,0)';$S;
    'VSS1595':'(0,0,0,0,0,0,0,0,0,0,0,0,0,0,0,0,0,0,0,0,0,0,0,0,0,0,0,0,0,0,0,0,~
0,0,0,0,0,0,0,0,J88,0)';$S;
    'VSS1594':'(0,0,0,0,0,0,0,0,0,0,0,0,0,0,0,0,0,0,0,0,0,0,0,0,0,0,0,0,0,0,0,0,~
0,0,0,0,0,0,0,0,G72,0)';$S;
    'VSS1593':'(0,0,0,0,0,0,0,0,0,0,0,0,0,0,0,0,0,0,0,0,0,0,0,0,0,0,0,0,0,0,0,0,~
0,0,0,0,0,0,0,0,G62,0)';$S;
    'VSS1592':'(0,0,0,0,0,0,0,0,0,0,0,0,0,0,0,0,0,0,0,0,0,0,0,0,0,0,0,0,0,0,0,0,~
0,0,0,0,0,0,0,0,G56,0)';$S;
    'VSS1591':'(0,0,0,0,0,0,0,0,0,0,0,0,0,0,0,0,0,0,0,0,0,0,0,0,0,0,0,0,0,0,0,0,~
0,0,0,0,0,0,0,0,G54,0)';$S;
    'VSS1590':'(0,0,0,0,0,0,0,0,0,0,0,0,0,0,0,0,0,0,0,0,0,0,0,0,0,0,0,0,0,0,0,0,~
0,0,0,0,0,0,0,0,G50,0)';$S;
    'VSS1589':'(0,0,0,0,0,0,0,0,0,0,0,0,0,0,0,0,0,0,0,0,0,0,0,0,0,0,0,0,0,0,0,0,~
0,0,0,0,0,0,0,0,J70,0)';$S;
    'VSS1588':'(0,0,0,0,0,0,0,0,0,0,0,0,0,0,0,0,0,0,0,0,0,0,0,0,0,0,0,0,0,0,0,0,~
0,0,0,0,0,0,0,0,G43,0)';$S;
    'VSS1587':'(0,0,0,0,0,0,0,0,0,0,0,0,0,0,0,0,0,0,0,0,0,0,0,0,0,0,0,0,0,0,0,0,~
0,0,0,0,0,0,0,0,J64,0)';$S;
    'VSS1586':'(0,0,0,0,0,0,0,0,0,0,0,0,0,0,0,0,0,0,0,0,0,0,0,0,0,0,0,0,0,0,0,0,~
0,0,0,0,0,0,0,0,G41,0)';$S;
    'VSS1585':'(0,0,0,0,0,0,0,0,0,0,0,0,0,0,0,0,0,0,0,0,0,0,0,0,0,0,0,0,0,0,0,0,~
0,0,0,0,0,0,0,0,G37,0)';$S;
    'VSS1584':'(0,0,0,0,0,0,0,0,0,0,0,0,0,0,0,0,0,0,0,0,0,0,0,0,0,0,0,0,0,0,0,0,~
0,0,0,0,0,0,0,0,G31,0)';$S;
    'VSS1583':'(0,0,0,0,0,0,0,0,0,0,0,0,0,0,0,0,0,0,0,0,0,0,0,0,0,0,0,0,0,0,0,0,~
0,0,0,0,0,0,0,0,G29,0)';$S;
    'VSS1582':'(0,0,0,0,0,0,0,0,0,0,0,0,0,0,0,0,0,0,0,0,0,0,0,0,0,0,0,0,0,0,0,0,~
0,0,0,0,0,0,0,0,J5,0)';$S;
    'VSS1581':'(0,0,0,0,0,0,0,0,0,0,0,0,0,0,0,0,0,0,0,0,0,0,0,0,0,0,0,0,0,0,0,0,~
0,0,0,0,0,0,0,0,G23,0)';$S;
    'VSS1580':'(0,0,0,0,0,0,0,0,0,0,0,0,0,0,0,0,0,0,0,0,0,0,0,0,0,0,0,0,0,0,0,0,~
0,0,0,0,0,0,0,0,J39,0)';$S;
    'VSS1579':'(0,0,0,0,0,0,0,0,0,0,0,0,0,0,0,0,0,0,0,0,0,0,0,0,0,0,0,0,0,0,0,0,~
0,0,0,0,0,0,0,0,G19,0)';$S;
    'VSS1578':'(0,0,0,0,0,0,0,0,0,0,0,0,0,0,0,0,0,0,0,0,0,0,0,0,0,0,0,0,0,0,0,0,~
0,0,0,0,0,0,0,0,G13,0)';$S;
    'VSS1577':'(0,0,0,0,0,0,0,0,0,0,0,0,0,0,0,0,0,0,0,0,0,0,0,0,0,0,0,0,0,0,0,0,~
0,0,0,0,0,0,0,0,F89,0)';$S;
    'VSS1576':'(0,0,0,0,0,0,0,0,0,0,0,0,0,0,0,0,0,0,0,0,0,0,0,0,0,0,0,0,0,0,0,0,~
0,0,0,0,0,0,0,0,F83,0)';$S;
    'VSS1575':'(0,0,0,0,0,0,0,0,0,0,0,0,0,0,0,0,0,0,0,0,0,0,0,0,0,0,0,0,0,0,0,0,~
0,0,0,0,0,0,0,0,J21,0)';$S;
    'VSS1574':'(0,0,0,0,0,0,0,0,0,0,0,0,0,0,0,0,0,0,0,0,0,0,0,0,0,0,0,0,0,0,0,0,~
0,0,0,0,0,0,0,0,F49,0)';$S;
    'VSS1573':'(0,0,0,0,0,0,0,0,0,0,0,0,0,0,0,0,0,0,0,0,0,0,0,0,0,0,0,0,0,0,0,0,~
0,0,0,0,0,0,0,0,F4,0)';$S;
    'VSS1572':'(0,0,0,0,0,0,0,0,0,0,0,0,0,0,0,0,0,0,0,0,0,0,0,0,0,0,0,0,0,0,0,0,~
0,0,0,0,0,0,0,0,F36,0)';$S;
    'VSS1571':'(0,0,0,0,0,0,0,0,0,0,0,0,0,0,0,0,0,0,0,0,0,0,0,0,0,0,0,0,0,0,0,0,~
0,0,0,0,0,0,0,0,F30,0)';$S;
    'VSS1570':'(0,0,0,0,0,0,0,0,0,0,0,0,0,0,0,0,0,0,0,0,0,0,0,0,0,0,0,0,0,0,0,0,~
0,0,0,0,0,0,0,0,F24,0)';$S;
    'VSS1567':'(0,0,0,0,0,0,0,0,0,0,0,0,0,0,0,0,0,0,0,0,0,0,0,0,0,0,0,0,0,0,0,0,~
0,0,0,0,0,0,0,0,H75,0)';$S;
    'VSS1564':'(0,0,0,0,0,0,0,0,0,0,0,0,0,0,0,0,0,0,0,0,0,0,0,0,0,0,0,0,0,0,0,0,~
0,0,0,0,0,0,0,0,H65,0)';$S;
    'VSS1560':'(0,0,0,0,0,0,0,0,0,0,0,0,0,0,0,0,0,0,0,0,0,0,0,0,0,0,0,0,0,0,0,0,~
0,0,0,0,0,0,0,0,H57,0)';$S;
    'VSS1558':'(0,0,0,0,0,0,0,0,0,0,0,0,0,0,0,0,0,0,0,0,0,0,0,0,0,0,0,0,0,0,0,0,~
0,0,0,0,0,0,0,0,H51,0)';$S;
    'VSS1546':'(0,0,0,0,0,0,0,0,0,0,0,0,0,0,0,0,0,0,0,0,0,0,0,0,0,0,0,0,0,0,0,0,~
0,0,0,0,0,0,0,0,H2,0)';$S;
    'VSS1544':'(0,0,0,0,0,0,0,0,0,0,0,0,0,0,0,0,0,0,0,0,0,0,0,0,0,0,0,0,0,0,0,0,~
0,0,0,0,0,0,0,0,H14,0)';$S;
    'VSS1538':'(0,0,0,0,0,0,0,0,0,0,0,0,0,0,0,0,0,0,0,0,0,0,0,0,0,0,0,0,0,0,0,0,~
0,0,0,0,0,0,0,0,G74,0)';$S;
    'VSS1536':'(0,0,0,0,0,0,0,0,0,0,0,0,0,0,0,0,0,0,0,0,0,0,0,0,0,0,0,0,0,0,0,0,~
0,0,0,0,0,0,0,0,G7,0)';$S;
    'VSS1535':'(0,0,0,0,0,0,0,0,0,0,0,0,0,0,0,0,0,0,0,0,0,0,0,0,0,0,0,0,0,0,0,0,~
0,0,0,0,0,0,0,0,G68,0)';$S;
    'VSS1534':'(0,0,0,0,0,0,0,0,0,0,0,0,0,0,0,0,0,0,0,0,0,0,0,0,0,0,0,0,0,0,0,0,~
0,0,0,0,0,0,0,0,G66,0)';$S;
    'VSS1532':'(0,0,0,0,0,0,0,0,0,0,0,0,0,0,0,0,0,0,0,0,0,0,0,0,0,0,0,0,0,0,0,0,~
0,0,0,0,0,0,0,0,G60,0)';$S;
    'VSS1527':'(0,0,0,0,0,0,0,0,0,0,0,0,0,0,0,0,0,0,0,0,0,0,0,0,0,0,0,0,0,0,0,0,~
0,0,0,0,0,0,0,0,G48,0)';$S;
    'VSS1523':'(0,0,0,0,0,0,0,0,0,0,0,0,0,0,0,0,0,0,0,0,0,0,0,0,0,0,0,0,0,0,0,0,~
0,0,0,0,0,0,0,0,G35,0)';$S;
    'VSS1521':'(0,0,0,0,0,0,0,0,0,0,0,0,0,0,0,0,0,0,0,0,0,0,0,0,0,0,0,0,0,0,0,0,~
0,0,0,0,0,0,0,0,G3,0)';$S;
    'VSS1519':'(0,0,0,0,0,0,0,0,0,0,0,0,0,0,0,0,0,0,0,0,0,0,0,0,0,0,0,0,0,0,0,0,~
0,0,0,0,0,0,0,0,G25,0)';$S;
    'VSS1516':'(0,0,0,0,0,0,0,0,0,0,0,0,0,0,0,0,0,0,0,0,0,0,0,0,0,0,0,0,0,0,0,0,~
0,0,0,0,0,0,0,0,G17,0)';$S;
    'VSS1514':'(0,0,0,0,0,0,0,0,0,0,0,0,0,0,0,0,0,0,0,0,0,0,0,0,0,0,0,0,0,0,0,0,~
0,0,0,0,0,0,0,0,G11,0)';$S;
    'VSS1511':'(0,0,0,0,0,0,0,0,0,0,0,0,0,0,0,0,0,0,0,0,0,0,0,0,0,0,0,0,0,0,0,0,~
0,0,0,0,0,0,0,0,F79,0)';$S;
    'VSS1510':'(0,0,0,0,0,0,0,0,0,0,0,0,0,0,0,0,0,0,0,0,0,0,0,0,0,0,0,0,0,0,0,0,~
0,0,0,0,0,0,0,0,F73,0)';$S;
    'VSS1509':'(0,0,0,0,0,0,0,0,0,0,0,0,0,0,0,0,0,0,0,0,0,0,0,0,0,0,0,0,0,0,0,0,~
0,0,0,0,0,0,0,0,F67,0)';$S;
    'VSS1508':'(0,0,0,0,0,0,0,0,0,0,0,0,0,0,0,0,0,0,0,0,0,0,0,0,0,0,0,0,0,0,0,0,~
0,0,0,0,0,0,0,0,F61,0)';$S;
    'VSS1507':'(0,0,0,0,0,0,0,0,0,0,0,0,0,0,0,0,0,0,0,0,0,0,0,0,0,0,0,0,0,0,0,0,~
0,0,0,0,0,0,0,0,F6,0)';$S;
    'VSS1504':'(0,0,0,0,0,0,0,0,0,0,0,0,0,0,0,0,0,0,0,0,0,0,0,0,0,0,0,0,0,0,0,0,~
0,0,0,0,0,0,0,0,F55,0)';$S;
    'VSS1502':'(0,0,0,0,0,0,0,0,0,0,0,0,0,0,0,0,0,0,0,0,0,0,0,0,0,0,0,0,0,0,0,0,~
0,0,0,0,0,0,0,0,F42,0)';$S;
    'VSS1495':'(0,0,0,0,0,0,0,0,0,0,0,0,0,0,0,0,0,0,0,0,0,0,0,0,0,0,0,0,0,0,0,0,~
0,0,0,0,0,0,0,0,F18,0)';$S;
    'VSS1494':'(0,0,0,0,0,0,0,0,0,0,0,0,0,0,0,0,0,0,0,0,0,0,0,0,0,0,0,0,0,0,0,0,~
0,0,0,0,0,0,0,0,F12,0)';$S;
    'VSS1273':'(0,0,0,0,0,0,0,0,0,0,0,0,0,0,0,0,0,0,0,0,0,0,0,0,0,0,0,0,0,0,0,0,~
0,0,0,0,0,0,0,0,E86,0)';$S;
    'VSS1272':'(0,0,0,0,0,0,0,0,0,0,0,0,0,0,0,0,0,0,0,0,0,0,0,0,0,0,0,0,0,0,0,0,~
0,0,0,0,0,0,0,0,E76,0)';$S;
    'VSS1131':'(0,0,0,0,0,0,0,0,0,0,0,0,0,0,0,0,0,0,0,0,0,0,0,0,0,0,0,0,0,0,0,0,~
0,0,0,0,0,0,0,0,E78,0)';$S;
    'VSS1129':'(0,0,0,0,0,0,0,0,0,0,0,0,0,0,0,0,0,0,0,0,0,0,0,0,0,0,0,0,0,0,0,0,~
0,0,0,0,0,0,0,0,E74,0)';$S;
    'VSS1126':'(0,0,0,0,0,0,0,0,0,0,0,0,0,0,0,0,0,0,0,0,0,0,0,0,0,0,0,0,0,0,0,0,~
0,0,0,0,0,0,0,0,E52,0)';$S;
    'VSS1271':'(0,0,0,0,0,0,0,0,0,0,0,0,0,0,0,0,0,0,0,0,0,0,0,0,0,0,0,0,0,0,0,0,~
0,0,0,0,0,0,0,0,0,E39)';$S;
    'VSS1125':'(0,0,0,0,0,0,0,0,0,0,0,0,0,0,0,0,0,0,0,0,0,0,0,0,0,0,0,0,0,0,0,0,~
0,0,0,0,0,0,0,0,0,E5)';$S;
    'VSS907':'(0,0,0,0,0,0,0,0,0,0,0,0,0,0,0,0,0,0,0,0,0,0,0,0,0,0,0,0,0,0,0,0,0~
,0,0,0,0,0,0,0,0,D83)';$S;
    'VSS906':'(0,0,0,0,0,0,0,0,0,0,0,0,0,0,0,0,0,0,0,0,0,0,0,0,0,0,0,0,0,0,0,0,0~
,0,0,0,0,0,0,0,0,D81)';$S;
    'VSS902':'(0,0,0,0,0,0,0,0,0,0,0,0,0,0,0,0,0,0,0,0,0,0,0,0,0,0,0,0,0,0,0,0,0~
,0,0,0,0,0,0,0,0,D71)';$S;
    'VSS901':'(0,0,0,0,0,0,0,0,0,0,0,0,0,0,0,0,0,0,0,0,0,0,0,0,0,0,0,0,0,0,0,0,0~
,0,0,0,0,0,0,0,0,D69)';$S;
    'VSS900':'(0,0,0,0,0,0,0,0,0,0,0,0,0,0,0,0,0,0,0,0,0,0,0,0,0,0,0,0,0,0,0,0,0~
,0,0,0,0,0,0,0,0,D61)';$S;
    'VSS899':'(0,0,0,0,0,0,0,0,0,0,0,0,0,0,0,0,0,0,0,0,0,0,0,0,0,0,0,0,0,0,0,0,0~
,0,0,0,0,0,0,0,0,D6)';$S;
    'VSS898':'(0,0,0,0,0,0,0,0,0,0,0,0,0,0,0,0,0,0,0,0,0,0,0,0,0,0,0,0,0,0,0,0,0~
,0,0,0,0,0,0,0,0,D59)';$S;
    'VSS897':'(0,0,0,0,0,0,0,0,0,0,0,0,0,0,0,0,0,0,0,0,0,0,0,0,0,0,0,0,0,0,0,0,0~
,0,0,0,0,0,0,0,0,D57)';$S;
    'VSS896':'(0,0,0,0,0,0,0,0,0,0,0,0,0,0,0,0,0,0,0,0,0,0,0,0,0,0,0,0,0,0,0,0,0~
,0,0,0,0,0,0,0,0,D55)';$S;
    'VSS895':'(0,0,0,0,0,0,0,0,0,0,0,0,0,0,0,0,0,0,0,0,0,0,0,0,0,0,0,0,0,0,0,0,0~
,0,0,0,0,0,0,0,0,D53)';$S;
    'VSS892':'(0,0,0,0,0,0,0,0,0,0,0,0,0,0,0,0,0,0,0,0,0,0,0,0,0,0,0,0,0,0,0,0,0~
,0,0,0,0,0,0,0,0,D51)';$S;
    'VSS891':'(0,0,0,0,0,0,0,0,0,0,0,0,0,0,0,0,0,0,0,0,0,0,0,0,0,0,0,0,0,0,0,0,0~
,0,0,0,0,0,0,0,0,D49)';$S;
    'VSS889':'(0,0,0,0,0,0,0,0,0,0,0,0,0,0,0,0,0,0,0,0,0,0,0,0,0,0,0,0,0,0,0,0,0~
,0,0,0,0,0,0,0,0,D47)';$S;
    'VSS888':'(0,0,0,0,0,0,0,0,0,0,0,0,0,0,0,0,0,0,0,0,0,0,0,0,0,0,0,0,0,0,0,0,0~
,0,0,0,0,0,0,0,0,D44)';$S;
    'VSS886':'(0,0,0,0,0,0,0,0,0,0,0,0,0,0,0,0,0,0,0,0,0,0,0,0,0,0,0,0,0,0,0,0,0~
,0,0,0,0,0,0,0,0,D42)';$S;
    'VSS885':'(0,0,0,0,0,0,0,0,0,0,0,0,0,0,0,0,0,0,0,0,0,0,0,0,0,0,0,0,0,0,0,0,0~
,0,0,0,0,0,0,0,0,D40)';$S;
    'VSS884':'(0,0,0,0,0,0,0,0,0,0,0,0,0,0,0,0,0,0,0,0,0,0,0,0,0,0,0,0,0,0,0,0,0~
,0,0,0,0,0,0,0,0,D38)';$S;
    'VSS881':'(0,0,0,0,0,0,0,0,0,0,0,0,0,0,0,0,0,0,0,0,0,0,0,0,0,0,0,0,0,0,0,0,0~
,0,0,0,0,0,0,0,0,D36)';$S;
    'VSS879':'(0,0,0,0,0,0,0,0,0,0,0,0,0,0,0,0,0,0,0,0,0,0,0,0,0,0,0,0,0,0,0,0,0~
,0,0,0,0,0,0,0,0,D34)';$S;
    'VSS878':'(0,0,0,0,0,0,0,0,0,0,0,0,0,0,0,0,0,0,0,0,0,0,0,0,0,0,0,0,0,0,0,0,0~
,0,0,0,0,0,0,0,0,D32)';$S;
    'VSS877':'(0,0,0,0,0,0,0,0,0,0,0,0,0,0,0,0,0,0,0,0,0,0,0,0,0,0,0,0,0,0,0,0,0~
,0,0,0,0,0,0,0,0,D30)';$S;
    'VSS876':'(0,0,0,0,0,0,0,0,0,0,0,0,0,0,0,0,0,0,0,0,0,0,0,0,0,0,0,0,0,0,0,0,0~
,0,0,0,0,0,0,0,0,D28)';$S;
    'VSS875':'(0,0,0,0,0,0,0,0,0,0,0,0,0,0,0,0,0,0,0,0,0,0,0,0,0,0,0,0,0,0,0,0,0~
,0,0,0,0,0,0,0,0,D26)';$S;
    'VSS874':'(0,0,0,0,0,0,0,0,0,0,0,0,0,0,0,0,0,0,0,0,0,0,0,0,0,0,0,0,0,0,0,0,0~
,0,0,0,0,0,0,0,0,D24)';$S;
    'VSS873':'(0,0,0,0,0,0,0,0,0,0,0,0,0,0,0,0,0,0,0,0,0,0,0,0,0,0,0,0,0,0,0,0,0~
,0,0,0,0,0,0,0,0,D22)';$S;
    'VSS871':'(0,0,0,0,0,0,0,0,0,0,0,0,0,0,0,0,0,0,0,0,0,0,0,0,0,0,0,0,0,0,0,0,0~
,0,0,0,0,0,0,0,0,D20)';$S;
    'VSS869':'(0,0,0,0,0,0,0,0,0,0,0,0,0,0,0,0,0,0,0,0,0,0,0,0,0,0,0,0,0,0,0,0,0~
,0,0,0,0,0,0,0,0,D18)';$S;
    'VSS868':'(0,0,0,0,0,0,0,0,0,0,0,0,0,0,0,0,0,0,0,0,0,0,0,0,0,0,0,0,0,0,0,0,0~
,0,0,0,0,0,0,0,0,D16)';$S;
    'VSS866':'(0,0,0,0,0,0,0,0,0,0,0,0,0,0,0,0,0,0,0,0,0,0,0,0,0,0,0,0,0,0,0,0,0~
,0,0,0,0,0,0,0,0,D14)';$S;
    'VSS865':'(0,0,0,0,0,0,0,0,0,0,0,0,0,0,0,0,0,0,0,0,0,0,0,0,0,0,0,0,0,0,0,0,0~
,0,0,0,0,0,0,0,0,D12)';$S;
    'VSS864':'(0,0,0,0,0,0,0,0,0,0,0,0,0,0,0,0,0,0,0,0,0,0,0,0,0,0,0,0,0,0,0,0,0~
,0,0,0,0,0,0,0,0,D10)';$S;
    'VSS663':'(0,0,0,0,0,0,0,0,0,0,0,0,0,0,0,0,0,0,0,0,0,0,0,0,0,0,0,0,0,0,0,0,0~
,0,0,0,0,0,0,0,0,D8)';$S;
    'VSS662':'(0,0,0,0,0,0,0,0,0,0,0,0,0,0,0,0,0,0,0,0,0,0,0,0,0,0,0,0,0,0,0,0,0~
,0,0,0,0,0,0,0,0,D79)';$S;
    'VSS659':'(0,0,0,0,0,0,0,0,0,0,0,0,0,0,0,0,0,0,0,0,0,0,0,0,0,0,0,0,0,0,0,0,0~
,0,0,0,0,0,0,0,0,D67)';$S;
    'VSS658':'(0,0,0,0,0,0,0,0,0,0,0,0,0,0,0,0,0,0,0,0,0,0,0,0,0,0,0,0,0,0,0,0,0~
,0,0,0,0,0,0,0,0,D65)';$S;
    'VSS657':'(0,0,0,0,0,0,0,0,0,0,0,0,0,0,0,0,0,0,0,0,0,0,0,0,0,0,0,0,0,0,0,0,0~
,0,0,0,0,0,0,0,0,D63)';$S;
    'VSS619':'(0,0,0,0,0,0,0,0,0,0,0,0,0,0,0,0,0,0,0,0,0,0,0,0,0,0,0,0,0,0,0,0,0~
,0,0,0,0,0,0,0,0,C86)';$S;
    'VSS618':'(0,0,0,0,0,0,0,0,0,0,0,0,0,0,0,0,0,0,0,0,0,0,0,0,0,0,0,0,0,0,0,0,0~
,0,0,0,0,0,0,0,0,C82)';$S;
    'VSS617':'(0,0,0,0,0,0,0,0,0,0,0,0,0,0,0,0,0,0,0,0,0,0,0,0,0,0,0,0,0,0,0,0,0~
,0,0,0,0,0,0,0,0,C80)';$S;
    'VSS616':'(0,0,0,0,0,0,0,0,0,0,0,0,0,0,0,0,0,0,0,0,0,0,0,0,0,0,0,0,0,0,0,0,0~
,0,0,0,0,0,0,0,0,C78)';$S;
    'VSS615':'(0,0,0,0,0,0,0,0,0,0,0,0,0,0,0,0,0,0,0,0,0,0,0,0,0,0,0,0,0,0,0,0,0~
,0,0,0,0,0,0,0,0,C74)';$S;
    'VSS614':'(0,0,0,0,0,0,0,0,0,0,0,0,0,0,0,0,0,0,0,0,0,0,0,0,0,0,0,0,0,0,0,0,0~
,0,0,0,0,0,0,0,0,C72)';$S;
    'VSS613':'(0,0,0,0,0,0,0,0,0,0,0,0,0,0,0,0,0,0,0,0,0,0,0,0,0,0,0,0,0,0,0,0,0~
,0,0,0,0,0,0,0,0,C52)';$S;
    'VSS612':'(0,0,0,0,0,0,0,0,0,0,0,0,0,0,0,0,0,0,0,0,0,0,0,0,0,0,0,0,0,0,0,0,0~
,0,0,0,0,0,0,0,0,C5)';$S;
    'VSS610':'(0,0,0,0,0,0,0,0,0,0,0,0,0,0,0,0,0,0,0,0,0,0,0,0,0,0,0,0,0,0,0,0,0~
,0,0,0,0,0,0,0,0,C45)';$S;
    'VSS609':'(0,0,0,0,0,0,0,0,0,0,0,0,0,0,0,0,0,0,0,0,0,0,0,0,0,0,0,0,0,0,0,0,0~
,0,0,0,0,0,0,0,0,C39)';$S;
    'VSS392':'(0,0,0,0,0,0,0,0,0,0,0,0,0,0,0,0,0,0,0,0,0,0,0,0,0,0,0,0,0,0,0,0,0~
,0,0,0,0,0,0,0,0,B87)';$S;
    'VSS391':'(0,0,0,0,0,0,0,0,0,0,0,0,0,0,0,0,0,0,0,0,0,0,0,0,0,0,0,0,0,0,0,0,0~
,0,0,0,0,0,0,0,0,B83)';$S;
    'VSS390':'(0,0,0,0,0,0,0,0,0,0,0,0,0,0,0,0,0,0,0,0,0,0,0,0,0,0,0,0,0,0,0,0,0~
,0,0,0,0,0,0,0,0,B75)';$S;
    'VSS389':'(0,0,0,0,0,0,0,0,0,0,0,0,0,0,0,0,0,0,0,0,0,0,0,0,0,0,0,0,0,0,0,0,0~
,0,0,0,0,0,0,0,0,B67)';$S;
    'VSS388':'(0,0,0,0,0,0,0,0,0,0,0,0,0,0,0,0,0,0,0,0,0,0,0,0,0,0,0,0,0,0,0,0,0~
,0,0,0,0,0,0,0,0,B61)';$S;
    'VSS387':'(0,0,0,0,0,0,0,0,0,0,0,0,0,0,0,0,0,0,0,0,0,0,0,0,0,0,0,0,0,0,0,0,0~
,0,0,0,0,0,0,0,0,B6)';$S;
    'VSS386':'(0,0,0,0,0,0,0,0,0,0,0,0,0,0,0,0,0,0,0,0,0,0,0,0,0,0,0,0,0,0,0,0,0~
,0,0,0,0,0,0,0,0,B55)';$S;
    'VSS385':'(0,0,0,0,0,0,0,0,0,0,0,0,0,0,0,0,0,0,0,0,0,0,0,0,0,0,0,0,0,0,0,0,0~
,0,0,0,0,0,0,0,0,B49)';$S;
    'VSS384':'(0,0,0,0,0,0,0,0,0,0,0,0,0,0,0,0,0,0,0,0,0,0,0,0,0,0,0,0,0,0,0,0,0~
,0,0,0,0,0,0,0,0,B42)';$S;
    'VSS382':'(0,0,0,0,0,0,0,0,0,0,0,0,0,0,0,0,0,0,0,0,0,0,0,0,0,0,0,0,0,0,0,0,0~
,0,0,0,0,0,0,0,0,B36)';$S;
    'VSS381':'(0,0,0,0,0,0,0,0,0,0,0,0,0,0,0,0,0,0,0,0,0,0,0,0,0,0,0,0,0,0,0,0,0~
,0,0,0,0,0,0,0,0,B30)';$S;
    'VSS380':'(0,0,0,0,0,0,0,0,0,0,0,0,0,0,0,0,0,0,0,0,0,0,0,0,0,0,0,0,0,0,0,0,0~
,0,0,0,0,0,0,0,0,B24)';$S;
    'VSS379':'(0,0,0,0,0,0,0,0,0,0,0,0,0,0,0,0,0,0,0,0,0,0,0,0,0,0,0,0,0,0,0,0,0~
,0,0,0,0,0,0,0,0,B18)';$S;
    'VSS378':'(0,0,0,0,0,0,0,0,0,0,0,0,0,0,0,0,0,0,0,0,0,0,0,0,0,0,0,0,0,0,0,0,0~
,0,0,0,0,0,0,0,0,B12)';$S;
    'VSS16':'(0,0,0,0,0,0,0,0,0,0,0,0,0,0,0,0,0,0,0,0,0,0,0,0,0,0,0,0,0,0,0,0,0,~
0,0,0,0,0,0,0,0,A62)';$S;
    'VSS15':'(0,0,0,0,0,0,0,0,0,0,0,0,0,0,0,0,0,0,0,0,0,0,0,0,0,0,0,0,0,0,0,0,0,~
0,0,0,0,0,0,0,0,A60)';$S;
    'VSS14':'(0,0,0,0,0,0,0,0,0,0,0,0,0,0,0,0,0,0,0,0,0,0,0,0,0,0,0,0,0,0,0,0,0,~
0,0,0,0,0,0,0,0,A56)';$S;
    'VSS13':'(0,0,0,0,0,0,0,0,0,0,0,0,0,0,0,0,0,0,0,0,0,0,0,0,0,0,0,0,0,0,0,0,0,~
0,0,0,0,0,0,0,0,A54)';$S;
    'VSS12':'(0,0,0,0,0,0,0,0,0,0,0,0,0,0,0,0,0,0,0,0,0,0,0,0,0,0,0,0,0,0,0,0,0,~
0,0,0,0,0,0,0,0,A50)';$S;
    'VSS11':'(0,0,0,0,0,0,0,0,0,0,0,0,0,0,0,0,0,0,0,0,0,0,0,0,0,0,0,0,0,0,0,0,0,~
0,0,0,0,0,0,0,0,A41)';$S;
    'VSS10':'(0,0,0,0,0,0,0,0,0,0,0,0,0,0,0,0,0,0,0,0,0,0,0,0,0,0,0,0,0,0,0,0,0,~
0,0,0,0,0,0,0,0,A37)';$S;
    'VSS9':'(0,0,0,0,0,0,0,0,0,0,0,0,0,0,0,0,0,0,0,0,0,0,0,0,0,0,0,0,0,0,0,0,0,0~
,0,0,0,0,0,0,0,A35)';$S;
    'VSS8':'(0,0,0,0,0,0,0,0,0,0,0,0,0,0,0,0,0,0,0,0,0,0,0,0,0,0,0,0,0,0,0,0,0,0~
,0,0,0,0,0,0,0,A31)';$S;
    'VSS7':'(0,0,0,0,0,0,0,0,0,0,0,0,0,0,0,0,0,0,0,0,0,0,0,0,0,0,0,0,0,0,0,0,0,0~
,0,0,0,0,0,0,0,A29)';$S;
    'VSS6':'(0,0,0,0,0,0,0,0,0,0,0,0,0,0,0,0,0,0,0,0,0,0,0,0,0,0,0,0,0,0,0,0,0,0~
,0,0,0,0,0,0,0,A25)';$S;
    'VSS5':'(0,0,0,0,0,0,0,0,0,0,0,0,0,0,0,0,0,0,0,0,0,0,0,0,0,0,0,0,0,0,0,0,0,0~
,0,0,0,0,0,0,0,A23)';$S;
    'VSS4':'(0,0,0,0,0,0,0,0,0,0,0,0,0,0,0,0,0,0,0,0,0,0,0,0,0,0,0,0,0,0,0,0,0,0~
,0,0,0,0,0,0,0,A19)';$S;
    'VSS3':'(0,0,0,0,0,0,0,0,0,0,0,0,0,0,0,0,0,0,0,0,0,0,0,0,0,0,0,0,0,0,0,0,0,0~
,0,0,0,0,0,0,0,A17)';$S;
    'VSS2':'(0,0,0,0,0,0,0,0,0,0,0,0,0,0,0,0,0,0,0,0,0,0,0,0,0,0,0,0,0,0,0,0,0,0~
,0,0,0,0,0,0,0,A13)';$S;
    'VSS1':'(0,0,0,0,0,0,0,0,0,0,0,0,0,0,0,0,0,0,0,0,0,0,0,0,0,0,0,0,0,0,0,0,0,0~
,0,0,0,0,0,0,0,A11)';$S;
end_primitive;
primitive 'SS15P3SM386A-SS15P3S-M3/86A,SMA';body 'SS15P3SM386A';
    'ANODE_1':'(1)';IN;
    'CATHODE':'(K)';OUT;
    'ANODE_2':'(2)';IN;
end_primitive;
primitive 'SW_PUSHBUTTON4P_24-SW4S_DTSM-6A';body 'SW_PUSHBUTTON4P_24';
    '1':'(1)';BIDI;
    '2':'(2)';BIDI;
    '3':'(3)';BIDI;
    '4':'(4)';BIDI;
end_primitive;
primitive 'TCA9548APWR-TCA9548APWR,SMLF,IA';body 'TCA9548APWR';
    'A0':'(1)';IN;
    'A1':'(2)';IN;
    'RESET#':'(3)';IN;
    'SD0':'(4)';BIDI;
    'SC0':'(5)';BIDI;
    'SD1':'(6)';BIDI;
    'SC1':'(7)';BIDI;
    'SD2':'(8)';BIDI;
    'SC2':'(9)';BIDI;
    'SD3':'(10)';BIDI;
    'SC3':'(11)';BIDI;
    'GND':'(12)';
    'VCC':'(24)';
    'SDA':'(23)';BIDI;
    'SCL':'(22)';BIDI;
    'A2':'(21)';IN;
    'SC7':'(20)';BIDI;
    'SD7':'(19)';BIDI;
    'SC6':'(18)';BIDI;
    'SD6':'(17)';BIDI;
    'SC5':'(16)';BIDI;
    'SD5':'(15)';BIDI;
    'SC4':'(14)';BIDI;
    'SD4':'(13)';BIDI;
end_primitive;
primitive 'TDR_3P_TH2-EMPTY,N_A';body 'TDR_3P';
    'GND':'(1)';
    'IO1':'(2)';
    'IO2':'(3)';
end_primitive;
primitive 'TPS3700DDCR-TPS3700DDCR,SMLF,EA';body 'TPS3700DDCR';
    'VDD':'(5)';
    'INB-':'(4)';IN;
    'GND':'(2)';
    'OUTA':'(1)';OUT;
    'INA+':'(3)';IN;
    'OUTB':'(6)';OUT;
end_primitive;
primitive 'TPS3895ADRYR-TPS3895ADRYR,SMLFA';body 'TPS3895ADRYR';
    'ENABLE':'(1)';IN;
    'GND':'(2)';
    'SENSE':'(3)';BIDI;
    'SENSE_OUT':'(4)';OUT;
    'CT':'(5)';BIDI;
    'VCC':'(6)';
end_primitive;
primitive 'TP_TDR_4P_FTS_TH-TP_TDR_4P_DIPA';body 'TP_TDR_4P_FTS';
    'P1':'(2)';BIDI;
    'P2':'(3)';BIDI;
    'S1':'(1)';BIDI;
    'S2':'(4)';BIDI;
end_primitive;
primitive 'TP_TP_BOM ONLY-NA,TP12_BOM';body 'TP';
    'TP':'(1)';
end_primitive;
primitive 'TUSB211IRWBR-TUSB211IRWBR,SMLFA';body 'TUSB211IRWBR';
    'RSTN':'(5)';IN;
    'D2M':'(8)';BIDI;
    'VREG':'(11)';OUT;
    'TEST':'(3)';IN;
    'VCC':'(12)';
    'ENA_HS':'(9)';OUT;
    'CD':'(4)';OUT;
    'D1M':'(1)';BIDI;
    'D1P':'(2)';BIDI;
    'D2P':'(7)';BIDI;
    'EQ':'(6)';IN;
    'GND':'(10)';
end_primitive;
primitive 'ZENER_AC-5.0SMDJ14A,SMLF,IC,BCA';body 'ZENER_AC';
    'A':'(A)';BIDI;
    'C':'(C)';BIDI;
end_primitive;
END.
